FILE_TYPE = LIBRARY_PARTS;
{ Packager-XL run on 24-Aug-2023 AT 15:36:33 }
primitive '74CBTLV3126PW-74CBTLV3126PW,SMA';
  pin
    '2A':
      PIN_NUMBER='(5)';
      BIDIRECTIONAL='TRUE';
      INPUT_LOAD='(-0.01,0.01)';
      OUTPUT_LOAD='(1.0,-1.0)';
      PINUSE='BI';
    '3B':
      PIN_NUMBER='(8)';
      BIDIRECTIONAL='TRUE';
      INPUT_LOAD='(-0.01,0.01)';
      OUTPUT_LOAD='(1.0,-1.0)';
      PINUSE='BI';
    '1OE':
      PIN_NUMBER='(1)';
      INPUT_LOAD='(-0.01,0.01)';
      PINUSE='IN';
    '2OE':
      PIN_NUMBER='(4)';
      OUTPUT_LOAD='(1.0,-1.0)';
      PINUSE='OUT';
    '1B':
      PIN_NUMBER='(3)';
      BIDIRECTIONAL='TRUE';
      INPUT_LOAD='(-0.01,0.01)';
      OUTPUT_LOAD='(1.0,-1.0)';
      PINUSE='BI';
    '2B':
      PIN_NUMBER='(6)';
      BIDIRECTIONAL='TRUE';
      INPUT_LOAD='(-0.01,0.01)';
      OUTPUT_LOAD='(1.0,-1.0)';
      PINUSE='BI';
    '1A':
      PIN_NUMBER='(2)';
      PINUSE='POWER';
      NO_LOAD_CHECK='Both';
      NO_IO_CHECK='Both';
      NO_ASSERT_CHECK='TRUE';
      NO_DIR_CHECK='TRUE';
      ALLOW_CONNECT='TRUE';
    'GND':
      PIN_NUMBER='(7)';
      PINUSE='POWER';
      NO_LOAD_CHECK='Both';
      NO_IO_CHECK='Both';
      NO_ASSERT_CHECK='TRUE';
      NO_DIR_CHECK='TRUE';
      ALLOW_CONNECT='TRUE';
    '3A':
      PIN_NUMBER='(9)';
      BIDIRECTIONAL='TRUE';
      INPUT_LOAD='(-0.01,0.01)';
      OUTPUT_LOAD='(1.0,-1.0)';
      PINUSE='BI';
    '3OE':
      PIN_NUMBER='(10)';
      BIDIRECTIONAL='TRUE';
      INPUT_LOAD='(-0.01,0.01)';
      OUTPUT_LOAD='(1.0,-1.0)';
      PINUSE='BI';
    '4B':
      PIN_NUMBER='(11)';
      BIDIRECTIONAL='TRUE';
      INPUT_LOAD='(-0.01,0.01)';
      OUTPUT_LOAD='(1.0,-1.0)';
      PINUSE='BI';
    '4A':
      PIN_NUMBER='(12)';
      BIDIRECTIONAL='TRUE';
      INPUT_LOAD='(-0.01,0.01)';
      OUTPUT_LOAD='(1.0,-1.0)';
      PINUSE='BI';
    '4OE':
      PIN_NUMBER='(13)';
      BIDIRECTIONAL='TRUE';
      INPUT_LOAD='(-0.01,0.01)';
      OUTPUT_LOAD='(1.0,-1.0)';
      PINUSE='BI';
    'VCC':
      PIN_NUMBER='(14)';
      BIDIRECTIONAL='TRUE';
      INPUT_LOAD='(-0.01,0.01)';
      OUTPUT_LOAD='(1.0,-1.0)';
      PINUSE='BI';
  end_pin;
  body
      PART_NAME='74CBTLV3126PW';
      BODY_NAME='74CBTLV3126PW';
      JEDEC_TYPE='TSSOP14';
      PHYS_DES_PREFIX='U';
      CLASS='IC';
      STANDARD='';
      LIFECYCLE='';
      DESCRIPTION='IC OTHER(14P) 74CBTLV3126PW(TSSOP)';
      MANUFTR='NXP';
      MANUF_PN='74CBTLV3126PW';
      RD_CMPLS_LVL='EU(V1)';
      CMPLS_LVL='';
      FROM_PJ='S4L-CHARLES';
      DIP_SMD='';
      DATA='NXP_74CBTLV3126.pdf';
      EE_CHECK_LIST='';
      FP_ECN='';
      PSL='';
      CREATOR='';
      STATUS='';
      CREATEDAY='20130102';
      PARENT_PART_TYPE='74CBTLV3126PW';
      PARENT_PPT='74CBTLV3126PW';
      PARENT_PPT_PART='74CBTLV3126PW-74CBTLV3126PW,SMLF,IC,AL003126K08';
  end_body;
end_primitive;
primitive '74LVC1G02GW_SMLF-74LVC1G02GW,IA';
  pin
    'B':
      PIN_NUMBER='(1)';
      INPUT_LOAD='(-0.01,0.01)';
      PINUSE='IN';
    'A':
      PIN_NUMBER='(2)';
      INPUT_LOAD='(-0.01,0.01)';
      PINUSE='IN';
    'Y':
      PIN_NUMBER='(4)';
      OUTPUT_LOAD='(1.0,-1.0)';
      PINUSE='OUT';
    'VCC':
      PIN_NUMBER='(5)';
      PINUSE='POWER';
    'GND':
      PIN_NUMBER='(3)';
      PINUSE='POWER';
  end_pin;
  body
      CLASS='IC';
      PART_NAME='74LVC1G02GW';
      PHYS_DES_PREFIX='U';
      STANDARD='';
      LIFECYCLE='';
      ENVCOMP='YES';
      JEDEC_TYPE='SOT353_Q';
      DESCRIPTION='IC(5P) 74LVC1G02GW(SOT353)';
      HEIGHT='.044IN';
      COMPONENT_TYPE='SMALLSMT';
      LEAD_LENGTH='';
      LPID='';
      DAY='20100711';
      PARENT_PART_TYPE='74LVC1G02GW';
      PARENT_PPT='74LVC1G02GW';
      PARENT_PPT_PART='74LVC1G02GW_SMLF-74LVC1G02GW,IC,ALVC1G02000';
  end_body;
end_primitive;
primitive '74LVC1G07GV-74LVC1G07GV,SMLF,IA';
  pin
    'VCC':
      PIN_NUMBER='(5)';
      PINUSE='POWER';
      NO_LOAD_CHECK='Both';
      NO_IO_CHECK='Both';
      NO_ASSERT_CHECK='TRUE';
      NO_DIR_CHECK='TRUE';
      ALLOW_CONNECT='TRUE';
    'A':
      PIN_NUMBER='(2)';
      INPUT_LOAD='(-0.01,0.01)';
      PINUSE='IN';
    'GND':
      PIN_NUMBER='(3)';
      PINUSE='POWER';
      NO_LOAD_CHECK='Both';
      NO_IO_CHECK='Both';
      NO_ASSERT_CHECK='TRUE';
      NO_DIR_CHECK='TRUE';
      ALLOW_CONNECT='TRUE';
    'Y':
      PIN_NUMBER='(4)';
      OUTPUT_TYPE='(OC,AND)';
      OUTPUT_LOAD='(1.0,*)';
      PINUSE='OCA';
    'NC1':
      PIN_NUMBER='(1)';
      OUTPUT_TYPE='(TS,TS)';
      INPUT_LOAD='(-0.01,0.01)';
      OUTPUT_LOAD='(1.0,-1.0)';
      PINUSE='TRI';
  end_pin;
  body
      PART_NAME='74LVC1G07GV';
      BODY_NAME='74LVC1G07GV';
      PHYS_DES_PREFIX='U';
      CLASS='IC';
      STANDARD='';
      LIFECYCLE='';
      JEDEC_TYPE='SC-74A_2-9X1-5';
      DESCRIPTION='IC OTHER(5P) 74LVC1G07GV(SOT753)';
      MANUFTR='NXP';
      MANUF_PN='74LVC1G07GV';
      RD_CMPLS_LVL='EP(V1)';
      CMPLS_LVL='EP(V1)';
      FROM_PJ='S3D-ALAN';
      DIP_SMD='';
      DATA='NXP_74LVC1G07GV.pdf';
      EE_CHECK_LIST='';
      FP_ECN='74LVC1G07GV.msg';
      PSL='';
      CREATOR='';
      STATUS='';
      MSD='Level-1';
      ESD_CDM='NA';
      ESD_HBM='2000V';
      ESD_MM='200V';
      PIN_LENGTH_SHORT_PIN='0 MILS';
      PIN_LENGTH_LONG_PIN='0 MILS';
      CREATEDAY='20191122';
      PARENT_PART_TYPE='74LVC1G07GV';
      PARENT_PPT='74LVC1G07GV';
      PARENT_PPT_PART='74LVC1G07GV-74LVC1G07GV,SMLF,IC,AL1G0007001';
  end_body;
end_primitive;
primitive '74LVC1G07SE7-74LVC1G07SE-7,SMLA';
  pin
    'VCC':
      PIN_NUMBER='(5)';
      PINUSE='POWER';
      NO_LOAD_CHECK='Both';
      NO_IO_CHECK='Both';
      NO_ASSERT_CHECK='TRUE';
      NO_DIR_CHECK='TRUE';
      ALLOW_CONNECT='TRUE';
    'A':
      PIN_NUMBER='(2)';
      INPUT_LOAD='(-0.01,0.01)';
      PINUSE='IN';
    'GND':
      PIN_NUMBER='(3)';
      PINUSE='POWER';
      NO_LOAD_CHECK='Both';
      NO_IO_CHECK='Both';
      NO_ASSERT_CHECK='TRUE';
      NO_DIR_CHECK='TRUE';
      ALLOW_CONNECT='TRUE';
    'Y':
      PIN_NUMBER='(4)';
      OUTPUT_LOAD='(1.0,-1.0)';
      PINUSE='OUT';
    'NC1':
      PIN_NUMBER='(1)';
      OUTPUT_TYPE='(TS,TS)';
      INPUT_LOAD='(-0.01,0.01)';
      OUTPUT_LOAD='(1.0,-1.0)';
      PINUSE='TRI';
  end_pin;
  body
      PART_NAME='74LVC1G07SE7';
      BODY_NAME='74LVC1G07SE7';
      PHYS_DES_PREFIX='U';
      CLASS='IC';
      STANDARD='';
      LIFECYCLE='';
      JEDEC_TYPE='SOT353_0-65_2X1-25';
      DESCRIPTION='IC OTHER(5P)74LVC1G07SE-7(SOT353)';
      MANUFTR='DDS';
      MANUF_PN='74LVC1G07SE-7';
      RD_CMPLS_LVL='EP(V1)';
      CMPLS_LVL='EP(V1)';
      FROM_PJ='F0C-IVES';
      DIP_SMD='';
      DATA='DDS_74LVC1G07SE-7.pdf';
      EE_CHECK_LIST='';
      FP_ECN='';
      PSL='';
      CREATOR='';
      STATUS='';
      MSD='';
      ESD_CDM='';
      ESD_HBM='';
      ESD_MM='';
      PIN_LENGTH_SHORT_PIN='0 MILS';
      PIN_LENGTH_LONG_PIN='0 MILS';
      CREATEDAY='20210615';
      PARENT_PART_TYPE='74LVC1G07SE7';
      PARENT_PPT='74LVC1G07SE7';
      PARENT_PPT_PART='74LVC1G07SE7-74LVC1G07SE-7,SMLF,IC,AL1G07SE000';
  end_body;
end_primitive;
primitive '74LVC1G08W57-74LVC1G08W5-7,SMLA';
  pin
    'A':
      PIN_NUMBER='(1)';
      INPUT_LOAD='(-0.01,0.01)';
      PINUSE='IN';
    'B':
      PIN_NUMBER='(2)';
      INPUT_LOAD='(-0.01,0.01)';
      PINUSE='IN';
    'GND':
      PIN_NUMBER='(3)';
      PINUSE='POWER';
      NO_LOAD_CHECK='Both';
      NO_IO_CHECK='Both';
      NO_ASSERT_CHECK='TRUE';
      NO_DIR_CHECK='TRUE';
      ALLOW_CONNECT='TRUE';
    'Y':
      PIN_NUMBER='(4)';
      OUTPUT_LOAD='(1.0,-1.0)';
      PINUSE='OUT';
    'VCC':
      PIN_NUMBER='(5)';
      PINUSE='POWER';
      NO_LOAD_CHECK='Both';
      NO_IO_CHECK='Both';
      NO_ASSERT_CHECK='TRUE';
      NO_DIR_CHECK='TRUE';
      ALLOW_CONNECT='TRUE';
  end_pin;
  body
      PART_NAME='74LVC1G08W57';
      BODY_NAME='74LVC1G08W57';
      PHYS_DES_PREFIX='U';
      CLASS='IC';
      STANDARD='';
      LIFECYCLE='';
      JEDEC_TYPE='SOT25-5_0-95_3X1-6';
      DESCRIPTION='IC OTHER(5P) 74LVC1G08W5-7(SOT25)';
      MANUFTR='DDS';
      MANUF_PN='74LVC1G08W5-7';
      RD_CMPLS_LVL='EP(V1)';
      CMPLS_LVL='EP(V1)';
      FROM_PJ='S6S-KYLE';
      DIP_SMD='';
      DATA='DDS_74LVC1G08W5-7.pdf';
      EE_CHECK_LIST='';
      FP_ECN='';
      PSL='';
      CREATOR='';
      STATUS='';
      MSD='';
      ESD_CDM='';
      ESD_HBM='';
      ESD_MM='';
      PIN_LENGTH_SHORT_PIN='0 MILS';
      PIN_LENGTH_LONG_PIN='0 MILS';
      CREATEDAY='20210604';
      PARENT_PART_TYPE='74LVC1G08W57';
      PARENT_PPT='74LVC1G08W57';
      PARENT_PPT_PART='74LVC1G08W57-74LVC1G08W5-7,SMLF,IC,AL1G0008020';
  end_body;
end_primitive;
primitive '74LVC1G126SE7-74LVC1G126SE-7,SA';
  pin
    'A':
      PIN_NUMBER='(2)';
      INPUT_LOAD='(-0.01,0.01)';
      PINUSE='IN';
    'Y':
      PIN_NUMBER='(4)';
      OUTPUT_LOAD='(1.0,-1.0)';
      PINUSE='OUT';
    'VCC':
      PIN_NUMBER='(5)';
      PINUSE='POWER';
      NO_LOAD_CHECK='Both';
      NO_IO_CHECK='Both';
      NO_ASSERT_CHECK='TRUE';
      NO_DIR_CHECK='TRUE';
      ALLOW_CONNECT='TRUE';
    'GND':
      PIN_NUMBER='(3)';
      PINUSE='POWER';
      NO_LOAD_CHECK='Both';
      NO_IO_CHECK='Both';
      NO_ASSERT_CHECK='TRUE';
      NO_DIR_CHECK='TRUE';
      ALLOW_CONNECT='TRUE';
    'OE':
      PIN_NUMBER='(1)';
      INPUT_LOAD='(-0.01,0.01)';
      PINUSE='IN';
  end_pin;
  body
      PART_NAME='74LVC1G126SE7';
      BODY_NAME='74LVC1G126SE7';
      PHYS_DES_PREFIX='U';
      CLASS='IC';
      STANDARD='';
      LIFECYCLE='';
      JEDEC_TYPE='SOT353_0-65_2X1-25';
      DESCRIPTION='IC OTHER(5P) 74LVC1G126SE-7 (SOT353)';
      MANUFTR='DDS';
      MANUF_PN='74LVC1G126SE-7';
      RD_CMPLS_LVL='EP(V1)';
      CMPLS_LVL='EP(V1)';
      FROM_PJ='F0C-IVES';
      DIP_SMD='';
      DATA='DDS_74LVC1G126SE-7.pdf';
      EE_CHECK_LIST='';
      FP_ECN='';
      PSL='';
      CREATOR='';
      STATUS='';
      MSD='';
      ESD_CDM='';
      ESD_HBM='';
      ESD_MM='';
      PIN_LENGTH_SHORT_PIN='0 MILS';
      PIN_LENGTH_LONG_PIN='0 MILS';
      CREATEDAY='20210615';
      PARENT_PART_TYPE='74LVC1G126SE7';
      PARENT_PPT='74LVC1G126SE7';
      PARENT_PPT_PART='74LVC1G126SE7-74LVC1G126SE-7,SMLF,IC,AL1G0126009';
  end_body;
end_primitive;
primitive '74LVC1G17GW-74LVC1G17GW,SMLF,IA';
  pin
    'VCC':
      PIN_NUMBER='(5)';
      PINUSE='POWER';
      NO_LOAD_CHECK='Both';
      NO_IO_CHECK='Both';
      NO_ASSERT_CHECK='TRUE';
      NO_DIR_CHECK='TRUE';
      ALLOW_CONNECT='TRUE';
    'A':
      PIN_NUMBER='(2)';
      INPUT_LOAD='(-0.01,0.01)';
      PINUSE='IN';
    'GND':
      PIN_NUMBER='(3)';
      PINUSE='POWER';
      NO_LOAD_CHECK='Both';
      NO_IO_CHECK='Both';
      NO_ASSERT_CHECK='TRUE';
      NO_DIR_CHECK='TRUE';
      ALLOW_CONNECT='TRUE';
    'Y':
      PIN_NUMBER='(4)';
      OUTPUT_TYPE='(OC,AND)';
      OUTPUT_LOAD='(1.0,*)';
      PINUSE='OCA';
    'NC':
      PIN_NUMBER='(1)';
      OUTPUT_TYPE='(TS,TS)';
      INPUT_LOAD='(-0.01,0.01)';
      OUTPUT_LOAD='(1.0,-1.0)';
      PINUSE='TRI';
  end_pin;
  body
      PART_NAME='74LVC1G17GW';
      BODY_NAME='74LVC1G17GW';
      PHYS_DES_PREFIX='U';
      CLASS='IC';
      STANDARD='';
      LIFECYCLE='';
      JEDEC_TYPE='TSSOP5';
      DESCRIPTION='IC OTHER(5P) 74LVC1G17GW(TSSOP)';
      MANUFTR='NXP';
      MANUF_PN='74LVC1G17GW';
      RD_CMPLS_LVL='EP(V1)';
      CMPLS_LVL='EP(V1)';
      FROM_PJ='MF1-EUPHIE';
      DIP_SMD='';
      DATA='NXP_74LVC1G17.pdf';
      EE_CHECK_LIST='';
      FP_ECN='';
      PSL='';
      CREATOR='';
      STATUS='';
      CREATEDAY='20140828';
      PARENT_PART_TYPE='74LVC1G17GW';
      PARENT_PPT='74LVC1G17GW';
      PARENT_PPT_PART='74LVC1G17GW-74LVC1G17GW,SMLF,IC,AL1G0017K01';
  end_body;
end_primitive;
primitive '74LVC1G32GW_SMLF-74LVC1G32GW,IA';
  pin
    'I0':
      PIN_NUMBER='(1)';
      INPUT_LOAD='(-0.01,0.01)';
      PINUSE='IN';
    'I1':
      PIN_NUMBER='(2)';
      INPUT_LOAD='(-0.01,0.01)';
      PINUSE='IN';
    'O':
      PIN_NUMBER='(4)';
      OUTPUT_LOAD='(1.0,-1.0)';
      PINUSE='OUT';
    'VCC':
      PIN_NUMBER='(5)';
      PINUSE='POWER';
    'GND':
      PIN_NUMBER='(3)';
      PINUSE='POWER';
  end_pin;
  body
      CLASS='IC';
      PART_NAME='74LVC1G32GW';
      PHYS_DES_PREFIX='U';
      STANDARD='';
      LIFECYCLE='';
      JEDEC_TYPE='SOT353_Q';
      DESCRIPTION='IC(5P)74LVC1G32GW (SC70-5)';
      HEIGHT='.044IN';
      COMPONENT_TYPE='SMALLSMT';
      LEAD_LENGTH='';
      DFM_EXCLUSION='';
      DAY='20101005';
      PARENT_PART_TYPE='74LVC1G32GW';
      PARENT_PPT='74LVC1G32GW';
      PARENT_PPT_PART='74LVC1G32GW_SMLF-74LVC1G32GW,IC,ALVC1G32007';
  end_body;
end_primitive;
primitive '74LVC1G66GV-74LVC1G66GV,SMLF,IA';
  pin
    'Y':
      PIN_NUMBER='(1)';
      BIDIRECTIONAL='TRUE';
      INPUT_LOAD='(-0.01,0.01)';
      OUTPUT_LOAD='(1.0,-1.0)';
      PINUSE='BI';
    'Z':
      PIN_NUMBER='(2)';
      BIDIRECTIONAL='TRUE';
      INPUT_LOAD='(-0.01,0.01)';
      OUTPUT_LOAD='(1.0,-1.0)';
      PINUSE='BI';
    'GND':
      PIN_NUMBER='(3)';
      PINUSE='POWER';
      NO_LOAD_CHECK='Both';
      NO_IO_CHECK='Both';
      NO_ASSERT_CHECK='TRUE';
      NO_DIR_CHECK='TRUE';
      ALLOW_CONNECT='TRUE';
    'E':
      PIN_NUMBER='(4)';
      INPUT_LOAD='(-0.01,0.01)';
      PINUSE='IN';
    'VCC':
      PIN_NUMBER='(5)';
      PINUSE='POWER';
      NO_LOAD_CHECK='Both';
      NO_IO_CHECK='Both';
      NO_ASSERT_CHECK='TRUE';
      NO_DIR_CHECK='TRUE';
      ALLOW_CONNECT='TRUE';
  end_pin;
  body
      PART_NAME='74LVC1G66GV';
      BODY_NAME='74LVC1G66GV';
      PHYS_DES_PREFIX='U';
      CLASS='IC';
      STANDARD='';
      LIFECYCLE='';
      JEDEC_TYPE='SC74AXA';
      DESCRIPTION='IC(5P) 74LVC1G66GV(SOT753)';
      MANUFTR='PHI';
      MANUF_PN='74LVC1G66GV';
      RD_CMPLS_LVL='';
      CMPLS_LVL='EP';
      FROM_PJ='S4P-FRANK';
      DIP_SMD='';
      DATA='PHI_74LVC1G66.pdf';
      EE_CHECK_LIST='SC74AXA.xls';
      FP_ECN='';
      PSL='';
      CREATOR='';
      STATUS='';
      CREATEDAY='20140912';
      PARENT_PART_TYPE='74LVC1G66GV';
      PARENT_PPT='74LVC1G66GV';
      PARENT_PPT_PART='74LVC1G66GV-74LVC1G66GV,SMLF,IC,AL001G66000';
  end_body;
end_primitive;
primitive '74LVC2G07DW7-74LVC2G07DW-7,SMLA';
  pin
    '1A':
      PIN_NUMBER='(1)';
      INPUT_LOAD='(-0.01,0.01)';
      PINUSE='IN';
    '2A':
      PIN_NUMBER='(3)';
      INPUT_LOAD='(-0.01,0.01)';
      PINUSE='IN';
    '1Y':
      PIN_NUMBER='(6)';
      OUTPUT_LOAD='(1.0,-1.0)';
      PINUSE='OUT';
    '2Y':
      PIN_NUMBER='(4)';
      OUTPUT_LOAD='(1.0,-1.0)';
      PINUSE='OUT';
    'GND':
      PIN_NUMBER='(2)';
      PINUSE='POWER';
      NO_LOAD_CHECK='Both';
      NO_IO_CHECK='Both';
      NO_ASSERT_CHECK='TRUE';
      NO_DIR_CHECK='TRUE';
      ALLOW_CONNECT='TRUE';
    'VCC':
      PIN_NUMBER='(5)';
      PINUSE='POWER';
      NO_LOAD_CHECK='Both';
      NO_IO_CHECK='Both';
      NO_ASSERT_CHECK='TRUE';
      NO_DIR_CHECK='TRUE';
      ALLOW_CONNECT='TRUE';
  end_pin;
  body
      PART_NAME='74LVC2G07DW7';
      BODY_NAME='74LVC2G07DW7';
      PHYS_DES_PREFIX='U';
      CLASS='IC';
      STANDARD='';
      LIFECYCLE='';
      JEDEC_TYPE='SOT363_0-65_2X1-25XC';
      DESCRIPTION='IC OTHER(6P)74LVC2G07DW-7(SOT-363)';
      MANUFTR='DDS';
      MANUF_PN='74LVC2G07DW-7';
      RD_CMPLS_LVL='EP(V1)';
      CMPLS_LVL='EP(V1)';
      FROM_PJ='F0C-IVES';
      DIP_SMD='';
      DATA='DDS_74LVC2G07DW-7.pdf';
      EE_CHECK_LIST='';
      FP_ECN='';
      PSL='';
      CREATOR='';
      STATUS='';
      MSD='';
      ESD_CDM='';
      ESD_HBM='';
      ESD_MM='';
      PIN_LENGTH_SHORT_PIN='0 MILS';
      PIN_LENGTH_LONG_PIN='0 MILS';
      CREATEDAY='20210611';
      PARENT_PART_TYPE='74LVC2G07DW7';
      PARENT_PPT='74LVC2G07DW7';
      PARENT_PPT_PART='74LVC2G07DW7-74LVC2G07DW-7,SMLF,IC,AL002G07003';
  end_body;
end_primitive;
primitive '74LVC2G07DW7-74LVC2G07DW-7,SMLB';
  pin
    '1A':
      PIN_NUMBER='(1)';
      INPUT_LOAD='(-0.01,0.01)';
      PINUSE='IN';
    '2A':
      PIN_NUMBER='(3)';
      INPUT_LOAD='(-0.01,0.01)';
      PINUSE='IN';
    '1Y':
      PIN_NUMBER='(6)';
      OUTPUT_LOAD='(1.0,-1.0)';
      PINUSE='OUT';
    '2Y':
      PIN_NUMBER='(4)';
      OUTPUT_LOAD='(1.0,-1.0)';
      PINUSE='OUT';
    'GND':
      PIN_NUMBER='(2)';
      PINUSE='POWER';
      NO_LOAD_CHECK='Both';
      NO_IO_CHECK='Both';
      NO_ASSERT_CHECK='TRUE';
      NO_DIR_CHECK='TRUE';
      ALLOW_CONNECT='TRUE';
    'VCC':
      PIN_NUMBER='(5)';
      PINUSE='POWER';
      NO_LOAD_CHECK='Both';
      NO_IO_CHECK='Both';
      NO_ASSERT_CHECK='TRUE';
      NO_DIR_CHECK='TRUE';
      ALLOW_CONNECT='TRUE';
  end_pin;
  body
      PART_NAME='74LVC2G07DW7';
      BODY_NAME='74LVC2G07DW7';
      PHYS_DES_PREFIX='U';
      CLASS='IC';
      STANDARD='';
      LIFECYCLE='';
      JEDEC_TYPE='SOT363_0-65_2X1-25XC';
      DESCRIPTION='IC OTHER(6P)74LVC2G07DW-7(SOT-363)';
      MANUFTR='DDS';
      MANUF_PN='74LVC2G07DW-7';
      RD_CMPLS_LVL='EP(V1)';
      CMPLS_LVL='EP(V1)';
      FROM_PJ='F0C-IVES';
      DIP_SMD='';
      DATA='DDS_74LVC2G07DW-7.pdf';
      EE_CHECK_LIST='';
      FP_ECN='';
      PSL='';
      CREATOR='';
      STATUS='';
      MSD='';
      ESD_CDM='';
      ESD_HBM='';
      ESD_MM='';
      PIN_LENGTH_SHORT_PIN='0 MILS';
      PIN_LENGTH_LONG_PIN='0 MILS';
      CREATEDAY='20210611';
      PARENT_PART_TYPE='74LVC2G07DW7';
      PARENT_PPT='74LVC2G07DW7';
      PARENT_PPT_PART='74LVC2G07DW7-74LVC2G07DW-7,SMLF,EMPTY,AL002G07003';
  end_body;
end_primitive;
primitive '74LVC2G08DP-74LVC2G08DP,SMLF,IA';
  pin
    'VCC':
      PIN_NUMBER='(8,0)';
      PINUSE='POWER';
      NO_LOAD_CHECK='Both';
      NO_IO_CHECK='Both';
      NO_ASSERT_CHECK='TRUE';
      NO_DIR_CHECK='TRUE';
      ALLOW_CONNECT='TRUE';
    'GND':
      PIN_NUMBER='(4,0)';
      PINUSE='POWER';
      NO_LOAD_CHECK='Both';
      NO_IO_CHECK='Both';
      NO_ASSERT_CHECK='TRUE';
      NO_DIR_CHECK='TRUE';
      ALLOW_CONNECT='TRUE';
    '1A':
      PIN_NUMBER='(1,0)';
      INPUT_LOAD='(-0.01,0.01)';
      PINUSE='IN';
    '1B':
      PIN_NUMBER='(2,0)';
      INPUT_LOAD='(-0.01,0.01)';
      PINUSE='IN';
    '1Y':
      PIN_NUMBER='(7,0)';
      OUTPUT_LOAD='(1.0,-1.0)';
      PINUSE='OUT';
    '2A':
      PIN_NUMBER='(0,5)';
      INPUT_LOAD='(-0.01,0.01)';
      PINUSE='IN';
    '2B':
      PIN_NUMBER='(0,6)';
      INPUT_LOAD='(-0.01,0.01)';
      PINUSE='IN';
    '2Y':
      PIN_NUMBER='(0,3)';
      OUTPUT_LOAD='(1.0,-1.0)';
      PINUSE='OUT';
  end_pin;
  body
      PART_NAME='74LVC2G08DP';
      BODY_NAME='74LVC2G08DP';
      PHYS_DES_PREFIX='U';
      CLASS='IC';
      STANDARD='';
      LIFECYCLE='';
      JEDEC_TYPE='TSSOP8_0-65_3X3';
      DESCRIPTION='IC OTHER(8P) 74LVC2G08DP(TSSOP)';
      MANUFTR='NXP';
      MANUF_PN='74LVC2G08DP';
      RD_CMPLS_LVL='EP(V1)';
      CMPLS_LVL='EP(V1)';
      FROM_PJ='F08-OWEN';
      DIP_SMD='';
      DATA='NXP_74LVC2G08DP.pdf';
      EE_CHECK_LIST='';
      FP_ECN='';
      PSL='';
      CREATOR='';
      STATUS='';
      MSD='';
      ESD_CDM='';
      ESD_HBM='';
      ESD_MM='';
      PIN_LENGTH_SHORT_PIN='';
      PIN_LENGTH_LONG_PIN='';
      CREATEDAY='20160122';
      PARENT_PART_TYPE='74LVC2G08DP';
      PARENT_PPT='74LVC2G08DP';
      PARENT_PPT_PART='74LVC2G08DP-74LVC2G08DP,SMLF,IC,ALVC2G08K01';
  end_body;
end_primitive;
primitive '74LVC2G17GW-74LVC2G17GW,SMLF,IA';
  pin
    'VCC':
      PIN_NUMBER='(5)';
      PINUSE='POWER';
      NO_LOAD_CHECK='Both';
      NO_IO_CHECK='Both';
      NO_ASSERT_CHECK='TRUE';
      NO_DIR_CHECK='TRUE';
      ALLOW_CONNECT='TRUE';
    'B1':
      PIN_NUMBER='(4)';
      OUTPUT_LOAD='(1.0,-1.0)';
      PINUSE='OUT';
    'GND':
      PIN_NUMBER='(2)';
      PINUSE='POWER';
      NO_LOAD_CHECK='Both';
      NO_IO_CHECK='Both';
      NO_ASSERT_CHECK='TRUE';
      NO_DIR_CHECK='TRUE';
      ALLOW_CONNECT='TRUE';
    'A0':
      PIN_NUMBER='(1)';
      INPUT_LOAD='(-0.01,0.01)';
      PINUSE='IN';
    'A1':
      PIN_NUMBER='(3)';
      INPUT_LOAD='(-0.01,0.01)';
      PINUSE='IN';
    'B0':
      PIN_NUMBER='(6)';
      OUTPUT_LOAD='(1.0,-1.0)';
      PINUSE='OUT';
  end_pin;
  body
      PART_NAME='74LVC2G17GW';
      BODY_NAME='74LVC2G17GW';
      PHYS_DES_PREFIX='U';
      CLASS='IC';
      STANDARD='';
      LIFECYCLE='';
      JEDEC_TYPE='SOT363';
      DESCRIPTION='IC(6P) 74LVC2G17GW (SC-88)';
      MANUFTR='PHI';
      MANUF_PN='74LVC2G17GW';
      RD_CMPLS_LVL='EP';
      CMPLS_LVL='EP';
      FROM_PJ='T6S-LOUISE';
      DIP_SMD='';
      DATA='74LVC2G17.pdf';
      EE_CHECK_LIST='';
      FP_ECN='';
      PSL='';
      CREATOR='';
      STATUS='';
      CREATEDAY='20121122';
      PARENT_PART_TYPE='74LVC2G17GW';
      PARENT_PPT='74LVC2G17GW';
      PARENT_PPT_PART='74LVC2G17GW-74LVC2G17GW,SMLF,IC,AL2G0017005';
  end_body;
end_primitive;
primitive '9FGL0251DKILFT-9FGL0251DKILFT,A';
  pin
    'XIN||CLKIN_25':
      PIN_NUMBER='(1)';
      INPUT_LOAD='(-0.01,0.01)';
      PINUSE='IN';
    'X2':
      PIN_NUMBER='(2)';
      OUTPUT_LOAD='(1.0,-1.0)';
      PINUSE='OUT';
    'VDDXTAL3.3':
      PIN_NUMBER='(3)';
      PINUSE='POWER';
      NO_LOAD_CHECK='Both';
      NO_IO_CHECK='Both';
      NO_ASSERT_CHECK='TRUE';
      NO_DIR_CHECK='TRUE';
      ALLOW_CONNECT='TRUE';
    'VSADR||REF3.3':
      PIN_NUMBER='(4)';
      BIDIRECTIONAL='TRUE';
      INPUT_LOAD='(-0.01,0.01)';
      OUTPUT_LOAD='(1.0,-1.0)';
      PINUSE='BI';
    'GNDREF':
      PIN_NUMBER='(5)';
      PINUSE='POWER';
      NO_LOAD_CHECK='Both';
      NO_IO_CHECK='Both';
      NO_ASSERT_CHECK='TRUE';
      NO_DIR_CHECK='TRUE';
      ALLOW_CONNECT='TRUE';
    'GNDDIG':
      PIN_NUMBER='(6)';
      PINUSE='POWER';
      NO_LOAD_CHECK='Both';
      NO_IO_CHECK='Both';
      NO_ASSERT_CHECK='TRUE';
      NO_DIR_CHECK='TRUE';
      ALLOW_CONNECT='TRUE';
    'VDDDIG3.3':
      PIN_NUMBER='(7)';
      PINUSE='POWER';
      NO_LOAD_CHECK='Both';
      NO_IO_CHECK='Both';
      NO_ASSERT_CHECK='TRUE';
      NO_DIR_CHECK='TRUE';
      ALLOW_CONNECT='TRUE';
    'SCLK_3.3':
      PIN_NUMBER='(8)';
      INPUT_LOAD='(-0.01,0.01)';
      PINUSE='IN';
    'SDATA_3.3':
      PIN_NUMBER='(9)';
      BIDIRECTIONAL='TRUE';
      INPUT_LOAD='(-0.01,0.01)';
      OUTPUT_LOAD='(1.0,-1.0)';
      PINUSE='BI';
    'GND_10':
      PIN_NUMBER='(10)';
      PINUSE='POWER';
      NO_LOAD_CHECK='Both';
      NO_IO_CHECK='Both';
      NO_ASSERT_CHECK='TRUE';
      NO_DIR_CHECK='TRUE';
      ALLOW_CONNECT='TRUE';
    'VDD3.3_11':
      PIN_NUMBER='(11)';
      PINUSE='POWER';
      NO_LOAD_CHECK='Both';
      NO_IO_CHECK='Both';
      NO_ASSERT_CHECK='TRUE';
      NO_DIR_CHECK='TRUE';
      ALLOW_CONNECT='TRUE';
    'VOE0#':
      PIN_NUMBER='(12)';
      INPUT_LOAD='(-0.01,0.01)';
      PINUSE='IN';
    'DIF0':
      PIN_NUMBER='(13)';
      OUTPUT_LOAD='(1.0,-1.0)';
      PINUSE='OUT';
    'DIF0#':
      PIN_NUMBER='(14)';
      OUTPUT_LOAD='(1.0,-1.0)';
      PINUSE='OUT';
    'GNDA':
      PIN_NUMBER='(15)';
      PINUSE='POWER';
      NO_LOAD_CHECK='Both';
      NO_IO_CHECK='Both';
      NO_ASSERT_CHECK='TRUE';
      NO_DIR_CHECK='TRUE';
      ALLOW_CONNECT='TRUE';
    'VDDA3.3':
      PIN_NUMBER='(16)';
      PINUSE='POWER';
      NO_LOAD_CHECK='Both';
      NO_IO_CHECK='Both';
      NO_ASSERT_CHECK='TRUE';
      NO_DIR_CHECK='TRUE';
      ALLOW_CONNECT='TRUE';
    'DIF1':
      PIN_NUMBER='(17)';
      OUTPUT_LOAD='(1.0,-1.0)';
      PINUSE='OUT';
    'DIF1#':
      PIN_NUMBER='(18)';
      OUTPUT_LOAD='(1.0,-1.0)';
      PINUSE='OUT';
    'VOE1#':
      PIN_NUMBER='(19)';
      INPUT_LOAD='(-0.01,0.01)';
      PINUSE='IN';
    'VDD3.3_20':
      PIN_NUMBER='(20)';
      PINUSE='POWER';
      NO_LOAD_CHECK='Both';
      NO_IO_CHECK='Both';
      NO_ASSERT_CHECK='TRUE';
      NO_DIR_CHECK='TRUE';
      ALLOW_CONNECT='TRUE';
    'GND_21':
      PIN_NUMBER='(21)';
      PINUSE='POWER';
      NO_LOAD_CHECK='Both';
      NO_IO_CHECK='Both';
      NO_ASSERT_CHECK='TRUE';
      NO_DIR_CHECK='TRUE';
      ALLOW_CONNECT='TRUE';
    '^CKPWRGD_PD#':
      PIN_NUMBER='(22)';
      INPUT_LOAD='(-0.01,0.01)';
      PINUSE='IN';
    '^VSS_EN_TRI':
      PIN_NUMBER='(23)';
      INPUT_LOAD='(-0.01,0.01)';
      PINUSE='IN';
    'GNDXTAL':
      PIN_NUMBER='(24)';
      PINUSE='POWER';
      NO_LOAD_CHECK='Both';
      NO_IO_CHECK='Both';
      NO_ASSERT_CHECK='TRUE';
      NO_DIR_CHECK='TRUE';
      ALLOW_CONNECT='TRUE';
    'TH_GND':
      PIN_NUMBER='(25)';
      PINUSE='POWER';
      NO_LOAD_CHECK='Both';
      NO_IO_CHECK='Both';
      NO_ASSERT_CHECK='TRUE';
      NO_DIR_CHECK='TRUE';
      ALLOW_CONNECT='TRUE';
  end_pin;
  body
      PART_NAME='9FGL0251DKILFT';
      BODY_NAME='9FGL0251DKILFT';
      PHYS_DES_PREFIX='U';
      CLASS='IC';
      STANDARD='';
      LIFECYCLE='';
      JEDEC_TYPE='VFQFPN24_TH_0-5_4X4XI';
      DESCRIPTION='IC(24P)9FGL0251DKILFT(VFQFPN)';
      MANUFTR='RTT';
      MANUF_PN='9FGL0251DKILFT';
      RD_CMPLS_LVL='EP(V1)';
      CMPLS_LVL='';
      FROM_PJ='S7G-DAVID';
      DIP_SMD='';
      DATA='RTT_9FGL0251DKILFT.pdf';
      EE_CHECK_LIST='';
      FP_ECN='';
      PSL='';
      CREATOR='';
      STATUS='';
      MSD='';
      ESD_CDM='';
      ESD_HBM='';
      ESD_MM='';
      PIN_LENGTH_SHORT_PIN='0 MILS';
      PIN_LENGTH_LONG_PIN='0 MILS';
      CREATEDAY='20221223';
      PARENT_PART_TYPE='9FGL0251DKILFT';
      PARENT_PPT='9FGL0251DKILFT';
      PARENT_PPT_PART='9FGL0251DKILFT-9FGL0251DKILFT,SMLF,IC,AL000251002';
  end_body;
end_primitive;
primitive '9QXL2001BNHGI8-9QXL2001BNHGI8,A';
  pin
    'DIF_IN#':
      PIN_NUMBER='(H1)';
      INPUT_LOAD='(-0.01,0.01)';
      PINUSE='IN';
    'NC12':
      PIN_NUMBER='(J2)';
      OUTPUT_TYPE='(TS,TS)';
      INPUT_LOAD='(-0.01,0.01)';
      OUTPUT_LOAD='(1.0,-1.0)';
      PINUSE='TRI';
    'NC1':
      PIN_NUMBER='(B3)';
      OUTPUT_TYPE='(TS,TS)';
      INPUT_LOAD='(-0.01,0.01)';
      OUTPUT_LOAD='(1.0,-1.0)';
      PINUSE='TRI';
    'NC10':
      PIN_NUMBER='(G2)';
      OUTPUT_TYPE='(TS,TS)';
      INPUT_LOAD='(-0.01,0.01)';
      OUTPUT_LOAD='(1.0,-1.0)';
      PINUSE='TRI';
    'DIF15':
      PIN_NUMBER='(A5)';
      OUTPUT_LOAD='(1.0,-1.0)';
      PINUSE='OUT';
    'DIF17':
      PIN_NUMBER='(A1)';
      OUTPUT_LOAD='(1.0,-1.0)';
      PINUSE='OUT';
    'DIF18#':
      PIN_NUMBER='(D1)';
      OUTPUT_LOAD='(1.0,-1.0)';
      PINUSE='OUT';
    'VCKPWRGD_PD#':
      PIN_NUMBER='(M6)';
      INPUT_LOAD='(-0.01,0.01)';
      PINUSE='IN';
    'EPAD':
      PIN_NUMBER='(TH)';
      PINUSE='POWER';
      NO_LOAD_CHECK='Both';
      NO_IO_CHECK='Both';
      NO_ASSERT_CHECK='TRUE';
      NO_DIR_CHECK='TRUE';
      ALLOW_CONNECT='TRUE';
    'NC8':
      PIN_NUMBER='(F2)';
      OUTPUT_TYPE='(TS,TS)';
      INPUT_LOAD='(-0.01,0.01)';
      OUTPUT_LOAD='(1.0,-1.0)';
      PINUSE='TRI';
    'NC11':
      PIN_NUMBER='(G11)';
      OUTPUT_TYPE='(TS,TS)';
      INPUT_LOAD='(-0.01,0.01)';
      OUTPUT_LOAD='(1.0,-1.0)';
      PINUSE='TRI';
    'NC14':
      PIN_NUMBER='(K2)';
      OUTPUT_TYPE='(TS,TS)';
      INPUT_LOAD='(-0.01,0.01)';
      OUTPUT_LOAD='(1.0,-1.0)';
      PINUSE='TRI';
    'NC15':
      PIN_NUMBER='(L6)';
      OUTPUT_TYPE='(TS,TS)';
      INPUT_LOAD='(-0.01,0.01)';
      OUTPUT_LOAD='(1.0,-1.0)';
      PINUSE='TRI';
    'NC13':
      PIN_NUMBER='(J11)';
      OUTPUT_TYPE='(TS,TS)';
      INPUT_LOAD='(-0.01,0.01)';
      OUTPUT_LOAD='(1.0,-1.0)';
      PINUSE='TRI';
    'DIF0':
      PIN_NUMBER='(J1)';
      OUTPUT_LOAD='(1.0,-1.0)';
      PINUSE='OUT';
    'DIF0#':
      PIN_NUMBER='(K1)';
      OUTPUT_LOAD='(1.0,-1.0)';
      PINUSE='OUT';
    'DIF1':
      PIN_NUMBER='(L1)';
      OUTPUT_LOAD='(1.0,-1.0)';
      PINUSE='OUT';
    'DIF1#':
      PIN_NUMBER='(M1)';
      OUTPUT_LOAD='(1.0,-1.0)';
      PINUSE='OUT';
    'DIF10':
      PIN_NUMBER='(D12)';
      OUTPUT_LOAD='(1.0,-1.0)';
      PINUSE='OUT';
    'DIF10#':
      PIN_NUMBER='(C12)';
      OUTPUT_LOAD='(1.0,-1.0)';
      PINUSE='OUT';
    'DIF11':
      PIN_NUMBER='(B12)';
      OUTPUT_LOAD='(1.0,-1.0)';
      PINUSE='OUT';
    'DIF12#':
      PIN_NUMBER='(A10)';
      OUTPUT_LOAD='(1.0,-1.0)';
      PINUSE='OUT';
    'DIF12':
      PIN_NUMBER='(A11)';
      OUTPUT_LOAD='(1.0,-1.0)';
      PINUSE='OUT';
    'DIF13#':
      PIN_NUMBER='(A8)';
      OUTPUT_LOAD='(1.0,-1.0)';
      PINUSE='OUT';
    'DIF14':
      PIN_NUMBER='(A7)';
      OUTPUT_LOAD='(1.0,-1.0)';
      PINUSE='OUT';
    'DIF14#':
      PIN_NUMBER='(A6)';
      OUTPUT_LOAD='(1.0,-1.0)';
      PINUSE='OUT';
    'DIF15#':
      PIN_NUMBER='(A4)';
      OUTPUT_LOAD='(1.0,-1.0)';
      PINUSE='OUT';
    'DIF16':
      PIN_NUMBER='(A3)';
      OUTPUT_LOAD='(1.0,-1.0)';
      PINUSE='OUT';
    'DIF16#':
      PIN_NUMBER='(A2)';
      OUTPUT_LOAD='(1.0,-1.0)';
      PINUSE='OUT';
    'DIF18':
      PIN_NUMBER='(C1)';
      OUTPUT_LOAD='(1.0,-1.0)';
      PINUSE='OUT';
    'DIF_IN':
      PIN_NUMBER='(G1)';
      INPUT_LOAD='(-0.01,0.01)';
      PINUSE='IN';
    'DIF11#':
      PIN_NUMBER='(A12)';
      OUTPUT_LOAD='(1.0,-1.0)';
      PINUSE='OUT';
    'DIF13':
      PIN_NUMBER='(A9)';
      OUTPUT_LOAD='(1.0,-1.0)';
      PINUSE='OUT';
    'DIF17#':
      PIN_NUMBER='(B1)';
      OUTPUT_LOAD='(1.0,-1.0)';
      PINUSE='OUT';
    'NC9':
      PIN_NUMBER='(F11)';
      OUTPUT_TYPE='(TS,TS)';
      INPUT_LOAD='(-0.01,0.01)';
      OUTPUT_LOAD='(1.0,-1.0)';
      PINUSE='TRI';
    'NC7':
      PIN_NUMBER='(D11)';
      OUTPUT_TYPE='(TS,TS)';
      INPUT_LOAD='(-0.01,0.01)';
      OUTPUT_LOAD='(1.0,-1.0)';
      PINUSE='TRI';
    'NC16':
      PIN_NUMBER='(L7)';
      OUTPUT_TYPE='(TS,TS)';
      INPUT_LOAD='(-0.01,0.01)';
      OUTPUT_LOAD='(1.0,-1.0)';
      PINUSE='TRI';
    'NC17':
      PIN_NUMBER='(L3)';
      OUTPUT_TYPE='(TS,TS)';
      INPUT_LOAD='(-0.01,0.01)';
      OUTPUT_LOAD='(1.0,-1.0)';
      PINUSE='TRI';
    'NC18':
      PIN_NUMBER='(L9)';
      OUTPUT_TYPE='(TS,TS)';
      INPUT_LOAD='(-0.01,0.01)';
      OUTPUT_LOAD='(1.0,-1.0)';
      PINUSE='TRI';
    'NC2':
      PIN_NUMBER='(B5)';
      OUTPUT_TYPE='(TS,TS)';
      INPUT_LOAD='(-0.01,0.01)';
      OUTPUT_LOAD='(1.0,-1.0)';
      PINUSE='TRI';
    'NC3':
      PIN_NUMBER='(B7)';
      OUTPUT_TYPE='(TS,TS)';
      INPUT_LOAD='(-0.01,0.01)';
      OUTPUT_LOAD='(1.0,-1.0)';
      PINUSE='TRI';
    'NC4':
      PIN_NUMBER='(B9)';
      OUTPUT_TYPE='(TS,TS)';
      INPUT_LOAD='(-0.01,0.01)';
      OUTPUT_LOAD='(1.0,-1.0)';
      PINUSE='TRI';
    'NC5':
      PIN_NUMBER='(C2)';
      OUTPUT_TYPE='(TS,TS)';
      INPUT_LOAD='(-0.01,0.01)';
      OUTPUT_LOAD='(1.0,-1.0)';
      PINUSE='TRI';
    'NC6':
      PIN_NUMBER='(D2)';
      OUTPUT_TYPE='(TS,TS)';
      INPUT_LOAD='(-0.01,0.01)';
      OUTPUT_LOAD='(1.0,-1.0)';
      PINUSE='TRI';
    'DIF2':
      PIN_NUMBER='(M2)';
      OUTPUT_LOAD='(1.0,-1.0)';
      PINUSE='OUT';
    'DIF2#':
      PIN_NUMBER='(M3)';
      OUTPUT_LOAD='(1.0,-1.0)';
      PINUSE='OUT';
    'DIF3':
      PIN_NUMBER='(M4)';
      OUTPUT_LOAD='(1.0,-1.0)';
      PINUSE='OUT';
    'DIF3#':
      PIN_NUMBER='(M5)';
      OUTPUT_LOAD='(1.0,-1.0)';
      PINUSE='OUT';
    'DIF4':
      PIN_NUMBER='(M7)';
      OUTPUT_LOAD='(1.0,-1.0)';
      PINUSE='OUT';
    'DIF4#':
      PIN_NUMBER='(M8)';
      OUTPUT_LOAD='(1.0,-1.0)';
      PINUSE='OUT';
    'DIF5':
      PIN_NUMBER='(M9)';
      OUTPUT_LOAD='(1.0,-1.0)';
      PINUSE='OUT';
    'DIF5#':
      PIN_NUMBER='(M10)';
      OUTPUT_LOAD='(1.0,-1.0)';
      PINUSE='OUT';
    'DIF6':
      PIN_NUMBER='(M11)';
      OUTPUT_LOAD='(1.0,-1.0)';
      PINUSE='OUT';
    'DIF6#':
      PIN_NUMBER='(M12)';
      OUTPUT_LOAD='(1.0,-1.0)';
      PINUSE='OUT';
    'DIF7':
      PIN_NUMBER='(L12)';
      OUTPUT_LOAD='(1.0,-1.0)';
      PINUSE='OUT';
    'DIF7#':
      PIN_NUMBER='(K12)';
      OUTPUT_LOAD='(1.0,-1.0)';
      PINUSE='OUT';
    'DIF8':
      PIN_NUMBER='(J12)';
      OUTPUT_LOAD='(1.0,-1.0)';
      PINUSE='OUT';
    'DIF8#':
      PIN_NUMBER='(H12)';
      OUTPUT_LOAD='(1.0,-1.0)';
      PINUSE='OUT';
    'DIF9':
      PIN_NUMBER='(G12)';
      OUTPUT_LOAD='(1.0,-1.0)';
      PINUSE='OUT';
    'DIF9#':
      PIN_NUMBER='(F12)';
      OUTPUT_LOAD='(1.0,-1.0)';
      PINUSE='OUT';
    'VSBEN':
      PIN_NUMBER='(E2)';
      INPUT_LOAD='(-0.01,0.01)';
      PINUSE='IN';
    'VOE5#||DATA':
      PIN_NUMBER='(L8)';
      INPUT_LOAD='(-0.01,0.01)';
      PINUSE='IN';
    'VOE6#||CLK':
      PIN_NUMBER='(L10)';
      INPUT_LOAD='(-0.01,0.01)';
      PINUSE='IN';
    'VOE7#':
      PIN_NUMBER='(K11)';
      INPUT_LOAD='(-0.01,0.01)';
      PINUSE='IN';
    'VOE8#':
      PIN_NUMBER='(H11)';
      INPUT_LOAD='(-0.01,0.01)';
      PINUSE='IN';
    'VOE9#':
      PIN_NUMBER='(E12)';
      INPUT_LOAD='(-0.01,0.01)';
      PINUSE='IN';
    'VOE10#||SHFT_LD#':
      PIN_NUMBER='(E11)';
      INPUT_LOAD='(-0.01,0.01)';
      PINUSE='IN';
    'VOE11#':
      PIN_NUMBER='(C11)';
      INPUT_LOAD='(-0.01,0.01)';
      PINUSE='IN';
    'VOE12#':
      PIN_NUMBER='(B10)';
      INPUT_LOAD='(-0.01,0.01)';
      PINUSE='IN';
    'SMBCLK':
      PIN_NUMBER='(L5)';
      INPUT_LOAD='(-0.01,0.01)';
      PINUSE='IN';
    'SMBDAT':
      PIN_NUMBER='(L4)';
      BIDIRECTIONAL='TRUE';
      INPUT_LOAD='(-0.01,0.01)';
      OUTPUT_LOAD='(1.0,-1.0)';
      PINUSE='BI';
    'VDDA3.3':
      PIN_NUMBER='(B6)';
      PINUSE='POWER';
      NO_LOAD_CHECK='Both';
      NO_IO_CHECK='Both';
      NO_ASSERT_CHECK='TRUE';
      NO_DIR_CHECK='TRUE';
      ALLOW_CONNECT='TRUE';
    'VDDO3.3_B2':
      PIN_NUMBER='(B2)';
      PINUSE='POWER';
      NO_LOAD_CHECK='Both';
      NO_IO_CHECK='Both';
      NO_ASSERT_CHECK='TRUE';
      NO_DIR_CHECK='TRUE';
      ALLOW_CONNECT='TRUE';
    'VDDO3.3_B11':
      PIN_NUMBER='(B11)';
      PINUSE='POWER';
      NO_LOAD_CHECK='Both';
      NO_IO_CHECK='Both';
      NO_ASSERT_CHECK='TRUE';
      NO_DIR_CHECK='TRUE';
      ALLOW_CONNECT='TRUE';
    'VDDO3.3_L2':
      PIN_NUMBER='(L2)';
      PINUSE='POWER';
      NO_LOAD_CHECK='Both';
      NO_IO_CHECK='Both';
      NO_ASSERT_CHECK='TRUE';
      NO_DIR_CHECK='TRUE';
      ALLOW_CONNECT='TRUE';
    'VDDO3.3_L11':
      PIN_NUMBER='(L11)';
      PINUSE='POWER';
      NO_LOAD_CHECK='Both';
      NO_IO_CHECK='Both';
      NO_ASSERT_CHECK='TRUE';
      NO_DIR_CHECK='TRUE';
      ALLOW_CONNECT='TRUE';
    'VDDR3.3':
      PIN_NUMBER='(H2)';
      PINUSE='POWER';
      NO_LOAD_CHECK='Both';
      NO_IO_CHECK='Both';
      NO_ASSERT_CHECK='TRUE';
      NO_DIR_CHECK='TRUE';
      ALLOW_CONNECT='TRUE';
    '^VSADR0_TRI':
      PIN_NUMBER='(B4)';
      INPUT_LOAD='(-0.01,0.01)';
      PINUSE='IN';
    '^VSADR1_TRI':
      PIN_NUMBER='(B8)';
      INPUT_LOAD='(-0.01,0.01)';
      PINUSE='IN';
    'DIF19':
      PIN_NUMBER='(E1)';
      OUTPUT_LOAD='(1.0,-1.0)';
      PINUSE='OUT';
    'DIF19#':
      PIN_NUMBER='(F1)';
      OUTPUT_LOAD='(1.0,-1.0)';
      PINUSE='OUT';
  end_pin;
  body
      PART_NAME='9QXL2001BNHGI8';
      BODY_NAME='9QXL2001BNHGI8';
      PHYS_DES_PREFIX='U';
      CLASS='IC';
      STANDARD='';
      LIFECYCLE='';
      JEDEC_TYPE='GQFN80_TH_0-5_6X6';
      DESCRIPTION='IC OTHER(80P)9QXL2001BNHGI8(GQFN)';
      MANUFTR='IDT';
      MANUF_PN='9QXL2001BNHGI8';
      RD_CMPLS_LVL='EP(V1)';
      CMPLS_LVL='';
      FROM_PJ='F0C-ALEN';
      DIP_SMD='';
      DATA='IDT_9QXL2001BNHGI8.pdf';
      EE_CHECK_LIST='';
      FP_ECN='';
      PSL='';
      CREATOR='';
      STATUS='';
      MSD='NA';
      ESD_CDM='NA';
      ESD_HBM='NA';
      ESD_MM='NA';
      PIN_LENGTH_SHORT_PIN='0 MILS';
      PIN_LENGTH_LONG_PIN='0 MILS';
      CREATEDAY='20190118';
      PARENT_PART_TYPE='9QXL2001BNHGI8';
      PARENT_PPT='9QXL2001BNHGI8';
      PARENT_PPT_PART='9QXL2001BNHGI8-9QXL2001BNHGI8,SMLF,IC,AJ020010003';
  end_body;
end_primitive;
primitive '9SQ440NQQI8-9SQ440NQQI8,SMLF,IA';
  pin
    '25M1#':
      PIN_NUMBER='(A2,0)';
      OUTPUT_LOAD='(1.0,-1.0)';
      PINUSE='OUT';
    'EPAD':
      PIN_NUMBER='(C1,0)';
      PINUSE='POWER';
      NO_LOAD_CHECK='Both';
      NO_IO_CHECK='Both';
      NO_ASSERT_CHECK='TRUE';
      NO_DIR_CHECK='TRUE';
      ALLOW_CONNECT='TRUE';
    'GNDXTAL':
      PIN_NUMBER='(A14,0)';
      PINUSE='POWER';
      NO_LOAD_CHECK='Both';
      NO_IO_CHECK='Both';
      NO_ASSERT_CHECK='TRUE';
      NO_DIR_CHECK='TRUE';
      ALLOW_CONNECT='TRUE';
    'SMB_ADR1_TRI':
      PIN_NUMBER='(B9,0)';
      INPUT_LOAD='(-0.01,0.01)';
      PINUSE='IN';
    'SBI_CLK':
      PIN_NUMBER='(A54,0)';
      INPUT_LOAD='(-0.01,0.01)';
      PINUSE='IN';
    'SHFT_LD#':
      PIN_NUMBER='(B42,0)';
      INPUT_LOAD='(-0.01,0.01)';
      PINUSE='IN';
    'OE2#':
      PIN_NUMBER='(A29,0)';
      INPUT_LOAD='(-0.01,0.01)';
      PINUSE='IN';
    'OE3#':
      PIN_NUMBER='(A26,0)';
      INPUT_LOAD='(-0.01,0.01)';
      PINUSE='IN';
    'OE4#':
      PIN_NUMBER='(B19,0)';
      INPUT_LOAD='(-0.01,0.01)';
      PINUSE='IN';
    'OE1#':
      PIN_NUMBER='(A30,0)';
      INPUT_LOAD='(-0.01,0.01)';
      PINUSE='IN';
    'OE5#':
      PIN_NUMBER='(B15,0)';
      INPUT_LOAD='(-0.01,0.01)';
      PINUSE='IN';
    '25M0#':
      PIN_NUMBER='(A4,0)';
      OUTPUT_LOAD='(1.0,-1.0)';
      PINUSE='OUT';
    '25M0':
      PIN_NUMBER='(A5,0)';
      OUTPUT_LOAD='(1.0,-1.0)';
      PINUSE='OUT';
    '25M1':
      PIN_NUMBER='(A3,0)';
      OUTPUT_LOAD='(1.0,-1.0)';
      PINUSE='OUT';
    '25M2#':
      PIN_NUMBER='(A55,0)';
      OUTPUT_LOAD='(1.0,-1.0)';
      PINUSE='OUT';
    '25M2':
      PIN_NUMBER='(A56,0)';
      OUTPUT_LOAD='(1.0,-1.0)';
      PINUSE='OUT';
    '25MPG':
      PIN_NUMBER='(A1,0)';
      INPUT_LOAD='(-0.01,0.01)';
      PINUSE='IN';
    '100M0#':
      PIN_NUMBER='(A33,0)';
      OUTPUT_LOAD='(1.0,-1.0)';
      PINUSE='OUT';
    '100M0':
      PIN_NUMBER='(A34,0)';
      OUTPUT_LOAD='(1.0,-1.0)';
      PINUSE='OUT';
    '100M1#':
      PIN_NUMBER='(A31,0)';
      OUTPUT_LOAD='(1.0,-1.0)';
      PINUSE='OUT';
    '100M1':
      PIN_NUMBER='(A32,0)';
      OUTPUT_LOAD='(1.0,-1.0)';
      PINUSE='OUT';
    '100M2#':
      PIN_NUMBER='(A27,0)';
      OUTPUT_LOAD='(1.0,-1.0)';
      PINUSE='OUT';
    '100M2':
      PIN_NUMBER='(A28,0)';
      OUTPUT_LOAD='(1.0,-1.0)';
      PINUSE='OUT';
    '100M3#':
      PIN_NUMBER='(A24,0)';
      OUTPUT_LOAD='(1.0,-1.0)';
      PINUSE='OUT';
    '100M3':
      PIN_NUMBER='(A25,0)';
      OUTPUT_LOAD='(1.0,-1.0)';
      PINUSE='OUT';
    '100M4#':
      PIN_NUMBER='(A22,0)';
      OUTPUT_LOAD='(1.0,-1.0)';
      PINUSE='OUT';
    '100M4':
      PIN_NUMBER='(A23,0)';
      OUTPUT_LOAD='(1.0,-1.0)';
      PINUSE='OUT';
    '100M5#':
      PIN_NUMBER='(A20,0)';
      OUTPUT_LOAD='(1.0,-1.0)';
      PINUSE='OUT';
    '100M5':
      PIN_NUMBER='(A21,0)';
      OUTPUT_LOAD='(1.0,-1.0)';
      PINUSE='OUT';
    '100M6#':
      PIN_NUMBER='(A18,0)';
      OUTPUT_LOAD='(1.0,-1.0)';
      PINUSE='OUT';
    '100M6':
      PIN_NUMBER='(A19,0)';
      OUTPUT_LOAD='(1.0,-1.0)';
      PINUSE='OUT';
    'GNDS':
      PIN_NUMBER='(B10,0)';
      PINUSE='POWER';
      NO_LOAD_CHECK='Both';
      NO_IO_CHECK='Both';
      NO_ASSERT_CHECK='TRUE';
      NO_DIR_CHECK='TRUE';
      ALLOW_CONNECT='TRUE';
    'MXCK0#':
      PIN_NUMBER='(A51,0)';
      OUTPUT_LOAD='(1.0,-1.0)';
      PINUSE='OUT';
    'MXCK0':
      PIN_NUMBER='(A52,0)';
      OUTPUT_LOAD='(1.0,-1.0)';
      PINUSE='OUT';
    'MXCK1#':
      PIN_NUMBER='(A49,0)';
      OUTPUT_LOAD='(1.0,-1.0)';
      PINUSE='OUT';
    'MXCK1':
      PIN_NUMBER='(A50,0)';
      OUTPUT_LOAD='(1.0,-1.0)';
      PINUSE='OUT';
    'MXCK2#':
      PIN_NUMBER='(A47,0)';
      OUTPUT_LOAD='(1.0,-1.0)';
      PINUSE='OUT';
    'MXCK2':
      PIN_NUMBER='(A48,0)';
      OUTPUT_LOAD='(1.0,-1.0)';
      PINUSE='OUT';
    'MXCK3#':
      PIN_NUMBER='(A45,0)';
      OUTPUT_LOAD='(1.0,-1.0)';
      PINUSE='OUT';
    'MXCK3':
      PIN_NUMBER='(A46,0)';
      OUTPUT_LOAD='(1.0,-1.0)';
      PINUSE='OUT';
    'MXCK4#':
      PIN_NUMBER='(A43,0)';
      OUTPUT_LOAD='(1.0,-1.0)';
      PINUSE='OUT';
    'MXCK4':
      PIN_NUMBER='(A44,0)';
      OUTPUT_LOAD='(1.0,-1.0)';
      PINUSE='OUT';
    'MXCK5#':
      PIN_NUMBER='(A41,0)';
      OUTPUT_LOAD='(1.0,-1.0)';
      PINUSE='OUT';
    'MXCK5':
      PIN_NUMBER='(A42,0)';
      OUTPUT_LOAD='(1.0,-1.0)';
      PINUSE='OUT';
    'MXCK6#':
      PIN_NUMBER='(A39,0)';
      OUTPUT_LOAD='(1.0,-1.0)';
      PINUSE='OUT';
    'MXCK6':
      PIN_NUMBER='(A40,0)';
      OUTPUT_LOAD='(1.0,-1.0)';
      PINUSE='OUT';
    'MXCK7#':
      PIN_NUMBER='(A37,0)';
      OUTPUT_LOAD='(1.0,-1.0)';
      PINUSE='OUT';
    'MXCK7':
      PIN_NUMBER='(A38,0)';
      OUTPUT_LOAD='(1.0,-1.0)';
      PINUSE='OUT';
    'MXCK8#':
      PIN_NUMBER='(A35,0)';
      OUTPUT_LOAD='(1.0,-1.0)';
      PINUSE='OUT';
    'MXCK8':
      PIN_NUMBER='(A36,0)';
      OUTPUT_LOAD='(1.0,-1.0)';
      PINUSE='OUT';
    'MXCK_SEL_100M#':
      PIN_NUMBER='(B38,0)';
      INPUT_LOAD='(-0.01,0.01)';
      PINUSE='IN';
    'NVGND':
      PIN_NUMBER='(B12,0)';
      PINUSE='POWER';
      NO_LOAD_CHECK='Both';
      NO_IO_CHECK='Both';
      NO_ASSERT_CHECK='TRUE';
      NO_DIR_CHECK='TRUE';
      ALLOW_CONNECT='TRUE';
    'OE0#':
      PIN_NUMBER='(B27,0)';
      INPUT_LOAD='(-0.01,0.01)';
      PINUSE='IN';
    'OE6#':
      PIN_NUMBER='(B14,0)';
      INPUT_LOAD='(-0.01,0.01)';
      PINUSE='IN';
    'PFT_IN#':
      PIN_NUMBER='(A9,0)';
      INPUT_LOAD='(-0.01,0.01)';
      PINUSE='IN';
    'PFT_IN':
      PIN_NUMBER='(A8,0)';
      INPUT_LOAD='(-0.01,0.01)';
      PINUSE='IN';
    'PFT_LOST#':
      PIN_NUMBER='(B4,0)';
      OUTPUT_LOAD='(1.0,-1.0)';
      PINUSE='OUT';
    'PFT_OUT#':
      PIN_NUMBER='(A7,0)';
      OUTPUT_LOAD='(1.0,-1.0)';
      PINUSE='OUT';
    'PFT_OUT':
      PIN_NUMBER='(A6,0)';
      OUTPUT_LOAD='(1.0,-1.0)';
      PINUSE='OUT';
    'PWRGD||PWRDN#':
      PIN_NUMBER='(A17,0)';
      INPUT_LOAD='(-0.01,0.01)';
      PINUSE='IN';
    'SBI_IN':
      PIN_NUMBER='(B43,0)';
      INPUT_LOAD='(-0.01,0.01)';
      PINUSE='IN';
    'SBI_OUT':
      PIN_NUMBER='(A53,0)';
      OUTPUT_LOAD='(1.0,-1.0)';
      PINUSE='OUT';
    'SCLK':
      PIN_NUMBER='(A10,0)';
      INPUT_LOAD='(-0.01,0.01)';
      PINUSE='IN';
    'SMBDATTA':
      PIN_NUMBER='(B8,0)';
      BIDIRECTIONAL='TRUE';
      INPUT_LOAD='(-0.01,0.01)';
      OUTPUT_LOAD='(1.0,-1.0)';
      PINUSE='BI';
    'SMB_ADR0_TRI':
      PIN_NUMBER='(A11,0)';
      INPUT_LOAD='(-0.01,0.01)';
      PINUSE='IN';
    'SS_EN_TRI':
      PIN_NUMBER='(A16,0)';
      INPUT_LOAD='(-0.01,0.01)';
      PINUSE='IN';
    'VDDA25M':
      PIN_NUMBER='(B1,0)';
      PINUSE='POWER';
      NO_LOAD_CHECK='Both';
      NO_IO_CHECK='Both';
      NO_ASSERT_CHECK='TRUE';
      NO_DIR_CHECK='TRUE';
      ALLOW_CONNECT='TRUE';
    'VDDA100M':
      PIN_NUMBER='(B17,0)';
      PINUSE='POWER';
      NO_LOAD_CHECK='Both';
      NO_IO_CHECK='Both';
      NO_ASSERT_CHECK='TRUE';
      NO_DIR_CHECK='TRUE';
      ALLOW_CONNECT='TRUE';
    'VDDPT':
      PIN_NUMBER='(B6,0)';
      PINUSE='POWER';
      NO_LOAD_CHECK='Both';
      NO_IO_CHECK='Both';
      NO_ASSERT_CHECK='TRUE';
      NO_DIR_CHECK='TRUE';
      ALLOW_CONNECT='TRUE';
    'VDDXTAL':
      PIN_NUMBER='(A12,0)';
      PINUSE='POWER';
      NO_LOAD_CHECK='Both';
      NO_IO_CHECK='Both';
      NO_ASSERT_CHECK='TRUE';
      NO_DIR_CHECK='TRUE';
      ALLOW_CONNECT='TRUE';
    'XIN_CLKIN':
      PIN_NUMBER='(A13,0)';
      INPUT_LOAD='(-0.01,0.01)';
      PINUSE='IN';
    'XOUT':
      PIN_NUMBER='(B11,0)';
      OUTPUT_LOAD='(1.0,-1.0)';
      PINUSE='OUT';
    'VDDMXCK_B29':
      PIN_NUMBER='(B29,0)';
      PINUSE='POWER';
      NO_LOAD_CHECK='Both';
      NO_IO_CHECK='Both';
      NO_ASSERT_CHECK='TRUE';
      NO_DIR_CHECK='TRUE';
      ALLOW_CONNECT='TRUE';
    'VDDMXCK_B32':
      PIN_NUMBER='(B32,0)';
      PINUSE='POWER';
      NO_LOAD_CHECK='Both';
      NO_IO_CHECK='Both';
      NO_ASSERT_CHECK='TRUE';
      NO_DIR_CHECK='TRUE';
      ALLOW_CONNECT='TRUE';
    'VDDMXCK_B35':
      PIN_NUMBER='(B35,0)';
      PINUSE='POWER';
      NO_LOAD_CHECK='Both';
      NO_IO_CHECK='Both';
      NO_ASSERT_CHECK='TRUE';
      NO_DIR_CHECK='TRUE';
      ALLOW_CONNECT='TRUE';
    'VDDMXCK_B40':
      PIN_NUMBER='(B40,0)';
      PINUSE='POWER';
      NO_LOAD_CHECK='Both';
      NO_IO_CHECK='Both';
      NO_ASSERT_CHECK='TRUE';
      NO_DIR_CHECK='TRUE';
      ALLOW_CONNECT='TRUE';
    'VDD100M_B21':
      PIN_NUMBER='(B21,0)';
      PINUSE='POWER';
      NO_LOAD_CHECK='Both';
      NO_IO_CHECK='Both';
      NO_ASSERT_CHECK='TRUE';
      NO_DIR_CHECK='TRUE';
      ALLOW_CONNECT='TRUE';
    'VDD100M_B23':
      PIN_NUMBER='(B23,0)';
      PINUSE='POWER';
      NO_LOAD_CHECK='Both';
      NO_IO_CHECK='Both';
      NO_ASSERT_CHECK='TRUE';
      NO_DIR_CHECK='TRUE';
      ALLOW_CONNECT='TRUE';
    'NC_B22':
      PIN_NUMBER='(0,B22)';
      OUTPUT_TYPE='(TS,TS)';
      INPUT_LOAD='(-0.01,0.01)';
      OUTPUT_LOAD='(1.0,-1.0)';
      PINUSE='TRI';
    'NC_B20':
      PIN_NUMBER='(0,B20)';
      OUTPUT_TYPE='(TS,TS)';
      INPUT_LOAD='(-0.01,0.01)';
      OUTPUT_LOAD='(1.0,-1.0)';
      PINUSE='TRI';
    'NC_B18':
      PIN_NUMBER='(0,B18)';
      OUTPUT_TYPE='(TS,TS)';
      INPUT_LOAD='(-0.01,0.01)';
      OUTPUT_LOAD='(1.0,-1.0)';
      PINUSE='TRI';
    'NC_B16':
      PIN_NUMBER='(0,B16)';
      OUTPUT_TYPE='(TS,TS)';
      INPUT_LOAD='(-0.01,0.01)';
      OUTPUT_LOAD='(1.0,-1.0)';
      PINUSE='TRI';
    'NC_B13':
      PIN_NUMBER='(0,B13)';
      OUTPUT_TYPE='(TS,TS)';
      INPUT_LOAD='(-0.01,0.01)';
      OUTPUT_LOAD='(1.0,-1.0)';
      PINUSE='TRI';
    'NC_B7':
      PIN_NUMBER='(0,B7)';
      OUTPUT_TYPE='(TS,TS)';
      INPUT_LOAD='(-0.01,0.01)';
      OUTPUT_LOAD='(1.0,-1.0)';
      PINUSE='TRI';
    'NC_B5':
      PIN_NUMBER='(0,B5)';
      OUTPUT_TYPE='(TS,TS)';
      INPUT_LOAD='(-0.01,0.01)';
      OUTPUT_LOAD='(1.0,-1.0)';
      PINUSE='TRI';
    'NC_B3':
      PIN_NUMBER='(0,B3)';
      OUTPUT_TYPE='(TS,TS)';
      INPUT_LOAD='(-0.01,0.01)';
      OUTPUT_LOAD='(1.0,-1.0)';
      PINUSE='TRI';
    'NC_B2':
      PIN_NUMBER='(0,B2)';
      OUTPUT_TYPE='(TS,TS)';
      INPUT_LOAD='(-0.01,0.01)';
      OUTPUT_LOAD='(1.0,-1.0)';
      PINUSE='TRI';
    'NC_A15':
      PIN_NUMBER='(0,A15)';
      OUTPUT_TYPE='(TS,TS)';
      INPUT_LOAD='(-0.01,0.01)';
      OUTPUT_LOAD='(1.0,-1.0)';
      PINUSE='TRI';
    'NC_B24':
      PIN_NUMBER='(0,B24)';
      OUTPUT_TYPE='(TS,TS)';
      INPUT_LOAD='(-0.01,0.01)';
      OUTPUT_LOAD='(1.0,-1.0)';
      PINUSE='TRI';
    'NC_B25':
      PIN_NUMBER='(0,B25)';
      OUTPUT_TYPE='(TS,TS)';
      INPUT_LOAD='(-0.01,0.01)';
      OUTPUT_LOAD='(1.0,-1.0)';
      PINUSE='TRI';
    'NC_B26':
      PIN_NUMBER='(0,B26)';
      OUTPUT_TYPE='(TS,TS)';
      INPUT_LOAD='(-0.01,0.01)';
      OUTPUT_LOAD='(1.0,-1.0)';
      PINUSE='TRI';
    'NC_B28':
      PIN_NUMBER='(0,B28)';
      OUTPUT_TYPE='(TS,TS)';
      INPUT_LOAD='(-0.01,0.01)';
      OUTPUT_LOAD='(1.0,-1.0)';
      PINUSE='TRI';
    'NC_B30':
      PIN_NUMBER='(0,B30)';
      OUTPUT_TYPE='(TS,TS)';
      INPUT_LOAD='(-0.01,0.01)';
      OUTPUT_LOAD='(1.0,-1.0)';
      PINUSE='TRI';
    'NC_B31':
      PIN_NUMBER='(0,B31)';
      OUTPUT_TYPE='(TS,TS)';
      INPUT_LOAD='(-0.01,0.01)';
      OUTPUT_LOAD='(1.0,-1.0)';
      PINUSE='TRI';
    'NC_B33':
      PIN_NUMBER='(0,B33)';
      OUTPUT_TYPE='(TS,TS)';
      INPUT_LOAD='(-0.01,0.01)';
      OUTPUT_LOAD='(1.0,-1.0)';
      PINUSE='TRI';
    'NC_B34':
      PIN_NUMBER='(0,B34)';
      OUTPUT_TYPE='(TS,TS)';
      INPUT_LOAD='(-0.01,0.01)';
      OUTPUT_LOAD='(1.0,-1.0)';
      PINUSE='TRI';
    'NC_B36':
      PIN_NUMBER='(0,B36)';
      OUTPUT_TYPE='(TS,TS)';
      INPUT_LOAD='(-0.01,0.01)';
      OUTPUT_LOAD='(1.0,-1.0)';
      PINUSE='TRI';
    'NC_B37':
      PIN_NUMBER='(0,B37)';
      OUTPUT_TYPE='(TS,TS)';
      INPUT_LOAD='(-0.01,0.01)';
      OUTPUT_LOAD='(1.0,-1.0)';
      PINUSE='TRI';
    'NC_B39':
      PIN_NUMBER='(0,B39)';
      OUTPUT_TYPE='(TS,TS)';
      INPUT_LOAD='(-0.01,0.01)';
      OUTPUT_LOAD='(1.0,-1.0)';
      PINUSE='TRI';
    'NC_B41':
      PIN_NUMBER='(0,B41)';
      OUTPUT_TYPE='(TS,TS)';
      INPUT_LOAD='(-0.01,0.01)';
      OUTPUT_LOAD='(1.0,-1.0)';
      PINUSE='TRI';
    'NC_B44':
      PIN_NUMBER='(0,B44)';
      OUTPUT_TYPE='(TS,TS)';
      INPUT_LOAD='(-0.01,0.01)';
      OUTPUT_LOAD='(1.0,-1.0)';
      PINUSE='TRI';
  end_pin;
  body
      PART_NAME='9SQ440NQQI8';
      BODY_NAME='9SQ440NQQI8';
      PHYS_DES_PREFIX='U';
      CLASS='IC';
      STANDARD='';
      LIFECYCLE='';
      JEDEC_TYPE='QFN100_TH_0-5_8X8';
      DESCRIPTION='IC OTHER(100P)9SQ440NQQI8(QFN)';
      MANUFTR='IDT';
      MANUF_PN='9SQ440NQQI8';
      RD_CMPLS_LVL='EP(V1)';
      CMPLS_LVL='';
      FROM_PJ='S6X-SANDY';
      DIP_SMD='';
      DATA='IDT_9SQ440NQQI8.pdf';
      EE_CHECK_LIST='';
      FP_ECN='';
      PSL='';
      CREATOR='';
      STATUS='';
      MSD='NA';
      ESD_CDM='N/A';
      ESD_HBM='N/A';
      ESD_MM='N/A';
      PIN_LENGTH_SHORT_PIN='0 MILS';
      PIN_LENGTH_LONG_PIN='0 MILS';
      CREATEDAY='20191205';
      PARENT_PART_TYPE='9SQ440NQQI8';
      PARENT_PPT='9SQ440NQQI8';
      PARENT_PPT_PART='9SQ440NQQI8-9SQ440NQQI8,SMLF,IC,AJ004400000';
  end_body;
end_primitive;
primitive '9ZXL0451EKILFT-9ZXL0451EKILFT,A';
  pin
    'DIF_IN':
      PIN_NUMBER='(3)';
      INPUT_LOAD='(-0.01,0.01)';
      PINUSE='IN';
    'DIF_IN#':
      PIN_NUMBER='(4)';
      INPUT_LOAD='(-0.01,0.01)';
      PINUSE='IN';
    'VDDR':
      PIN_NUMBER='(2)';
      PINUSE='POWER';
      NO_LOAD_CHECK='Both';
      NO_IO_CHECK='Both';
      NO_ASSERT_CHECK='TRUE';
      NO_DIR_CHECK='TRUE';
      ALLOW_CONNECT='TRUE';
    'VDD3':
      PIN_NUMBER='(25)';
      PINUSE='POWER';
      NO_LOAD_CHECK='Both';
      NO_IO_CHECK='Both';
      NO_ASSERT_CHECK='TRUE';
      NO_DIR_CHECK='TRUE';
      ALLOW_CONNECT='TRUE';
    'VDD4':
      PIN_NUMBER='(29)';
      PINUSE='POWER';
      NO_LOAD_CHECK='Both';
      NO_IO_CHECK='Both';
      NO_ASSERT_CHECK='TRUE';
      NO_DIR_CHECK='TRUE';
      ALLOW_CONNECT='TRUE';
    'FBOUT_NC':
      PIN_NUMBER='(9)';
      OUTPUT_LOAD='(1.0,-1.0)';
      PINUSE='OUT';
    'VOE0#':
      PIN_NUMBER='(15)';
      INPUT_LOAD='(-0.01,0.01)';
      PINUSE='IN';
    'VOE3#':
      PIN_NUMBER='(26)';
      INPUT_LOAD='(-0.01,0.01)';
      PINUSE='IN';
    'SMBDAT':
      PIN_NUMBER='(6)';
      BIDIRECTIONAL='TRUE';
      INPUT_LOAD='(-0.01,0.01)';
      OUTPUT_LOAD='(1.0,-1.0)';
      PINUSE='BI';
    'NC1':
      PIN_NUMBER='(11)';
      OUTPUT_TYPE='(TS,TS)';
      INPUT_LOAD='(-0.01,0.01)';
      OUTPUT_LOAD='(1.0,-1.0)';
      PINUSE='TRI';
    'FBOUT_NC#':
      PIN_NUMBER='(8)';
      OUTPUT_LOAD='(1.0,-1.0)';
      PINUSE='OUT';
    'SMBCLK':
      PIN_NUMBER='(7)';
      INPUT_LOAD='(-0.01,0.01)';
      PINUSE='IN';
    'VDD2':
      PIN_NUMBER='(21)';
      PINUSE='POWER';
      NO_LOAD_CHECK='Both';
      NO_IO_CHECK='Both';
      NO_ASSERT_CHECK='TRUE';
      NO_DIR_CHECK='TRUE';
      ALLOW_CONNECT='TRUE';
    '^CKPWRGD_PD#':
      PIN_NUMBER='(1)';
      INPUT_LOAD='(-0.01,0.01)';
      PINUSE='IN';
    'DIF0#':
      PIN_NUMBER='(14)';
      OUTPUT_LOAD='(1.0,-1.0)';
      PINUSE='OUT';
    'DIF0':
      PIN_NUMBER='(13)';
      OUTPUT_LOAD='(1.0,-1.0)';
      PINUSE='OUT';
    'VOE1#':
      PIN_NUMBER='(18)';
      INPUT_LOAD='(-0.01,0.01)';
      PINUSE='IN';
    'DIF1#':
      PIN_NUMBER='(20)';
      OUTPUT_LOAD='(1.0,-1.0)';
      PINUSE='OUT';
    'DIF2':
      PIN_NUMBER='(22)';
      OUTPUT_LOAD='(1.0,-1.0)';
      PINUSE='OUT';
    'VOE2#':
      PIN_NUMBER='(24)';
      INPUT_LOAD='(-0.01,0.01)';
      PINUSE='IN';
    'DIF2#':
      PIN_NUMBER='(23)';
      OUTPUT_LOAD='(1.0,-1.0)';
      PINUSE='OUT';
    'DIF3#':
      PIN_NUMBER='(28)';
      OUTPUT_LOAD='(1.0,-1.0)';
      PINUSE='OUT';
    'NC0':
      PIN_NUMBER='(10)';
      OUTPUT_TYPE='(TS,TS)';
      INPUT_LOAD='(-0.01,0.01)';
      OUTPUT_LOAD='(1.0,-1.0)';
      PINUSE='TRI';
    'VDDA':
      PIN_NUMBER='(31)';
      PINUSE='POWER';
      NO_LOAD_CHECK='Both';
      NO_IO_CHECK='Both';
      NO_ASSERT_CHECK='TRUE';
      NO_DIR_CHECK='TRUE';
      ALLOW_CONNECT='TRUE';
    'VDD1':
      PIN_NUMBER='(16)';
      PINUSE='POWER';
      NO_LOAD_CHECK='Both';
      NO_IO_CHECK='Both';
      NO_ASSERT_CHECK='TRUE';
      NO_DIR_CHECK='TRUE';
      ALLOW_CONNECT='TRUE';
    '^HIBW_BYPM_LOBW#':
      PIN_NUMBER='(32)';
      INPUT_LOAD='(-0.01,0.01)';
      PINUSE='IN';
    'EPAD_GND':
      PIN_NUMBER='(33)';
      PINUSE='POWER';
      NO_LOAD_CHECK='Both';
      NO_IO_CHECK='Both';
      NO_ASSERT_CHECK='TRUE';
      NO_DIR_CHECK='TRUE';
      ALLOW_CONNECT='TRUE';
    'DIF1':
      PIN_NUMBER='(19)';
      OUTPUT_LOAD='(1.0,-1.0)';
      PINUSE='OUT';
    'DIF3':
      PIN_NUMBER='(27)';
      OUTPUT_LOAD='(1.0,-1.0)';
      PINUSE='OUT';
    'VDD0':
      PIN_NUMBER='(12)';
      PINUSE='POWER';
      NO_LOAD_CHECK='Both';
      NO_IO_CHECK='Both';
      NO_ASSERT_CHECK='TRUE';
      NO_DIR_CHECK='TRUE';
      ALLOW_CONNECT='TRUE';
    'NC3':
      PIN_NUMBER='(30)';
      OUTPUT_TYPE='(TS,TS)';
      INPUT_LOAD='(-0.01,0.01)';
      OUTPUT_LOAD='(1.0,-1.0)';
      PINUSE='TRI';
    'NC2':
      PIN_NUMBER='(17)';
      OUTPUT_TYPE='(TS,TS)';
      INPUT_LOAD='(-0.01,0.01)';
      OUTPUT_LOAD='(1.0,-1.0)';
      PINUSE='TRI';
    'VSADR0_TRI':
      PIN_NUMBER='(5)';
      INPUT_LOAD='(-0.01,0.01)';
      PINUSE='IN';
  end_pin;
  body
      PART_NAME='9ZXL0451EKILFT';
      BODY_NAME='9ZXL0451EKILFT';
      PHYS_DES_PREFIX='U';
      CLASS='IC';
      STANDARD='';
      LIFECYCLE='';
      JEDEC_TYPE='VFQFPN32_TH_0-5_5X5XD';
      DESCRIPTION='IC OTHER(32P) 9ZXL0451EKILFT(VFQFPN)';
      MANUFTR='IDT';
      MANUF_PN='9ZXL0451EKILFT';
      RD_CMPLS_LVL='EP(V1)';
      CMPLS_LVL='EP(V1)';
      FROM_PJ='S69-JEFF';
      DIP_SMD='';
      DATA='IDT_9ZXL0451EKILFT.pdf';
      EE_CHECK_LIST='';
      FP_ECN='';
      PSL='';
      CREATOR='';
      STATUS='';
      MSD='NA';
      ESD_CDM='NA';
      ESD_HBM='NA';
      ESD_MM='NA';
      PIN_LENGTH_SHORT_PIN='0 MILS';
      PIN_LENGTH_LONG_PIN='0 MILS';
      CREATEDAY='20190416';
      PARENT_PART_TYPE='9ZXL0451EKILFT';
      PARENT_PPT='9ZXL0451EKILFT';
      PARENT_PPT_PART='9ZXL0451EKILFT-9ZXL0451EKILFT,SMLF,IC,AL000451003';
  end_body;
end_primitive;
primitive 'ADC128D818CIMTXNOPB-ADC128D818A';
  pin
    'VREF':
      PIN_NUMBER='(1)';
      INPUT_LOAD='(-0.01,0.01)';
      PINUSE='IN';
    'V+':
      PIN_NUMBER='(5)';
      PINUSE='POWER';
      NO_LOAD_CHECK='Both';
      NO_IO_CHECK='Both';
      NO_ASSERT_CHECK='TRUE';
      NO_DIR_CHECK='TRUE';
      ALLOW_CONNECT='TRUE';
    'A0':
      PIN_NUMBER='(7)';
      INPUT_LOAD='(-0.01,0.01)';
      PINUSE='IN';
    'A1':
      PIN_NUMBER='(8)';
      INPUT_LOAD='(-0.01,0.01)';
      PINUSE='IN';
    'IN7':
      PIN_NUMBER='(9)';
      INPUT_LOAD='(-0.01,0.01)';
      PINUSE='IN';
    'IN6':
      PIN_NUMBER='(10)';
      INPUT_LOAD='(-0.01,0.01)';
      PINUSE='IN';
    'IN5':
      PIN_NUMBER='(11)';
      INPUT_LOAD='(-0.01,0.01)';
      PINUSE='IN';
    'IN4':
      PIN_NUMBER='(12)';
      INPUT_LOAD='(-0.01,0.01)';
      PINUSE='IN';
    'IN3':
      PIN_NUMBER='(13)';
      INPUT_LOAD='(-0.01,0.01)';
      PINUSE='IN';
    'IN2':
      PIN_NUMBER='(14)';
      INPUT_LOAD='(-0.01,0.01)';
      PINUSE='IN';
    'IN1':
      PIN_NUMBER='(15)';
      INPUT_LOAD='(-0.01,0.01)';
      PINUSE='IN';
    'IN0':
      PIN_NUMBER='(16)';
      INPUT_LOAD='(-0.01,0.01)';
      PINUSE='IN';
    'SDA':
      PIN_NUMBER='(2)';
      BIDIRECTIONAL='TRUE';
      INPUT_LOAD='(-0.01,0.01)';
      OUTPUT_LOAD='(1.0,-1.0)';
      PINUSE='BI';
    'SCL':
      PIN_NUMBER='(3)';
      INPUT_LOAD='(-0.01,0.01)';
      PINUSE='IN';
    'GND':
      PIN_NUMBER='(4)';
      PINUSE='POWER';
      NO_LOAD_CHECK='Both';
      NO_IO_CHECK='Both';
      NO_ASSERT_CHECK='TRUE';
      NO_DIR_CHECK='TRUE';
      ALLOW_CONNECT='TRUE';
    'INT#':
      PIN_NUMBER='(6)';
      OUTPUT_LOAD='(1.0,-1.0)';
      PINUSE='OUT';
  end_pin;
  body
      PART_NAME='ADC128D818CIMTXNOPB';
      BODY_NAME='ADC128D818CIMTXNOPB';
      PHYS_DES_PREFIX='U';
      CLASS='IC';
      STANDARD='';
      LIFECYCLE='';
      JEDEC_TYPE='TSSOP16XC';
      DESCRIPTION='IC OTHER(16P)ADC128D818CIMTX/NOPB(TSSOP)';
      MANUFTR='TIC';
      MANUF_PN='ADC128D818CIMTX/NOPB';
      RD_CMPLS_LVL='EP(V1)';
      CMPLS_LVL='';
      FROM_PJ='S1U-OWEN';
      DIP_SMD='';
      DATA='TIC_ADC128D818CIMTXNOPB.pdf';
      EE_CHECK_LIST='';
      FP_ECN='';
      PSL='';
      CREATOR='';
      STATUS='';
      CREATEDAY='20150604';
      PARENT_PART_TYPE='ADC128D818CIMTXNOPB';
      PARENT_PPT='ADC128D818CIMTXNOPB';
      PARENT_PPT_PART='ADC128D818CIMTXNOPB-ADC128D818CIMTX/NOPB,SMLF,IC,AL000128K00';
  end_body;
end_primitive;
primitive 'ADM1086AKSZREEL7-ADM1086AKSZ-RA';
  pin
    'VCC':
      PIN_NUMBER='(6)';
      PINUSE='POWER';
      NO_LOAD_CHECK='Both';
      NO_IO_CHECK='Both';
      NO_ASSERT_CHECK='TRUE';
      NO_DIR_CHECK='TRUE';
      ALLOW_CONNECT='TRUE';
    'VIN':
      PIN_NUMBER='(3)';
      PINUSE='POWER';
      NO_LOAD_CHECK='Both';
      NO_IO_CHECK='Both';
      NO_ASSERT_CHECK='TRUE';
      NO_DIR_CHECK='TRUE';
      ALLOW_CONNECT='TRUE';
    'ENIN':
      PIN_NUMBER='(1)';
      INPUT_LOAD='(-0.01,0.01)';
      PINUSE='IN';
    'ENOUT':
      PIN_NUMBER='(4)';
      OUTPUT_LOAD='(1.0,-1.0)';
      PINUSE='OUT';
    'CEXT':
      PIN_NUMBER='(5)';
      BIDIRECTIONAL='TRUE';
      INPUT_LOAD='(-0.01,0.01)';
      OUTPUT_LOAD='(1.0,-1.0)';
      PINUSE='BI';
    'GND':
      PIN_NUMBER='(2)';
      PINUSE='POWER';
      NO_LOAD_CHECK='Both';
      NO_IO_CHECK='Both';
      NO_ASSERT_CHECK='TRUE';
      NO_DIR_CHECK='TRUE';
      ALLOW_CONNECT='TRUE';
  end_pin;
  body
      PART_NAME='ADM1086AKSZREEL7';
      BODY_NAME='ADM1086AKSZREEL7';
      PHYS_DES_PREFIX='U';
      CLASS='IC';
      STANDARD='End of Design';
      LIFECYCLE='Comp-Approve';
      JEDEC_TYPE='SC70-6_0-65_2X1-25XA';
      DESCRIPTION='IC OTHER(6P)ADM1086AKSZ-REEL7(SC70)';
      MANUFTR='ADV';
      MANUF_PN='ADM1086AKSZ-REEL7';
      RD_CMPLS_LVL='EP(V1)';
      CMPLS_LVL='';
      FROM_PJ='S9S-CHRIS';
      DIP_SMD='';
      DATA='ADV_ADM1086AKSZ-REEL7.pdf';
      EE_CHECK_LIST='';
      FP_ECN='ADM1086AKSZ-REEL7.msg';
      PSL='';
      CREATOR='';
      STATUS='';
      MSD='NA';
      ESD_CDM='NA';
      ESD_HBM='NA';
      ESD_MM='NA';
      PIN_LENGTH_SHORT_PIN='0 MILS';
      PIN_LENGTH_LONG_PIN='0 MILS';
      CREATEDAY='20200525';
      PARENT_PART_TYPE='ADM1086AKSZREEL7';
      PARENT_PPT='ADM1086AKSZREEL7';
      PARENT_PPT_PART='ADM1086AKSZREEL7-ADM1086AKSZ-REEL7,SMLF,IC,AL001086001';
  end_body;
end_primitive;
primitive 'AP331AWG7-AP331AWG-7,SMLF,EMPTA';
  pin
    'IN+':
      PIN_NUMBER='(3)';
      INPUT_LOAD='(-0.01,0.01)';
      PINUSE='IN';
    'IN-':
      PIN_NUMBER='(1)';
      INPUT_LOAD='(-0.01,0.01)';
      PINUSE='IN';
    'OUTPUT':
      PIN_NUMBER='(4)';
      OUTPUT_LOAD='(1.0,-1.0)';
      PINUSE='OUT';
    'VCC':
      PIN_NUMBER='(5)';
      PINUSE='POWER';
      NO_LOAD_CHECK='Both';
      NO_IO_CHECK='Both';
      NO_ASSERT_CHECK='TRUE';
      NO_DIR_CHECK='TRUE';
      ALLOW_CONNECT='TRUE';
    'GND':
      PIN_NUMBER='(2)';
      PINUSE='POWER';
      NO_LOAD_CHECK='Both';
      NO_IO_CHECK='Both';
      NO_ASSERT_CHECK='TRUE';
      NO_DIR_CHECK='TRUE';
      ALLOW_CONNECT='TRUE';
  end_pin;
  body
      PART_NAME='AP331AWG7';
      BODY_NAME='AP331AWG7';
      PHYS_DES_PREFIX='U';
      CLASS='IC';
      STANDARD='';
      LIFECYCLE='';
      JEDEC_TYPE='SOT25';
      DESCRIPTION='IC OTHER(5P) AP331AWG-7 (SOT25)';
      MANUFTR='DDS';
      MANUF_PN='AP331AWG-7';
      RD_CMPLS_LVL='EP(V1)';
      CMPLS_LVL='EP(V1)';
      FROM_PJ='T6G-ALLEN';
      DIP_SMD='';
      DATA='DDS_AP331AWG-7.pdf';
      EE_CHECK_LIST='';
      FP_ECN='';
      PSL='';
      CREATOR='';
      STATUS='';
      MSD='';
      ESD_CDM='';
      ESD_HBM='';
      ESD_MM='';
      PIN_LENGTH_SHORT_PIN='0 MILS';
      PIN_LENGTH_LONG_PIN='0 MILS';
      CREATEDAY='20210812';
      PARENT_PART_TYPE='AP331AWG7';
      PARENT_PPT='AP331AWG7';
      PARENT_PPT_PART='AP331AWG7-AP331AWG-7,SMLF,EMPTY,AL000331011';
  end_body;
end_primitive;
primitive 'APX80929SAG7-APX809-29SAG-7,SMA';
  pin
    'VCC':
      PIN_NUMBER='(3)';
      PINUSE='POWER';
      NO_LOAD_CHECK='Both';
      NO_IO_CHECK='Both';
      NO_ASSERT_CHECK='TRUE';
      NO_DIR_CHECK='TRUE';
      ALLOW_CONNECT='TRUE';
    'RESET_L':
      PIN_NUMBER='(2)';
      OUTPUT_LOAD='(1.0,-1.0)';
      PINUSE='OUT';
    'GND':
      PIN_NUMBER='(1)';
      PINUSE='POWER';
      NO_LOAD_CHECK='Both';
      NO_IO_CHECK='Both';
      NO_ASSERT_CHECK='TRUE';
      NO_DIR_CHECK='TRUE';
      ALLOW_CONNECT='TRUE';
  end_pin;
  body
      PART_NAME='APX80929SAG7';
      BODY_NAME='APX80929SAG7';
      PHYS_DES_PREFIX='U';
      CLASS='IC';
      STANDARD='';
      LIFECYCLE='';
      JEDEC_TYPE='SOT23_123XI';
      DESCRIPTION='IC OTHER(3P) APX809-29SAG-7(SOT23)';
      MANUFTR='DDS';
      MANUF_PN='APX809-29SAG-7';
      RD_CMPLS_LVL='EP(V1)';
      CMPLS_LVL='EP(V1)';
      FROM_PJ='S2VA-JOSEPH';
      DIP_SMD='';
      DATA='DDS_APX809-810_rev4.pdf';
      EE_CHECK_LIST='';
      FP_ECN='';
      PSL='';
      CREATOR='';
      STATUS='';
      CREATEDAY='20130717';
      PARENT_PART_TYPE='APX80929SAG7';
      PARENT_PPT='APX80929SAG7';
      PARENT_PPT_PART='APX80929SAG7-APX809-29SAG-7,SMLF,IC,AL080929000';
  end_body;
end_primitive;
primitive 'BAS70057F-BAS70-05-7-F,SMLF,ICA';
  pin
    'A':
      PIN_NUMBER='(2)';
      INPUT_LOAD='(-0.01,0.01)';
      PINUSE='IN';
    'B':
      PIN_NUMBER='(1)';
      INPUT_LOAD='(-0.01,0.01)';
      PINUSE='IN';
    'C':
      PIN_NUMBER='(3)';
      BIDIRECTIONAL='TRUE';
      INPUT_LOAD='(-0.01,0.01)';
      OUTPUT_LOAD='(1.0,-1.0)';
      PINUSE='BI';
  end_pin;
  body
      PART_NAME='BAS70057F';
      BODY_NAME='BAS70057F';
      PHYS_DES_PREFIX='U';
      CLASS='IC';
      STANDARD='End of Design';
      LIFECYCLE='Comp-Approve';
      JEDEC_TYPE='SOT23_123XB';
      DESCRIPTION='DIODE SMD BAS70-05-7-F(70V,SHTKY,SOT-23)';
      MANUFTR='DDS';
      MANUF_PN='BAS70-05-7-F';
      RD_CMPLS_LVL='EP(V1)';
      CMPLS_LVL='EP(V1)';
      DIP_SMD='';
      FP_ECN='';
      FROM_PJ='S1D-OZ';
      DATA='DDS_BAS70-04-05-06.pdf';
      EE_CHECK_LIST='';
      STATUS='';
      PSL='';
      PREFERENCE='';
      CREATOR='';
      CREATEDAY='20121220';
      PARENT_PART_TYPE='BAS70057F';
      PARENT_PPT='BAS70057F';
      PARENT_PPT_PART='BAS70057F-BAS70-05-7-F,SMLF,IC,BC0BAS70Z01';
  end_body;
end_primitive;
primitive 'BAT547F-BAT547F,SMLF,IC,BC0BATA';
  pin
    '1':
      PIN_NUMBER='(1)';
      BIDIRECTIONAL='TRUE';
      INPUT_LOAD='(-0.01,0.01)';
      OUTPUT_LOAD='(1.0,-1.0)';
      PINUSE='BI';
    '3':
      PIN_NUMBER='(3)';
      BIDIRECTIONAL='TRUE';
      INPUT_LOAD='(-0.01,0.01)';
      OUTPUT_LOAD='(1.0,-1.0)';
      PINUSE='BI';
  end_pin;
  body
      PART_NAME='BAT547F';
      BODY_NAME='BAT547F';
      PHYS_DES_PREFIX='D';
      CLASS='IC';
      NC_PINS='(2)';
      STANDARD='';
      LIFECYCLE='';
      JEDEC_TYPE='SOT23_123XB';
      DESCRIPTION='DIODE BAT54-7-F(30V.200MA SCHOTTKY)';
      MANUFTR='DDS';
      MANUF_PN='BAT54-7-F';
      RD_CMPLS_LVL='';
      CMPLS_LVL='EU';
      DIP_SMD='';
      FP_ECN='';
      FROM_PJ='S50-STEVE';
      DATA='DDS_BAT54-7-F(A.C.S-7-F).pdf';
      EE_CHECK_LIST='';
      STATUS='';
      PSL='';
      PREFERENCE='';
      CREATOR='';
      CREATEDAY='20130912';
      PARENT_PART_TYPE='BAT547F';
      PARENT_PPT='BAT547F';
      PARENT_PPT_PART='BAT547F-BAT547F,SMLF,IC,BC0BAT54Z53';
  end_body;
end_primitive;
primitive 'BC847BPN-BC847BPN,SMLF,IC,BA00A';
  pin
    'B1':
      PIN_NUMBER='(2,0)';
      INPUT_LOAD='(-0.01,0.01)';
      PINUSE='IN';
    'C1':
      PIN_NUMBER='(6,0)';
      BIDIRECTIONAL='TRUE';
      INPUT_LOAD='(-0.01,0.01)';
      OUTPUT_LOAD='(1.0,-1.0)';
      PINUSE='BI';
    'E1':
      PIN_NUMBER='(1,0)';
      BIDIRECTIONAL='TRUE';
      INPUT_LOAD='(-0.01,0.01)';
      OUTPUT_LOAD='(1.0,-1.0)';
      PINUSE='BI';
    'B2':
      PIN_NUMBER='(0,5)';
      INPUT_LOAD='(-0.01,0.01)';
      PINUSE='IN';
    'C2':
      PIN_NUMBER='(0,3)';
      BIDIRECTIONAL='TRUE';
      INPUT_LOAD='(-0.01,0.01)';
      OUTPUT_LOAD='(1.0,-1.0)';
      PINUSE='BI';
    'E2':
      PIN_NUMBER='(0,4)';
      BIDIRECTIONAL='TRUE';
      INPUT_LOAD='(-0.01,0.01)';
      OUTPUT_LOAD='(1.0,-1.0)';
      PINUSE='BI';
  end_pin;
  body
      PART_NAME='BC847BPN';
      BODY_NAME='BC847BPN';
      PHYS_DES_PREFIX='Q';
      CLASS='IC';
      STANDARD='';
      LIFECYCLE='';
      JEDEC_TYPE='SOT363XB';
      DESCRIPTION='TRANS SMD BC847BPN(45V,0.1A,0.3W)';
      MANUFTR='NXE';
      MANUF_PN='BC847BPN';
      RD_CMPLS_LVL='EP(V1)';
      CMPLS_LVL='';
      DIP_SMD='';
      FP_ECN='';
      FROM_PJ='F0T-IVES';
      DATA='NXE_BC847BPN.pdf';
      EE_CHECK_LIST='';
      STATUS='';
      PSL='';
      PREFERENCE='';
      CREATOR='';
      CREATEDAY='20221208';
      ESD_CDM='';
      ESD_HBM='';
      ESD_MM='';
      MSD='';
      PIN_LENGTH_LONG_PIN='0 MILS';
      PIN_LENGTH_SHORT_PIN='0 MILS';
      PARENT_PART_TYPE='BC847BPN';
      PARENT_PPT='BC847BPN';
      PARENT_PPT_PART='BC847BPN-BC847BPN,SMLF,IC,BA008470026';
  end_body;
end_primitive;
primitive 'CONN112_10137002101LF-CONN112_A';
  pin
    'A8':
      PIN_NUMBER='(A8,0)';
      BIDIRECTIONAL='TRUE';
      INPUT_LOAD='(-0.01,0.01)';
      OUTPUT_LOAD='(1.0,-1.0)';
      PINUSE='BI';
    'A7':
      PIN_NUMBER='(A7,0)';
      BIDIRECTIONAL='TRUE';
      INPUT_LOAD='(-0.01,0.01)';
      OUTPUT_LOAD='(1.0,-1.0)';
      PINUSE='BI';
    'A6':
      PIN_NUMBER='(A6,0)';
      BIDIRECTIONAL='TRUE';
      INPUT_LOAD='(-0.01,0.01)';
      OUTPUT_LOAD='(1.0,-1.0)';
      PINUSE='BI';
    'A5':
      PIN_NUMBER='(A5,0)';
      BIDIRECTIONAL='TRUE';
      INPUT_LOAD='(-0.01,0.01)';
      OUTPUT_LOAD='(1.0,-1.0)';
      PINUSE='BI';
    'B8':
      PIN_NUMBER='(B8,0)';
      BIDIRECTIONAL='TRUE';
      INPUT_LOAD='(-0.01,0.01)';
      OUTPUT_LOAD='(1.0,-1.0)';
      PINUSE='BI';
    'B7':
      PIN_NUMBER='(B7,0)';
      BIDIRECTIONAL='TRUE';
      INPUT_LOAD='(-0.01,0.01)';
      OUTPUT_LOAD='(1.0,-1.0)';
      PINUSE='BI';
    'B6':
      PIN_NUMBER='(B6,0)';
      BIDIRECTIONAL='TRUE';
      INPUT_LOAD='(-0.01,0.01)';
      OUTPUT_LOAD='(1.0,-1.0)';
      PINUSE='BI';
    'B5':
      PIN_NUMBER='(B5,0)';
      BIDIRECTIONAL='TRUE';
      INPUT_LOAD='(-0.01,0.01)';
      OUTPUT_LOAD='(1.0,-1.0)';
      PINUSE='BI';
    'C8':
      PIN_NUMBER='(C8,0)';
      BIDIRECTIONAL='TRUE';
      INPUT_LOAD='(-0.01,0.01)';
      OUTPUT_LOAD='(1.0,-1.0)';
      PINUSE='BI';
    'C7':
      PIN_NUMBER='(C7,0)';
      BIDIRECTIONAL='TRUE';
      INPUT_LOAD='(-0.01,0.01)';
      OUTPUT_LOAD='(1.0,-1.0)';
      PINUSE='BI';
    'C6':
      PIN_NUMBER='(C6,0)';
      BIDIRECTIONAL='TRUE';
      INPUT_LOAD='(-0.01,0.01)';
      OUTPUT_LOAD='(1.0,-1.0)';
      PINUSE='BI';
    'C5':
      PIN_NUMBER='(C5,0)';
      BIDIRECTIONAL='TRUE';
      INPUT_LOAD='(-0.01,0.01)';
      OUTPUT_LOAD='(1.0,-1.0)';
      PINUSE='BI';
    'D8':
      PIN_NUMBER='(D8,0)';
      BIDIRECTIONAL='TRUE';
      INPUT_LOAD='(-0.01,0.01)';
      OUTPUT_LOAD='(1.0,-1.0)';
      PINUSE='BI';
    'D7':
      PIN_NUMBER='(D7,0)';
      BIDIRECTIONAL='TRUE';
      INPUT_LOAD='(-0.01,0.01)';
      OUTPUT_LOAD='(1.0,-1.0)';
      PINUSE='BI';
    'D6':
      PIN_NUMBER='(D6,0)';
      BIDIRECTIONAL='TRUE';
      INPUT_LOAD='(-0.01,0.01)';
      OUTPUT_LOAD='(1.0,-1.0)';
      PINUSE='BI';
    'D5':
      PIN_NUMBER='(D5,0)';
      BIDIRECTIONAL='TRUE';
      INPUT_LOAD='(-0.01,0.01)';
      OUTPUT_LOAD='(1.0,-1.0)';
      PINUSE='BI';
    'E8':
      PIN_NUMBER='(E8,0)';
      BIDIRECTIONAL='TRUE';
      INPUT_LOAD='(-0.01,0.01)';
      OUTPUT_LOAD='(1.0,-1.0)';
      PINUSE='BI';
    'E7':
      PIN_NUMBER='(E7,0)';
      BIDIRECTIONAL='TRUE';
      INPUT_LOAD='(-0.01,0.01)';
      OUTPUT_LOAD='(1.0,-1.0)';
      PINUSE='BI';
    'E6':
      PIN_NUMBER='(E6,0)';
      BIDIRECTIONAL='TRUE';
      INPUT_LOAD='(-0.01,0.01)';
      OUTPUT_LOAD='(1.0,-1.0)';
      PINUSE='BI';
    'E5':
      PIN_NUMBER='(E5,0)';
      BIDIRECTIONAL='TRUE';
      INPUT_LOAD='(-0.01,0.01)';
      OUTPUT_LOAD='(1.0,-1.0)';
      PINUSE='BI';
    'F8':
      PIN_NUMBER='(F8,0)';
      BIDIRECTIONAL='TRUE';
      INPUT_LOAD='(-0.01,0.01)';
      OUTPUT_LOAD='(1.0,-1.0)';
      PINUSE='BI';
    'F7':
      PIN_NUMBER='(F7,0)';
      BIDIRECTIONAL='TRUE';
      INPUT_LOAD='(-0.01,0.01)';
      OUTPUT_LOAD='(1.0,-1.0)';
      PINUSE='BI';
    'F6':
      PIN_NUMBER='(F6,0)';
      BIDIRECTIONAL='TRUE';
      INPUT_LOAD='(-0.01,0.01)';
      OUTPUT_LOAD='(1.0,-1.0)';
      PINUSE='BI';
    'F5':
      PIN_NUMBER='(F5,0)';
      BIDIRECTIONAL='TRUE';
      INPUT_LOAD='(-0.01,0.01)';
      OUTPUT_LOAD='(1.0,-1.0)';
      PINUSE='BI';
    'G8':
      PIN_NUMBER='(G8,0)';
      BIDIRECTIONAL='TRUE';
      INPUT_LOAD='(-0.01,0.01)';
      OUTPUT_LOAD='(1.0,-1.0)';
      PINUSE='BI';
    'G7':
      PIN_NUMBER='(G7,0)';
      BIDIRECTIONAL='TRUE';
      INPUT_LOAD='(-0.01,0.01)';
      OUTPUT_LOAD='(1.0,-1.0)';
      PINUSE='BI';
    'G6':
      PIN_NUMBER='(G6,0)';
      BIDIRECTIONAL='TRUE';
      INPUT_LOAD='(-0.01,0.01)';
      OUTPUT_LOAD='(1.0,-1.0)';
      PINUSE='BI';
    'G5':
      PIN_NUMBER='(G5,0)';
      BIDIRECTIONAL='TRUE';
      INPUT_LOAD='(-0.01,0.01)';
      OUTPUT_LOAD='(1.0,-1.0)';
      PINUSE='BI';
    'H8':
      PIN_NUMBER='(H8,0)';
      BIDIRECTIONAL='TRUE';
      INPUT_LOAD='(-0.01,0.01)';
      OUTPUT_LOAD='(1.0,-1.0)';
      PINUSE='BI';
    'H7':
      PIN_NUMBER='(H7,0)';
      BIDIRECTIONAL='TRUE';
      INPUT_LOAD='(-0.01,0.01)';
      OUTPUT_LOAD='(1.0,-1.0)';
      PINUSE='BI';
    'H6':
      PIN_NUMBER='(H6,0)';
      BIDIRECTIONAL='TRUE';
      INPUT_LOAD='(-0.01,0.01)';
      OUTPUT_LOAD='(1.0,-1.0)';
      PINUSE='BI';
    'H5':
      PIN_NUMBER='(H5,0)';
      BIDIRECTIONAL='TRUE';
      INPUT_LOAD='(-0.01,0.01)';
      OUTPUT_LOAD='(1.0,-1.0)';
      PINUSE='BI';
    'I8':
      PIN_NUMBER='(I8,0)';
      BIDIRECTIONAL='TRUE';
      INPUT_LOAD='(-0.01,0.01)';
      OUTPUT_LOAD='(1.0,-1.0)';
      PINUSE='BI';
    'I7':
      PIN_NUMBER='(I7,0)';
      BIDIRECTIONAL='TRUE';
      INPUT_LOAD='(-0.01,0.01)';
      OUTPUT_LOAD='(1.0,-1.0)';
      PINUSE='BI';
    'I6':
      PIN_NUMBER='(I6,0)';
      BIDIRECTIONAL='TRUE';
      INPUT_LOAD='(-0.01,0.01)';
      OUTPUT_LOAD='(1.0,-1.0)';
      PINUSE='BI';
    'I5':
      PIN_NUMBER='(I5,0)';
      BIDIRECTIONAL='TRUE';
      INPUT_LOAD='(-0.01,0.01)';
      OUTPUT_LOAD='(1.0,-1.0)';
      PINUSE='BI';
    'J8':
      PIN_NUMBER='(J8,0)';
      BIDIRECTIONAL='TRUE';
      INPUT_LOAD='(-0.01,0.01)';
      OUTPUT_LOAD='(1.0,-1.0)';
      PINUSE='BI';
    'J7':
      PIN_NUMBER='(J7,0)';
      BIDIRECTIONAL='TRUE';
      INPUT_LOAD='(-0.01,0.01)';
      OUTPUT_LOAD='(1.0,-1.0)';
      PINUSE='BI';
    'J6':
      PIN_NUMBER='(J6,0)';
      BIDIRECTIONAL='TRUE';
      INPUT_LOAD='(-0.01,0.01)';
      OUTPUT_LOAD='(1.0,-1.0)';
      PINUSE='BI';
    'J5':
      PIN_NUMBER='(J5,0)';
      BIDIRECTIONAL='TRUE';
      INPUT_LOAD='(-0.01,0.01)';
      OUTPUT_LOAD='(1.0,-1.0)';
      PINUSE='BI';
    'K8':
      PIN_NUMBER='(K8,0)';
      BIDIRECTIONAL='TRUE';
      INPUT_LOAD='(-0.01,0.01)';
      OUTPUT_LOAD='(1.0,-1.0)';
      PINUSE='BI';
    'K7':
      PIN_NUMBER='(K7,0)';
      BIDIRECTIONAL='TRUE';
      INPUT_LOAD='(-0.01,0.01)';
      OUTPUT_LOAD='(1.0,-1.0)';
      PINUSE='BI';
    'K6':
      PIN_NUMBER='(K6,0)';
      BIDIRECTIONAL='TRUE';
      INPUT_LOAD='(-0.01,0.01)';
      OUTPUT_LOAD='(1.0,-1.0)';
      PINUSE='BI';
    'K5':
      PIN_NUMBER='(K5,0)';
      BIDIRECTIONAL='TRUE';
      INPUT_LOAD='(-0.01,0.01)';
      OUTPUT_LOAD='(1.0,-1.0)';
      PINUSE='BI';
    'L8':
      PIN_NUMBER='(L8,0)';
      BIDIRECTIONAL='TRUE';
      INPUT_LOAD='(-0.01,0.01)';
      OUTPUT_LOAD='(1.0,-1.0)';
      PINUSE='BI';
    'L7':
      PIN_NUMBER='(L7,0)';
      BIDIRECTIONAL='TRUE';
      INPUT_LOAD='(-0.01,0.01)';
      OUTPUT_LOAD='(1.0,-1.0)';
      PINUSE='BI';
    'L6':
      PIN_NUMBER='(L6,0)';
      BIDIRECTIONAL='TRUE';
      INPUT_LOAD='(-0.01,0.01)';
      OUTPUT_LOAD='(1.0,-1.0)';
      PINUSE='BI';
    'L5':
      PIN_NUMBER='(L5,0)';
      BIDIRECTIONAL='TRUE';
      INPUT_LOAD='(-0.01,0.01)';
      OUTPUT_LOAD='(1.0,-1.0)';
      PINUSE='BI';
    'M5':
      PIN_NUMBER='(M5,0)';
      BIDIRECTIONAL='TRUE';
      INPUT_LOAD='(-0.01,0.01)';
      OUTPUT_LOAD='(1.0,-1.0)';
      PINUSE='BI';
    'N5':
      PIN_NUMBER='(N5,0)';
      BIDIRECTIONAL='TRUE';
      INPUT_LOAD='(-0.01,0.01)';
      OUTPUT_LOAD='(1.0,-1.0)';
      PINUSE='BI';
    'M6':
      PIN_NUMBER='(M6,0)';
      BIDIRECTIONAL='TRUE';
      INPUT_LOAD='(-0.01,0.01)';
      OUTPUT_LOAD='(1.0,-1.0)';
      PINUSE='BI';
    'N6':
      PIN_NUMBER='(N6,0)';
      BIDIRECTIONAL='TRUE';
      INPUT_LOAD='(-0.01,0.01)';
      OUTPUT_LOAD='(1.0,-1.0)';
      PINUSE='BI';
    'M7':
      PIN_NUMBER='(M7,0)';
      BIDIRECTIONAL='TRUE';
      INPUT_LOAD='(-0.01,0.01)';
      OUTPUT_LOAD='(1.0,-1.0)';
      PINUSE='BI';
    'N7':
      PIN_NUMBER='(N7,0)';
      BIDIRECTIONAL='TRUE';
      INPUT_LOAD='(-0.01,0.01)';
      OUTPUT_LOAD='(1.0,-1.0)';
      PINUSE='BI';
    'M8':
      PIN_NUMBER='(M8,0)';
      BIDIRECTIONAL='TRUE';
      INPUT_LOAD='(-0.01,0.01)';
      OUTPUT_LOAD='(1.0,-1.0)';
      PINUSE='BI';
    'N8':
      PIN_NUMBER='(N8,0)';
      BIDIRECTIONAL='TRUE';
      INPUT_LOAD='(-0.01,0.01)';
      OUTPUT_LOAD='(1.0,-1.0)';
      PINUSE='BI';
    'A4':
      PIN_NUMBER='(0,A4)';
      BIDIRECTIONAL='TRUE';
      INPUT_LOAD='(-0.01,0.01)';
      OUTPUT_LOAD='(1.0,-1.0)';
      PINUSE='BI';
    'A3':
      PIN_NUMBER='(0,A3)';
      BIDIRECTIONAL='TRUE';
      INPUT_LOAD='(-0.01,0.01)';
      OUTPUT_LOAD='(1.0,-1.0)';
      PINUSE='BI';
    'A2':
      PIN_NUMBER='(0,A2)';
      BIDIRECTIONAL='TRUE';
      INPUT_LOAD='(-0.01,0.01)';
      OUTPUT_LOAD='(1.0,-1.0)';
      PINUSE='BI';
    'A1':
      PIN_NUMBER='(0,A1)';
      BIDIRECTIONAL='TRUE';
      INPUT_LOAD='(-0.01,0.01)';
      OUTPUT_LOAD='(1.0,-1.0)';
      PINUSE='BI';
    'B4':
      PIN_NUMBER='(0,B4)';
      BIDIRECTIONAL='TRUE';
      INPUT_LOAD='(-0.01,0.01)';
      OUTPUT_LOAD='(1.0,-1.0)';
      PINUSE='BI';
    'B3':
      PIN_NUMBER='(0,B3)';
      BIDIRECTIONAL='TRUE';
      INPUT_LOAD='(-0.01,0.01)';
      OUTPUT_LOAD='(1.0,-1.0)';
      PINUSE='BI';
    'B2':
      PIN_NUMBER='(0,B2)';
      BIDIRECTIONAL='TRUE';
      INPUT_LOAD='(-0.01,0.01)';
      OUTPUT_LOAD='(1.0,-1.0)';
      PINUSE='BI';
    'B1':
      PIN_NUMBER='(0,B1)';
      BIDIRECTIONAL='TRUE';
      INPUT_LOAD='(-0.01,0.01)';
      OUTPUT_LOAD='(1.0,-1.0)';
      PINUSE='BI';
    'C4':
      PIN_NUMBER='(0,C4)';
      BIDIRECTIONAL='TRUE';
      INPUT_LOAD='(-0.01,0.01)';
      OUTPUT_LOAD='(1.0,-1.0)';
      PINUSE='BI';
    'C3':
      PIN_NUMBER='(0,C3)';
      BIDIRECTIONAL='TRUE';
      INPUT_LOAD='(-0.01,0.01)';
      OUTPUT_LOAD='(1.0,-1.0)';
      PINUSE='BI';
    'C2':
      PIN_NUMBER='(0,C2)';
      BIDIRECTIONAL='TRUE';
      INPUT_LOAD='(-0.01,0.01)';
      OUTPUT_LOAD='(1.0,-1.0)';
      PINUSE='BI';
    'C1':
      PIN_NUMBER='(0,C1)';
      BIDIRECTIONAL='TRUE';
      INPUT_LOAD='(-0.01,0.01)';
      OUTPUT_LOAD='(1.0,-1.0)';
      PINUSE='BI';
    'D4':
      PIN_NUMBER='(0,D4)';
      BIDIRECTIONAL='TRUE';
      INPUT_LOAD='(-0.01,0.01)';
      OUTPUT_LOAD='(1.0,-1.0)';
      PINUSE='BI';
    'D3':
      PIN_NUMBER='(0,D3)';
      BIDIRECTIONAL='TRUE';
      INPUT_LOAD='(-0.01,0.01)';
      OUTPUT_LOAD='(1.0,-1.0)';
      PINUSE='BI';
    'D2':
      PIN_NUMBER='(0,D2)';
      BIDIRECTIONAL='TRUE';
      INPUT_LOAD='(-0.01,0.01)';
      OUTPUT_LOAD='(1.0,-1.0)';
      PINUSE='BI';
    'D1':
      PIN_NUMBER='(0,D1)';
      BIDIRECTIONAL='TRUE';
      INPUT_LOAD='(-0.01,0.01)';
      OUTPUT_LOAD='(1.0,-1.0)';
      PINUSE='BI';
    'E4':
      PIN_NUMBER='(0,E4)';
      BIDIRECTIONAL='TRUE';
      INPUT_LOAD='(-0.01,0.01)';
      OUTPUT_LOAD='(1.0,-1.0)';
      PINUSE='BI';
    'E3':
      PIN_NUMBER='(0,E3)';
      BIDIRECTIONAL='TRUE';
      INPUT_LOAD='(-0.01,0.01)';
      OUTPUT_LOAD='(1.0,-1.0)';
      PINUSE='BI';
    'E2':
      PIN_NUMBER='(0,E2)';
      BIDIRECTIONAL='TRUE';
      INPUT_LOAD='(-0.01,0.01)';
      OUTPUT_LOAD='(1.0,-1.0)';
      PINUSE='BI';
    'E1':
      PIN_NUMBER='(0,E1)';
      BIDIRECTIONAL='TRUE';
      INPUT_LOAD='(-0.01,0.01)';
      OUTPUT_LOAD='(1.0,-1.0)';
      PINUSE='BI';
    'F4':
      PIN_NUMBER='(0,F4)';
      BIDIRECTIONAL='TRUE';
      INPUT_LOAD='(-0.01,0.01)';
      OUTPUT_LOAD='(1.0,-1.0)';
      PINUSE='BI';
    'F3':
      PIN_NUMBER='(0,F3)';
      BIDIRECTIONAL='TRUE';
      INPUT_LOAD='(-0.01,0.01)';
      OUTPUT_LOAD='(1.0,-1.0)';
      PINUSE='BI';
    'F2':
      PIN_NUMBER='(0,F2)';
      BIDIRECTIONAL='TRUE';
      INPUT_LOAD='(-0.01,0.01)';
      OUTPUT_LOAD='(1.0,-1.0)';
      PINUSE='BI';
    'F1':
      PIN_NUMBER='(0,F1)';
      BIDIRECTIONAL='TRUE';
      INPUT_LOAD='(-0.01,0.01)';
      OUTPUT_LOAD='(1.0,-1.0)';
      PINUSE='BI';
    'G4':
      PIN_NUMBER='(0,G4)';
      BIDIRECTIONAL='TRUE';
      INPUT_LOAD='(-0.01,0.01)';
      OUTPUT_LOAD='(1.0,-1.0)';
      PINUSE='BI';
    'G3':
      PIN_NUMBER='(0,G3)';
      BIDIRECTIONAL='TRUE';
      INPUT_LOAD='(-0.01,0.01)';
      OUTPUT_LOAD='(1.0,-1.0)';
      PINUSE='BI';
    'G2':
      PIN_NUMBER='(0,G2)';
      BIDIRECTIONAL='TRUE';
      INPUT_LOAD='(-0.01,0.01)';
      OUTPUT_LOAD='(1.0,-1.0)';
      PINUSE='BI';
    'G1':
      PIN_NUMBER='(0,G1)';
      BIDIRECTIONAL='TRUE';
      INPUT_LOAD='(-0.01,0.01)';
      OUTPUT_LOAD='(1.0,-1.0)';
      PINUSE='BI';
    'H4':
      PIN_NUMBER='(0,H4)';
      BIDIRECTIONAL='TRUE';
      INPUT_LOAD='(-0.01,0.01)';
      OUTPUT_LOAD='(1.0,-1.0)';
      PINUSE='BI';
    'H3':
      PIN_NUMBER='(0,H3)';
      BIDIRECTIONAL='TRUE';
      INPUT_LOAD='(-0.01,0.01)';
      OUTPUT_LOAD='(1.0,-1.0)';
      PINUSE='BI';
    'H2':
      PIN_NUMBER='(0,H2)';
      BIDIRECTIONAL='TRUE';
      INPUT_LOAD='(-0.01,0.01)';
      OUTPUT_LOAD='(1.0,-1.0)';
      PINUSE='BI';
    'H1':
      PIN_NUMBER='(0,H1)';
      BIDIRECTIONAL='TRUE';
      INPUT_LOAD='(-0.01,0.01)';
      OUTPUT_LOAD='(1.0,-1.0)';
      PINUSE='BI';
    'I4':
      PIN_NUMBER='(0,I4)';
      BIDIRECTIONAL='TRUE';
      INPUT_LOAD='(-0.01,0.01)';
      OUTPUT_LOAD='(1.0,-1.0)';
      PINUSE='BI';
    'I3':
      PIN_NUMBER='(0,I3)';
      BIDIRECTIONAL='TRUE';
      INPUT_LOAD='(-0.01,0.01)';
      OUTPUT_LOAD='(1.0,-1.0)';
      PINUSE='BI';
    'I2':
      PIN_NUMBER='(0,I2)';
      BIDIRECTIONAL='TRUE';
      INPUT_LOAD='(-0.01,0.01)';
      OUTPUT_LOAD='(1.0,-1.0)';
      PINUSE='BI';
    'I1':
      PIN_NUMBER='(0,I1)';
      BIDIRECTIONAL='TRUE';
      INPUT_LOAD='(-0.01,0.01)';
      OUTPUT_LOAD='(1.0,-1.0)';
      PINUSE='BI';
    'J4':
      PIN_NUMBER='(0,J4)';
      BIDIRECTIONAL='TRUE';
      INPUT_LOAD='(-0.01,0.01)';
      OUTPUT_LOAD='(1.0,-1.0)';
      PINUSE='BI';
    'J3':
      PIN_NUMBER='(0,J3)';
      BIDIRECTIONAL='TRUE';
      INPUT_LOAD='(-0.01,0.01)';
      OUTPUT_LOAD='(1.0,-1.0)';
      PINUSE='BI';
    'J2':
      PIN_NUMBER='(0,J2)';
      BIDIRECTIONAL='TRUE';
      INPUT_LOAD='(-0.01,0.01)';
      OUTPUT_LOAD='(1.0,-1.0)';
      PINUSE='BI';
    'J1':
      PIN_NUMBER='(0,J1)';
      BIDIRECTIONAL='TRUE';
      INPUT_LOAD='(-0.01,0.01)';
      OUTPUT_LOAD='(1.0,-1.0)';
      PINUSE='BI';
    'K4':
      PIN_NUMBER='(0,K4)';
      BIDIRECTIONAL='TRUE';
      INPUT_LOAD='(-0.01,0.01)';
      OUTPUT_LOAD='(1.0,-1.0)';
      PINUSE='BI';
    'K3':
      PIN_NUMBER='(0,K3)';
      BIDIRECTIONAL='TRUE';
      INPUT_LOAD='(-0.01,0.01)';
      OUTPUT_LOAD='(1.0,-1.0)';
      PINUSE='BI';
    'K2':
      PIN_NUMBER='(0,K2)';
      BIDIRECTIONAL='TRUE';
      INPUT_LOAD='(-0.01,0.01)';
      OUTPUT_LOAD='(1.0,-1.0)';
      PINUSE='BI';
    'K1':
      PIN_NUMBER='(0,K1)';
      BIDIRECTIONAL='TRUE';
      INPUT_LOAD='(-0.01,0.01)';
      OUTPUT_LOAD='(1.0,-1.0)';
      PINUSE='BI';
    'L4':
      PIN_NUMBER='(0,L4)';
      BIDIRECTIONAL='TRUE';
      INPUT_LOAD='(-0.01,0.01)';
      OUTPUT_LOAD='(1.0,-1.0)';
      PINUSE='BI';
    'L3':
      PIN_NUMBER='(0,L3)';
      BIDIRECTIONAL='TRUE';
      INPUT_LOAD='(-0.01,0.01)';
      OUTPUT_LOAD='(1.0,-1.0)';
      PINUSE='BI';
    'L2':
      PIN_NUMBER='(0,L2)';
      BIDIRECTIONAL='TRUE';
      INPUT_LOAD='(-0.01,0.01)';
      OUTPUT_LOAD='(1.0,-1.0)';
      PINUSE='BI';
    'L1':
      PIN_NUMBER='(0,L1)';
      BIDIRECTIONAL='TRUE';
      INPUT_LOAD='(-0.01,0.01)';
      OUTPUT_LOAD='(1.0,-1.0)';
      PINUSE='BI';
    'M1':
      PIN_NUMBER='(0,M1)';
      BIDIRECTIONAL='TRUE';
      INPUT_LOAD='(-0.01,0.01)';
      OUTPUT_LOAD='(1.0,-1.0)';
      PINUSE='BI';
    'N1':
      PIN_NUMBER='(0,N1)';
      BIDIRECTIONAL='TRUE';
      INPUT_LOAD='(-0.01,0.01)';
      OUTPUT_LOAD='(1.0,-1.0)';
      PINUSE='BI';
    'M2':
      PIN_NUMBER='(0,M2)';
      BIDIRECTIONAL='TRUE';
      INPUT_LOAD='(-0.01,0.01)';
      OUTPUT_LOAD='(1.0,-1.0)';
      PINUSE='BI';
    'N2':
      PIN_NUMBER='(0,N2)';
      BIDIRECTIONAL='TRUE';
      INPUT_LOAD='(-0.01,0.01)';
      OUTPUT_LOAD='(1.0,-1.0)';
      PINUSE='BI';
    'M3':
      PIN_NUMBER='(0,M3)';
      BIDIRECTIONAL='TRUE';
      INPUT_LOAD='(-0.01,0.01)';
      OUTPUT_LOAD='(1.0,-1.0)';
      PINUSE='BI';
    'N3':
      PIN_NUMBER='(0,N3)';
      BIDIRECTIONAL='TRUE';
      INPUT_LOAD='(-0.01,0.01)';
      OUTPUT_LOAD='(1.0,-1.0)';
      PINUSE='BI';
    'M4':
      PIN_NUMBER='(0,M4)';
      BIDIRECTIONAL='TRUE';
      INPUT_LOAD='(-0.01,0.01)';
      OUTPUT_LOAD='(1.0,-1.0)';
      PINUSE='BI';
    'N4':
      PIN_NUMBER='(0,N4)';
      BIDIRECTIONAL='TRUE';
      INPUT_LOAD='(-0.01,0.01)';
      OUTPUT_LOAD='(1.0,-1.0)';
      PINUSE='BI';
  end_pin;
  body
      PART_NAME='CONN112_10137002101LF';
      BODY_NAME='CONN112_10137002101LF';
      PHYS_DES_PREFIX='J';
      CLASS='IO';
      STANDARD='';
      LIFECYCLE='';
      JEDEC_TYPE='HSD_F112D8_P2W1-2_RDH';
      DESCRIPTION='CONN DIP HOUSING 112P 8R FR(P1.2,H17.9)';
      MANUFTR='BER';
      MANUF_PN='10137002-101LF';
      RD_CMPLS_LVL='EP(V1)';
      CMPLS_LVL='';
      DIP_SMD='DIP';
      FROM_PJ='JG5-ALBERT';
      DATA='BER_10137002-101LF';
      FP_ECN='';
      EE_CHECK_LIST='';
      CREATOR='';
      CREATEDAY='20180413';
      PSL='';
      STATUS='';
      ESD_CDM='NA';
      ESD_HBM='NA';
      ESD_MM='NA';
      MSD='NA';
      PIN_LENGTH_LONG_PIN='71 MILS';
      PIN_LENGTH_SHORT_PIN='63 MILS';
      PARENT_PART_TYPE='CONN112_10137002101LF';
      PARENT_PPT='CONN112_10137002101LF';
      PARENT_PPT_PART='CONN112_10137002101LF-CONN112_10137002-101LF,THLF,IO,DFHSB2FR012';
  end_body;
end_primitive;
primitive 'CONN14_210HP207GBR1-CONN14_210A';
  pin
    '1':
      PIN_NUMBER='(1)';
      BIDIRECTIONAL='TRUE';
      INPUT_LOAD='(-0.01,0.01)';
      OUTPUT_LOAD='(1.0,-1.0)';
      PINUSE='BI';
    '2':
      PIN_NUMBER='(2)';
      BIDIRECTIONAL='TRUE';
      INPUT_LOAD='(-0.01,0.01)';
      OUTPUT_LOAD='(1.0,-1.0)';
      PINUSE='BI';
    '3':
      PIN_NUMBER='(3)';
      BIDIRECTIONAL='TRUE';
      INPUT_LOAD='(-0.01,0.01)';
      OUTPUT_LOAD='(1.0,-1.0)';
      PINUSE='BI';
    '4':
      PIN_NUMBER='(4)';
      BIDIRECTIONAL='TRUE';
      INPUT_LOAD='(-0.01,0.01)';
      OUTPUT_LOAD='(1.0,-1.0)';
      PINUSE='BI';
    '5':
      PIN_NUMBER='(5)';
      BIDIRECTIONAL='TRUE';
      INPUT_LOAD='(-0.01,0.01)';
      OUTPUT_LOAD='(1.0,-1.0)';
      PINUSE='BI';
    '6':
      PIN_NUMBER='(6)';
      BIDIRECTIONAL='TRUE';
      INPUT_LOAD='(-0.01,0.01)';
      OUTPUT_LOAD='(1.0,-1.0)';
      PINUSE='BI';
    '7':
      PIN_NUMBER='(7)';
      BIDIRECTIONAL='TRUE';
      INPUT_LOAD='(-0.01,0.01)';
      OUTPUT_LOAD='(1.0,-1.0)';
      PINUSE='BI';
    '8':
      PIN_NUMBER='(8)';
      BIDIRECTIONAL='TRUE';
      INPUT_LOAD='(-0.01,0.01)';
      OUTPUT_LOAD='(1.0,-1.0)';
      PINUSE='BI';
    '9':
      PIN_NUMBER='(9)';
      BIDIRECTIONAL='TRUE';
      INPUT_LOAD='(-0.01,0.01)';
      OUTPUT_LOAD='(1.0,-1.0)';
      PINUSE='BI';
    '10':
      PIN_NUMBER='(10)';
      BIDIRECTIONAL='TRUE';
      INPUT_LOAD='(-0.01,0.01)';
      OUTPUT_LOAD='(1.0,-1.0)';
      PINUSE='BI';
    '11':
      PIN_NUMBER='(11)';
      BIDIRECTIONAL='TRUE';
      INPUT_LOAD='(-0.01,0.01)';
      OUTPUT_LOAD='(1.0,-1.0)';
      PINUSE='BI';
    '12':
      PIN_NUMBER='(12)';
      BIDIRECTIONAL='TRUE';
      INPUT_LOAD='(-0.01,0.01)';
      OUTPUT_LOAD='(1.0,-1.0)';
      PINUSE='BI';
    '13':
      PIN_NUMBER='(13)';
      BIDIRECTIONAL='TRUE';
      INPUT_LOAD='(-0.01,0.01)';
      OUTPUT_LOAD='(1.0,-1.0)';
      PINUSE='BI';
    '14':
      PIN_NUMBER='(14)';
      BIDIRECTIONAL='TRUE';
      INPUT_LOAD='(-0.01,0.01)';
      OUTPUT_LOAD='(1.0,-1.0)';
      PINUSE='BI';
  end_pin;
  body
      PART_NAME='CONN14_210HP207GBR1';
      BODY_NAME='CONN14_210HP207GBR1';
      PHYS_DES_PREFIX='J';
      CLASS='IO';
      STANDARD='';
      LIFECYCLE='';
      JEDEC_TYPE='HEADER2X7XD';
      DESCRIPTION='CONN DIP HEADER 14P 2R MS(P2.54,H8.6)';
      MANUFTR='PRX';
      MANUF_PN='210-HP2-07GBR1';
      RD_CMPLS_LVL='EP(V1)';
      CMPLS_LVL='';
      DIP_SMD='DIP';
      FROM_PJ='F0T-BOB-JON';
      DATA='PRX_210-HP2-07GBR1.pdf';
      FP_ECN='210-HP2-07GBR1.msg';
      EE_CHECK_LIST='';
      CREATOR='';
      CREATEDAY='20211026';
      PSL='';
      STATUS='';
      ESD_CDM='';
      ESD_HBM='';
      ESD_MM='';
      MSD='';
      PIN_LENGTH_LONG_PIN='119 MILS';
      PIN_LENGTH_SHORT_PIN='119 MILS';
      PARENT_PART_TYPE='CONN14_210HP207GBR1';
      PARENT_PPT='CONN14_210HP207GBR1';
      PARENT_PPT_PART='CONN14_210HP207GBR1-CONN14_210-HP2-07GBR1,THLF,IO,DFHD14MS170';
  end_body;
end_primitive;
primitive 'CONN160_10131762101LF-CONN160_A';
  pin
    'A8':
      PIN_NUMBER='(A8,0)';
      BIDIRECTIONAL='TRUE';
      INPUT_LOAD='(-0.01,0.01)';
      OUTPUT_LOAD='(1.0,-1.0)';
      PINUSE='BI';
    'A7':
      PIN_NUMBER='(A7,0)';
      BIDIRECTIONAL='TRUE';
      INPUT_LOAD='(-0.01,0.01)';
      OUTPUT_LOAD='(1.0,-1.0)';
      PINUSE='BI';
    'A6':
      PIN_NUMBER='(A6,0)';
      BIDIRECTIONAL='TRUE';
      INPUT_LOAD='(-0.01,0.01)';
      OUTPUT_LOAD='(1.0,-1.0)';
      PINUSE='BI';
    'A5':
      PIN_NUMBER='(A5,0)';
      BIDIRECTIONAL='TRUE';
      INPUT_LOAD='(-0.01,0.01)';
      OUTPUT_LOAD='(1.0,-1.0)';
      PINUSE='BI';
    'B8':
      PIN_NUMBER='(B8,0)';
      BIDIRECTIONAL='TRUE';
      INPUT_LOAD='(-0.01,0.01)';
      OUTPUT_LOAD='(1.0,-1.0)';
      PINUSE='BI';
    'B7':
      PIN_NUMBER='(B7,0)';
      BIDIRECTIONAL='TRUE';
      INPUT_LOAD='(-0.01,0.01)';
      OUTPUT_LOAD='(1.0,-1.0)';
      PINUSE='BI';
    'B6':
      PIN_NUMBER='(B6,0)';
      BIDIRECTIONAL='TRUE';
      INPUT_LOAD='(-0.01,0.01)';
      OUTPUT_LOAD='(1.0,-1.0)';
      PINUSE='BI';
    'B5':
      PIN_NUMBER='(B5,0)';
      BIDIRECTIONAL='TRUE';
      INPUT_LOAD='(-0.01,0.01)';
      OUTPUT_LOAD='(1.0,-1.0)';
      PINUSE='BI';
    'C8':
      PIN_NUMBER='(C8,0)';
      BIDIRECTIONAL='TRUE';
      INPUT_LOAD='(-0.01,0.01)';
      OUTPUT_LOAD='(1.0,-1.0)';
      PINUSE='BI';
    'C7':
      PIN_NUMBER='(C7,0)';
      BIDIRECTIONAL='TRUE';
      INPUT_LOAD='(-0.01,0.01)';
      OUTPUT_LOAD='(1.0,-1.0)';
      PINUSE='BI';
    'C6':
      PIN_NUMBER='(C6,0)';
      BIDIRECTIONAL='TRUE';
      INPUT_LOAD='(-0.01,0.01)';
      OUTPUT_LOAD='(1.0,-1.0)';
      PINUSE='BI';
    'C5':
      PIN_NUMBER='(C5,0)';
      BIDIRECTIONAL='TRUE';
      INPUT_LOAD='(-0.01,0.01)';
      OUTPUT_LOAD='(1.0,-1.0)';
      PINUSE='BI';
    'D8':
      PIN_NUMBER='(D8,0)';
      BIDIRECTIONAL='TRUE';
      INPUT_LOAD='(-0.01,0.01)';
      OUTPUT_LOAD='(1.0,-1.0)';
      PINUSE='BI';
    'D7':
      PIN_NUMBER='(D7,0)';
      BIDIRECTIONAL='TRUE';
      INPUT_LOAD='(-0.01,0.01)';
      OUTPUT_LOAD='(1.0,-1.0)';
      PINUSE='BI';
    'D6':
      PIN_NUMBER='(D6,0)';
      BIDIRECTIONAL='TRUE';
      INPUT_LOAD='(-0.01,0.01)';
      OUTPUT_LOAD='(1.0,-1.0)';
      PINUSE='BI';
    'D5':
      PIN_NUMBER='(D5,0)';
      BIDIRECTIONAL='TRUE';
      INPUT_LOAD='(-0.01,0.01)';
      OUTPUT_LOAD='(1.0,-1.0)';
      PINUSE='BI';
    'E8':
      PIN_NUMBER='(E8,0)';
      BIDIRECTIONAL='TRUE';
      INPUT_LOAD='(-0.01,0.01)';
      OUTPUT_LOAD='(1.0,-1.0)';
      PINUSE='BI';
    'E7':
      PIN_NUMBER='(E7,0)';
      BIDIRECTIONAL='TRUE';
      INPUT_LOAD='(-0.01,0.01)';
      OUTPUT_LOAD='(1.0,-1.0)';
      PINUSE='BI';
    'E6':
      PIN_NUMBER='(E6,0)';
      BIDIRECTIONAL='TRUE';
      INPUT_LOAD='(-0.01,0.01)';
      OUTPUT_LOAD='(1.0,-1.0)';
      PINUSE='BI';
    'E5':
      PIN_NUMBER='(E5,0)';
      BIDIRECTIONAL='TRUE';
      INPUT_LOAD='(-0.01,0.01)';
      OUTPUT_LOAD='(1.0,-1.0)';
      PINUSE='BI';
    'F8':
      PIN_NUMBER='(F8,0)';
      BIDIRECTIONAL='TRUE';
      INPUT_LOAD='(-0.01,0.01)';
      OUTPUT_LOAD='(1.0,-1.0)';
      PINUSE='BI';
    'F7':
      PIN_NUMBER='(F7,0)';
      BIDIRECTIONAL='TRUE';
      INPUT_LOAD='(-0.01,0.01)';
      OUTPUT_LOAD='(1.0,-1.0)';
      PINUSE='BI';
    'F6':
      PIN_NUMBER='(F6,0)';
      BIDIRECTIONAL='TRUE';
      INPUT_LOAD='(-0.01,0.01)';
      OUTPUT_LOAD='(1.0,-1.0)';
      PINUSE='BI';
    'F5':
      PIN_NUMBER='(F5,0)';
      BIDIRECTIONAL='TRUE';
      INPUT_LOAD='(-0.01,0.01)';
      OUTPUT_LOAD='(1.0,-1.0)';
      PINUSE='BI';
    'G8':
      PIN_NUMBER='(G8,0)';
      BIDIRECTIONAL='TRUE';
      INPUT_LOAD='(-0.01,0.01)';
      OUTPUT_LOAD='(1.0,-1.0)';
      PINUSE='BI';
    'G7':
      PIN_NUMBER='(G7,0)';
      BIDIRECTIONAL='TRUE';
      INPUT_LOAD='(-0.01,0.01)';
      OUTPUT_LOAD='(1.0,-1.0)';
      PINUSE='BI';
    'G6':
      PIN_NUMBER='(G6,0)';
      BIDIRECTIONAL='TRUE';
      INPUT_LOAD='(-0.01,0.01)';
      OUTPUT_LOAD='(1.0,-1.0)';
      PINUSE='BI';
    'G5':
      PIN_NUMBER='(G5,0)';
      BIDIRECTIONAL='TRUE';
      INPUT_LOAD='(-0.01,0.01)';
      OUTPUT_LOAD='(1.0,-1.0)';
      PINUSE='BI';
    'H8':
      PIN_NUMBER='(H8,0)';
      BIDIRECTIONAL='TRUE';
      INPUT_LOAD='(-0.01,0.01)';
      OUTPUT_LOAD='(1.0,-1.0)';
      PINUSE='BI';
    'H7':
      PIN_NUMBER='(H7,0)';
      BIDIRECTIONAL='TRUE';
      INPUT_LOAD='(-0.01,0.01)';
      OUTPUT_LOAD='(1.0,-1.0)';
      PINUSE='BI';
    'H6':
      PIN_NUMBER='(H6,0)';
      BIDIRECTIONAL='TRUE';
      INPUT_LOAD='(-0.01,0.01)';
      OUTPUT_LOAD='(1.0,-1.0)';
      PINUSE='BI';
    'H5':
      PIN_NUMBER='(H5,0)';
      BIDIRECTIONAL='TRUE';
      INPUT_LOAD='(-0.01,0.01)';
      OUTPUT_LOAD='(1.0,-1.0)';
      PINUSE='BI';
    'I8':
      PIN_NUMBER='(I8,0)';
      BIDIRECTIONAL='TRUE';
      INPUT_LOAD='(-0.01,0.01)';
      OUTPUT_LOAD='(1.0,-1.0)';
      PINUSE='BI';
    'I7':
      PIN_NUMBER='(I7,0)';
      BIDIRECTIONAL='TRUE';
      INPUT_LOAD='(-0.01,0.01)';
      OUTPUT_LOAD='(1.0,-1.0)';
      PINUSE='BI';
    'I6':
      PIN_NUMBER='(I6,0)';
      BIDIRECTIONAL='TRUE';
      INPUT_LOAD='(-0.01,0.01)';
      OUTPUT_LOAD='(1.0,-1.0)';
      PINUSE='BI';
    'I5':
      PIN_NUMBER='(I5,0)';
      BIDIRECTIONAL='TRUE';
      INPUT_LOAD='(-0.01,0.01)';
      OUTPUT_LOAD='(1.0,-1.0)';
      PINUSE='BI';
    'J8':
      PIN_NUMBER='(J8,0)';
      BIDIRECTIONAL='TRUE';
      INPUT_LOAD='(-0.01,0.01)';
      OUTPUT_LOAD='(1.0,-1.0)';
      PINUSE='BI';
    'J7':
      PIN_NUMBER='(J7,0)';
      BIDIRECTIONAL='TRUE';
      INPUT_LOAD='(-0.01,0.01)';
      OUTPUT_LOAD='(1.0,-1.0)';
      PINUSE='BI';
    'J6':
      PIN_NUMBER='(J6,0)';
      BIDIRECTIONAL='TRUE';
      INPUT_LOAD='(-0.01,0.01)';
      OUTPUT_LOAD='(1.0,-1.0)';
      PINUSE='BI';
    'J5':
      PIN_NUMBER='(J5,0)';
      BIDIRECTIONAL='TRUE';
      INPUT_LOAD='(-0.01,0.01)';
      OUTPUT_LOAD='(1.0,-1.0)';
      PINUSE='BI';
    'K8':
      PIN_NUMBER='(K8,0)';
      BIDIRECTIONAL='TRUE';
      INPUT_LOAD='(-0.01,0.01)';
      OUTPUT_LOAD='(1.0,-1.0)';
      PINUSE='BI';
    'K7':
      PIN_NUMBER='(K7,0)';
      BIDIRECTIONAL='TRUE';
      INPUT_LOAD='(-0.01,0.01)';
      OUTPUT_LOAD='(1.0,-1.0)';
      PINUSE='BI';
    'K6':
      PIN_NUMBER='(K6,0)';
      BIDIRECTIONAL='TRUE';
      INPUT_LOAD='(-0.01,0.01)';
      OUTPUT_LOAD='(1.0,-1.0)';
      PINUSE='BI';
    'K5':
      PIN_NUMBER='(K5,0)';
      BIDIRECTIONAL='TRUE';
      INPUT_LOAD='(-0.01,0.01)';
      OUTPUT_LOAD='(1.0,-1.0)';
      PINUSE='BI';
    'L8':
      PIN_NUMBER='(L8,0)';
      BIDIRECTIONAL='TRUE';
      INPUT_LOAD='(-0.01,0.01)';
      OUTPUT_LOAD='(1.0,-1.0)';
      PINUSE='BI';
    'L7':
      PIN_NUMBER='(L7,0)';
      BIDIRECTIONAL='TRUE';
      INPUT_LOAD='(-0.01,0.01)';
      OUTPUT_LOAD='(1.0,-1.0)';
      PINUSE='BI';
    'L6':
      PIN_NUMBER='(L6,0)';
      BIDIRECTIONAL='TRUE';
      INPUT_LOAD='(-0.01,0.01)';
      OUTPUT_LOAD='(1.0,-1.0)';
      PINUSE='BI';
    'L5':
      PIN_NUMBER='(L5,0)';
      BIDIRECTIONAL='TRUE';
      INPUT_LOAD='(-0.01,0.01)';
      OUTPUT_LOAD='(1.0,-1.0)';
      PINUSE='BI';
    'M5':
      PIN_NUMBER='(M5,0)';
      BIDIRECTIONAL='TRUE';
      INPUT_LOAD='(-0.01,0.01)';
      OUTPUT_LOAD='(1.0,-1.0)';
      PINUSE='BI';
    'N5':
      PIN_NUMBER='(N5,0)';
      BIDIRECTIONAL='TRUE';
      INPUT_LOAD='(-0.01,0.01)';
      OUTPUT_LOAD='(1.0,-1.0)';
      PINUSE='BI';
    'M6':
      PIN_NUMBER='(M6,0)';
      BIDIRECTIONAL='TRUE';
      INPUT_LOAD='(-0.01,0.01)';
      OUTPUT_LOAD='(1.0,-1.0)';
      PINUSE='BI';
    'N6':
      PIN_NUMBER='(N6,0)';
      BIDIRECTIONAL='TRUE';
      INPUT_LOAD='(-0.01,0.01)';
      OUTPUT_LOAD='(1.0,-1.0)';
      PINUSE='BI';
    'M7':
      PIN_NUMBER='(M7,0)';
      BIDIRECTIONAL='TRUE';
      INPUT_LOAD='(-0.01,0.01)';
      OUTPUT_LOAD='(1.0,-1.0)';
      PINUSE='BI';
    'N7':
      PIN_NUMBER='(N7,0)';
      BIDIRECTIONAL='TRUE';
      INPUT_LOAD='(-0.01,0.01)';
      OUTPUT_LOAD='(1.0,-1.0)';
      PINUSE='BI';
    'M8':
      PIN_NUMBER='(M8,0)';
      BIDIRECTIONAL='TRUE';
      INPUT_LOAD='(-0.01,0.01)';
      OUTPUT_LOAD='(1.0,-1.0)';
      PINUSE='BI';
    'N8':
      PIN_NUMBER='(N8,0)';
      BIDIRECTIONAL='TRUE';
      INPUT_LOAD='(-0.01,0.01)';
      OUTPUT_LOAD='(1.0,-1.0)';
      PINUSE='BI';
    'O5':
      PIN_NUMBER='(O5,0)';
      BIDIRECTIONAL='TRUE';
      INPUT_LOAD='(-0.01,0.01)';
      OUTPUT_LOAD='(1.0,-1.0)';
      PINUSE='BI';
    'P5':
      PIN_NUMBER='(P5,0)';
      BIDIRECTIONAL='TRUE';
      INPUT_LOAD='(-0.01,0.01)';
      OUTPUT_LOAD='(1.0,-1.0)';
      PINUSE='BI';
    'Q5':
      PIN_NUMBER='(Q5,0)';
      BIDIRECTIONAL='TRUE';
      INPUT_LOAD='(-0.01,0.01)';
      OUTPUT_LOAD='(1.0,-1.0)';
      PINUSE='BI';
    'R5':
      PIN_NUMBER='(R5,0)';
      BIDIRECTIONAL='TRUE';
      INPUT_LOAD='(-0.01,0.01)';
      OUTPUT_LOAD='(1.0,-1.0)';
      PINUSE='BI';
    'S5':
      PIN_NUMBER='(S5,0)';
      BIDIRECTIONAL='TRUE';
      INPUT_LOAD='(-0.01,0.01)';
      OUTPUT_LOAD='(1.0,-1.0)';
      PINUSE='BI';
    'T5':
      PIN_NUMBER='(T5,0)';
      BIDIRECTIONAL='TRUE';
      INPUT_LOAD='(-0.01,0.01)';
      OUTPUT_LOAD='(1.0,-1.0)';
      PINUSE='BI';
    'O6':
      PIN_NUMBER='(O6,0)';
      BIDIRECTIONAL='TRUE';
      INPUT_LOAD='(-0.01,0.01)';
      OUTPUT_LOAD='(1.0,-1.0)';
      PINUSE='BI';
    'P6':
      PIN_NUMBER='(P6,0)';
      BIDIRECTIONAL='TRUE';
      INPUT_LOAD='(-0.01,0.01)';
      OUTPUT_LOAD='(1.0,-1.0)';
      PINUSE='BI';
    'Q6':
      PIN_NUMBER='(Q6,0)';
      BIDIRECTIONAL='TRUE';
      INPUT_LOAD='(-0.01,0.01)';
      OUTPUT_LOAD='(1.0,-1.0)';
      PINUSE='BI';
    'R6':
      PIN_NUMBER='(R6,0)';
      BIDIRECTIONAL='TRUE';
      INPUT_LOAD='(-0.01,0.01)';
      OUTPUT_LOAD='(1.0,-1.0)';
      PINUSE='BI';
    'S6':
      PIN_NUMBER='(S6,0)';
      BIDIRECTIONAL='TRUE';
      INPUT_LOAD='(-0.01,0.01)';
      OUTPUT_LOAD='(1.0,-1.0)';
      PINUSE='BI';
    'T6':
      PIN_NUMBER='(T6,0)';
      BIDIRECTIONAL='TRUE';
      INPUT_LOAD='(-0.01,0.01)';
      OUTPUT_LOAD='(1.0,-1.0)';
      PINUSE='BI';
    'O7':
      PIN_NUMBER='(O7,0)';
      BIDIRECTIONAL='TRUE';
      INPUT_LOAD='(-0.01,0.01)';
      OUTPUT_LOAD='(1.0,-1.0)';
      PINUSE='BI';
    'P7':
      PIN_NUMBER='(P7,0)';
      BIDIRECTIONAL='TRUE';
      INPUT_LOAD='(-0.01,0.01)';
      OUTPUT_LOAD='(1.0,-1.0)';
      PINUSE='BI';
    'Q7':
      PIN_NUMBER='(Q7,0)';
      BIDIRECTIONAL='TRUE';
      INPUT_LOAD='(-0.01,0.01)';
      OUTPUT_LOAD='(1.0,-1.0)';
      PINUSE='BI';
    'R7':
      PIN_NUMBER='(R7,0)';
      BIDIRECTIONAL='TRUE';
      INPUT_LOAD='(-0.01,0.01)';
      OUTPUT_LOAD='(1.0,-1.0)';
      PINUSE='BI';
    'S7':
      PIN_NUMBER='(S7,0)';
      BIDIRECTIONAL='TRUE';
      INPUT_LOAD='(-0.01,0.01)';
      OUTPUT_LOAD='(1.0,-1.0)';
      PINUSE='BI';
    'T7':
      PIN_NUMBER='(T7,0)';
      BIDIRECTIONAL='TRUE';
      INPUT_LOAD='(-0.01,0.01)';
      OUTPUT_LOAD='(1.0,-1.0)';
      PINUSE='BI';
    'O8':
      PIN_NUMBER='(O8,0)';
      BIDIRECTIONAL='TRUE';
      INPUT_LOAD='(-0.01,0.01)';
      OUTPUT_LOAD='(1.0,-1.0)';
      PINUSE='BI';
    'P8':
      PIN_NUMBER='(P8,0)';
      BIDIRECTIONAL='TRUE';
      INPUT_LOAD='(-0.01,0.01)';
      OUTPUT_LOAD='(1.0,-1.0)';
      PINUSE='BI';
    'Q8':
      PIN_NUMBER='(Q8,0)';
      BIDIRECTIONAL='TRUE';
      INPUT_LOAD='(-0.01,0.01)';
      OUTPUT_LOAD='(1.0,-1.0)';
      PINUSE='BI';
    'R8':
      PIN_NUMBER='(R8,0)';
      BIDIRECTIONAL='TRUE';
      INPUT_LOAD='(-0.01,0.01)';
      OUTPUT_LOAD='(1.0,-1.0)';
      PINUSE='BI';
    'S8':
      PIN_NUMBER='(S8,0)';
      BIDIRECTIONAL='TRUE';
      INPUT_LOAD='(-0.01,0.01)';
      OUTPUT_LOAD='(1.0,-1.0)';
      PINUSE='BI';
    'T8':
      PIN_NUMBER='(T8,0)';
      BIDIRECTIONAL='TRUE';
      INPUT_LOAD='(-0.01,0.01)';
      OUTPUT_LOAD='(1.0,-1.0)';
      PINUSE='BI';
    'A4':
      PIN_NUMBER='(0,A4)';
      BIDIRECTIONAL='TRUE';
      INPUT_LOAD='(-0.01,0.01)';
      OUTPUT_LOAD='(1.0,-1.0)';
      PINUSE='BI';
    'A3':
      PIN_NUMBER='(0,A3)';
      BIDIRECTIONAL='TRUE';
      INPUT_LOAD='(-0.01,0.01)';
      OUTPUT_LOAD='(1.0,-1.0)';
      PINUSE='BI';
    'A2':
      PIN_NUMBER='(0,A2)';
      BIDIRECTIONAL='TRUE';
      INPUT_LOAD='(-0.01,0.01)';
      OUTPUT_LOAD='(1.0,-1.0)';
      PINUSE='BI';
    'A1':
      PIN_NUMBER='(0,A1)';
      BIDIRECTIONAL='TRUE';
      INPUT_LOAD='(-0.01,0.01)';
      OUTPUT_LOAD='(1.0,-1.0)';
      PINUSE='BI';
    'B4':
      PIN_NUMBER='(0,B4)';
      BIDIRECTIONAL='TRUE';
      INPUT_LOAD='(-0.01,0.01)';
      OUTPUT_LOAD='(1.0,-1.0)';
      PINUSE='BI';
    'B3':
      PIN_NUMBER='(0,B3)';
      BIDIRECTIONAL='TRUE';
      INPUT_LOAD='(-0.01,0.01)';
      OUTPUT_LOAD='(1.0,-1.0)';
      PINUSE='BI';
    'B2':
      PIN_NUMBER='(0,B2)';
      BIDIRECTIONAL='TRUE';
      INPUT_LOAD='(-0.01,0.01)';
      OUTPUT_LOAD='(1.0,-1.0)';
      PINUSE='BI';
    'B1':
      PIN_NUMBER='(0,B1)';
      BIDIRECTIONAL='TRUE';
      INPUT_LOAD='(-0.01,0.01)';
      OUTPUT_LOAD='(1.0,-1.0)';
      PINUSE='BI';
    'C4':
      PIN_NUMBER='(0,C4)';
      BIDIRECTIONAL='TRUE';
      INPUT_LOAD='(-0.01,0.01)';
      OUTPUT_LOAD='(1.0,-1.0)';
      PINUSE='BI';
    'C3':
      PIN_NUMBER='(0,C3)';
      BIDIRECTIONAL='TRUE';
      INPUT_LOAD='(-0.01,0.01)';
      OUTPUT_LOAD='(1.0,-1.0)';
      PINUSE='BI';
    'C2':
      PIN_NUMBER='(0,C2)';
      BIDIRECTIONAL='TRUE';
      INPUT_LOAD='(-0.01,0.01)';
      OUTPUT_LOAD='(1.0,-1.0)';
      PINUSE='BI';
    'C1':
      PIN_NUMBER='(0,C1)';
      BIDIRECTIONAL='TRUE';
      INPUT_LOAD='(-0.01,0.01)';
      OUTPUT_LOAD='(1.0,-1.0)';
      PINUSE='BI';
    'D4':
      PIN_NUMBER='(0,D4)';
      BIDIRECTIONAL='TRUE';
      INPUT_LOAD='(-0.01,0.01)';
      OUTPUT_LOAD='(1.0,-1.0)';
      PINUSE='BI';
    'D3':
      PIN_NUMBER='(0,D3)';
      BIDIRECTIONAL='TRUE';
      INPUT_LOAD='(-0.01,0.01)';
      OUTPUT_LOAD='(1.0,-1.0)';
      PINUSE='BI';
    'D2':
      PIN_NUMBER='(0,D2)';
      BIDIRECTIONAL='TRUE';
      INPUT_LOAD='(-0.01,0.01)';
      OUTPUT_LOAD='(1.0,-1.0)';
      PINUSE='BI';
    'D1':
      PIN_NUMBER='(0,D1)';
      BIDIRECTIONAL='TRUE';
      INPUT_LOAD='(-0.01,0.01)';
      OUTPUT_LOAD='(1.0,-1.0)';
      PINUSE='BI';
    'E4':
      PIN_NUMBER='(0,E4)';
      BIDIRECTIONAL='TRUE';
      INPUT_LOAD='(-0.01,0.01)';
      OUTPUT_LOAD='(1.0,-1.0)';
      PINUSE='BI';
    'E3':
      PIN_NUMBER='(0,E3)';
      BIDIRECTIONAL='TRUE';
      INPUT_LOAD='(-0.01,0.01)';
      OUTPUT_LOAD='(1.0,-1.0)';
      PINUSE='BI';
    'E2':
      PIN_NUMBER='(0,E2)';
      BIDIRECTIONAL='TRUE';
      INPUT_LOAD='(-0.01,0.01)';
      OUTPUT_LOAD='(1.0,-1.0)';
      PINUSE='BI';
    'E1':
      PIN_NUMBER='(0,E1)';
      BIDIRECTIONAL='TRUE';
      INPUT_LOAD='(-0.01,0.01)';
      OUTPUT_LOAD='(1.0,-1.0)';
      PINUSE='BI';
    'F4':
      PIN_NUMBER='(0,F4)';
      BIDIRECTIONAL='TRUE';
      INPUT_LOAD='(-0.01,0.01)';
      OUTPUT_LOAD='(1.0,-1.0)';
      PINUSE='BI';
    'F3':
      PIN_NUMBER='(0,F3)';
      BIDIRECTIONAL='TRUE';
      INPUT_LOAD='(-0.01,0.01)';
      OUTPUT_LOAD='(1.0,-1.0)';
      PINUSE='BI';
    'F2':
      PIN_NUMBER='(0,F2)';
      BIDIRECTIONAL='TRUE';
      INPUT_LOAD='(-0.01,0.01)';
      OUTPUT_LOAD='(1.0,-1.0)';
      PINUSE='BI';
    'F1':
      PIN_NUMBER='(0,F1)';
      BIDIRECTIONAL='TRUE';
      INPUT_LOAD='(-0.01,0.01)';
      OUTPUT_LOAD='(1.0,-1.0)';
      PINUSE='BI';
    'G4':
      PIN_NUMBER='(0,G4)';
      BIDIRECTIONAL='TRUE';
      INPUT_LOAD='(-0.01,0.01)';
      OUTPUT_LOAD='(1.0,-1.0)';
      PINUSE='BI';
    'G3':
      PIN_NUMBER='(0,G3)';
      BIDIRECTIONAL='TRUE';
      INPUT_LOAD='(-0.01,0.01)';
      OUTPUT_LOAD='(1.0,-1.0)';
      PINUSE='BI';
    'G2':
      PIN_NUMBER='(0,G2)';
      BIDIRECTIONAL='TRUE';
      INPUT_LOAD='(-0.01,0.01)';
      OUTPUT_LOAD='(1.0,-1.0)';
      PINUSE='BI';
    'G1':
      PIN_NUMBER='(0,G1)';
      BIDIRECTIONAL='TRUE';
      INPUT_LOAD='(-0.01,0.01)';
      OUTPUT_LOAD='(1.0,-1.0)';
      PINUSE='BI';
    'H4':
      PIN_NUMBER='(0,H4)';
      BIDIRECTIONAL='TRUE';
      INPUT_LOAD='(-0.01,0.01)';
      OUTPUT_LOAD='(1.0,-1.0)';
      PINUSE='BI';
    'H3':
      PIN_NUMBER='(0,H3)';
      BIDIRECTIONAL='TRUE';
      INPUT_LOAD='(-0.01,0.01)';
      OUTPUT_LOAD='(1.0,-1.0)';
      PINUSE='BI';
    'H2':
      PIN_NUMBER='(0,H2)';
      BIDIRECTIONAL='TRUE';
      INPUT_LOAD='(-0.01,0.01)';
      OUTPUT_LOAD='(1.0,-1.0)';
      PINUSE='BI';
    'H1':
      PIN_NUMBER='(0,H1)';
      BIDIRECTIONAL='TRUE';
      INPUT_LOAD='(-0.01,0.01)';
      OUTPUT_LOAD='(1.0,-1.0)';
      PINUSE='BI';
    'I4':
      PIN_NUMBER='(0,I4)';
      BIDIRECTIONAL='TRUE';
      INPUT_LOAD='(-0.01,0.01)';
      OUTPUT_LOAD='(1.0,-1.0)';
      PINUSE='BI';
    'I3':
      PIN_NUMBER='(0,I3)';
      BIDIRECTIONAL='TRUE';
      INPUT_LOAD='(-0.01,0.01)';
      OUTPUT_LOAD='(1.0,-1.0)';
      PINUSE='BI';
    'I2':
      PIN_NUMBER='(0,I2)';
      BIDIRECTIONAL='TRUE';
      INPUT_LOAD='(-0.01,0.01)';
      OUTPUT_LOAD='(1.0,-1.0)';
      PINUSE='BI';
    'I1':
      PIN_NUMBER='(0,I1)';
      BIDIRECTIONAL='TRUE';
      INPUT_LOAD='(-0.01,0.01)';
      OUTPUT_LOAD='(1.0,-1.0)';
      PINUSE='BI';
    'J4':
      PIN_NUMBER='(0,J4)';
      BIDIRECTIONAL='TRUE';
      INPUT_LOAD='(-0.01,0.01)';
      OUTPUT_LOAD='(1.0,-1.0)';
      PINUSE='BI';
    'J3':
      PIN_NUMBER='(0,J3)';
      BIDIRECTIONAL='TRUE';
      INPUT_LOAD='(-0.01,0.01)';
      OUTPUT_LOAD='(1.0,-1.0)';
      PINUSE='BI';
    'J2':
      PIN_NUMBER='(0,J2)';
      BIDIRECTIONAL='TRUE';
      INPUT_LOAD='(-0.01,0.01)';
      OUTPUT_LOAD='(1.0,-1.0)';
      PINUSE='BI';
    'J1':
      PIN_NUMBER='(0,J1)';
      BIDIRECTIONAL='TRUE';
      INPUT_LOAD='(-0.01,0.01)';
      OUTPUT_LOAD='(1.0,-1.0)';
      PINUSE='BI';
    'K4':
      PIN_NUMBER='(0,K4)';
      BIDIRECTIONAL='TRUE';
      INPUT_LOAD='(-0.01,0.01)';
      OUTPUT_LOAD='(1.0,-1.0)';
      PINUSE='BI';
    'K3':
      PIN_NUMBER='(0,K3)';
      BIDIRECTIONAL='TRUE';
      INPUT_LOAD='(-0.01,0.01)';
      OUTPUT_LOAD='(1.0,-1.0)';
      PINUSE='BI';
    'K2':
      PIN_NUMBER='(0,K2)';
      BIDIRECTIONAL='TRUE';
      INPUT_LOAD='(-0.01,0.01)';
      OUTPUT_LOAD='(1.0,-1.0)';
      PINUSE='BI';
    'K1':
      PIN_NUMBER='(0,K1)';
      BIDIRECTIONAL='TRUE';
      INPUT_LOAD='(-0.01,0.01)';
      OUTPUT_LOAD='(1.0,-1.0)';
      PINUSE='BI';
    'L4':
      PIN_NUMBER='(0,L4)';
      BIDIRECTIONAL='TRUE';
      INPUT_LOAD='(-0.01,0.01)';
      OUTPUT_LOAD='(1.0,-1.0)';
      PINUSE='BI';
    'L3':
      PIN_NUMBER='(0,L3)';
      BIDIRECTIONAL='TRUE';
      INPUT_LOAD='(-0.01,0.01)';
      OUTPUT_LOAD='(1.0,-1.0)';
      PINUSE='BI';
    'L2':
      PIN_NUMBER='(0,L2)';
      BIDIRECTIONAL='TRUE';
      INPUT_LOAD='(-0.01,0.01)';
      OUTPUT_LOAD='(1.0,-1.0)';
      PINUSE='BI';
    'L1':
      PIN_NUMBER='(0,L1)';
      BIDIRECTIONAL='TRUE';
      INPUT_LOAD='(-0.01,0.01)';
      OUTPUT_LOAD='(1.0,-1.0)';
      PINUSE='BI';
    'M1':
      PIN_NUMBER='(0,M1)';
      BIDIRECTIONAL='TRUE';
      INPUT_LOAD='(-0.01,0.01)';
      OUTPUT_LOAD='(1.0,-1.0)';
      PINUSE='BI';
    'N1':
      PIN_NUMBER='(0,N1)';
      BIDIRECTIONAL='TRUE';
      INPUT_LOAD='(-0.01,0.01)';
      OUTPUT_LOAD='(1.0,-1.0)';
      PINUSE='BI';
    'M2':
      PIN_NUMBER='(0,M2)';
      BIDIRECTIONAL='TRUE';
      INPUT_LOAD='(-0.01,0.01)';
      OUTPUT_LOAD='(1.0,-1.0)';
      PINUSE='BI';
    'N2':
      PIN_NUMBER='(0,N2)';
      BIDIRECTIONAL='TRUE';
      INPUT_LOAD='(-0.01,0.01)';
      OUTPUT_LOAD='(1.0,-1.0)';
      PINUSE='BI';
    'M3':
      PIN_NUMBER='(0,M3)';
      BIDIRECTIONAL='TRUE';
      INPUT_LOAD='(-0.01,0.01)';
      OUTPUT_LOAD='(1.0,-1.0)';
      PINUSE='BI';
    'N3':
      PIN_NUMBER='(0,N3)';
      BIDIRECTIONAL='TRUE';
      INPUT_LOAD='(-0.01,0.01)';
      OUTPUT_LOAD='(1.0,-1.0)';
      PINUSE='BI';
    'M4':
      PIN_NUMBER='(0,M4)';
      BIDIRECTIONAL='TRUE';
      INPUT_LOAD='(-0.01,0.01)';
      OUTPUT_LOAD='(1.0,-1.0)';
      PINUSE='BI';
    'N4':
      PIN_NUMBER='(0,N4)';
      BIDIRECTIONAL='TRUE';
      INPUT_LOAD='(-0.01,0.01)';
      OUTPUT_LOAD='(1.0,-1.0)';
      PINUSE='BI';
    'O1':
      PIN_NUMBER='(0,O1)';
      BIDIRECTIONAL='TRUE';
      INPUT_LOAD='(-0.01,0.01)';
      OUTPUT_LOAD='(1.0,-1.0)';
      PINUSE='BI';
    'P1':
      PIN_NUMBER='(0,P1)';
      BIDIRECTIONAL='TRUE';
      INPUT_LOAD='(-0.01,0.01)';
      OUTPUT_LOAD='(1.0,-1.0)';
      PINUSE='BI';
    'Q1':
      PIN_NUMBER='(0,Q1)';
      BIDIRECTIONAL='TRUE';
      INPUT_LOAD='(-0.01,0.01)';
      OUTPUT_LOAD='(1.0,-1.0)';
      PINUSE='BI';
    'R1':
      PIN_NUMBER='(0,R1)';
      BIDIRECTIONAL='TRUE';
      INPUT_LOAD='(-0.01,0.01)';
      OUTPUT_LOAD='(1.0,-1.0)';
      PINUSE='BI';
    'S1':
      PIN_NUMBER='(0,S1)';
      BIDIRECTIONAL='TRUE';
      INPUT_LOAD='(-0.01,0.01)';
      OUTPUT_LOAD='(1.0,-1.0)';
      PINUSE='BI';
    'T1':
      PIN_NUMBER='(0,T1)';
      BIDIRECTIONAL='TRUE';
      INPUT_LOAD='(-0.01,0.01)';
      OUTPUT_LOAD='(1.0,-1.0)';
      PINUSE='BI';
    'O2':
      PIN_NUMBER='(0,O2)';
      BIDIRECTIONAL='TRUE';
      INPUT_LOAD='(-0.01,0.01)';
      OUTPUT_LOAD='(1.0,-1.0)';
      PINUSE='BI';
    'P2':
      PIN_NUMBER='(0,P2)';
      BIDIRECTIONAL='TRUE';
      INPUT_LOAD='(-0.01,0.01)';
      OUTPUT_LOAD='(1.0,-1.0)';
      PINUSE='BI';
    'Q2':
      PIN_NUMBER='(0,Q2)';
      BIDIRECTIONAL='TRUE';
      INPUT_LOAD='(-0.01,0.01)';
      OUTPUT_LOAD='(1.0,-1.0)';
      PINUSE='BI';
    'R2':
      PIN_NUMBER='(0,R2)';
      BIDIRECTIONAL='TRUE';
      INPUT_LOAD='(-0.01,0.01)';
      OUTPUT_LOAD='(1.0,-1.0)';
      PINUSE='BI';
    'S2':
      PIN_NUMBER='(0,S2)';
      BIDIRECTIONAL='TRUE';
      INPUT_LOAD='(-0.01,0.01)';
      OUTPUT_LOAD='(1.0,-1.0)';
      PINUSE='BI';
    'T2':
      PIN_NUMBER='(0,T2)';
      BIDIRECTIONAL='TRUE';
      INPUT_LOAD='(-0.01,0.01)';
      OUTPUT_LOAD='(1.0,-1.0)';
      PINUSE='BI';
    'O3':
      PIN_NUMBER='(0,O3)';
      BIDIRECTIONAL='TRUE';
      INPUT_LOAD='(-0.01,0.01)';
      OUTPUT_LOAD='(1.0,-1.0)';
      PINUSE='BI';
    'P3':
      PIN_NUMBER='(0,P3)';
      BIDIRECTIONAL='TRUE';
      INPUT_LOAD='(-0.01,0.01)';
      OUTPUT_LOAD='(1.0,-1.0)';
      PINUSE='BI';
    'Q3':
      PIN_NUMBER='(0,Q3)';
      BIDIRECTIONAL='TRUE';
      INPUT_LOAD='(-0.01,0.01)';
      OUTPUT_LOAD='(1.0,-1.0)';
      PINUSE='BI';
    'R3':
      PIN_NUMBER='(0,R3)';
      BIDIRECTIONAL='TRUE';
      INPUT_LOAD='(-0.01,0.01)';
      OUTPUT_LOAD='(1.0,-1.0)';
      PINUSE='BI';
    'S3':
      PIN_NUMBER='(0,S3)';
      BIDIRECTIONAL='TRUE';
      INPUT_LOAD='(-0.01,0.01)';
      OUTPUT_LOAD='(1.0,-1.0)';
      PINUSE='BI';
    'T3':
      PIN_NUMBER='(0,T3)';
      BIDIRECTIONAL='TRUE';
      INPUT_LOAD='(-0.01,0.01)';
      OUTPUT_LOAD='(1.0,-1.0)';
      PINUSE='BI';
    'O4':
      PIN_NUMBER='(0,O4)';
      BIDIRECTIONAL='TRUE';
      INPUT_LOAD='(-0.01,0.01)';
      OUTPUT_LOAD='(1.0,-1.0)';
      PINUSE='BI';
    'P4':
      PIN_NUMBER='(0,P4)';
      BIDIRECTIONAL='TRUE';
      INPUT_LOAD='(-0.01,0.01)';
      OUTPUT_LOAD='(1.0,-1.0)';
      PINUSE='BI';
    'Q4':
      PIN_NUMBER='(0,Q4)';
      BIDIRECTIONAL='TRUE';
      INPUT_LOAD='(-0.01,0.01)';
      OUTPUT_LOAD='(1.0,-1.0)';
      PINUSE='BI';
    'R4':
      PIN_NUMBER='(0,R4)';
      BIDIRECTIONAL='TRUE';
      INPUT_LOAD='(-0.01,0.01)';
      OUTPUT_LOAD='(1.0,-1.0)';
      PINUSE='BI';
    'S4':
      PIN_NUMBER='(0,S4)';
      BIDIRECTIONAL='TRUE';
      INPUT_LOAD='(-0.01,0.01)';
      OUTPUT_LOAD='(1.0,-1.0)';
      PINUSE='BI';
    'T4':
      PIN_NUMBER='(0,T4)';
      BIDIRECTIONAL='TRUE';
      INPUT_LOAD='(-0.01,0.01)';
      OUTPUT_LOAD='(1.0,-1.0)';
      PINUSE='BI';
  end_pin;
  body
      PART_NAME='CONN160_10131762101LF';
      BODY_NAME='CONN160_10131762101LF';
      PHYS_DES_PREFIX='J';
      CLASS='IO';
      STANDARD='';
      LIFECYCLE='';
      JEDEC_TYPE='HSD_F160D8_P2W1-2_RDH';
      DESCRIPTION='CONN DIP HOUSING 160P 8R FR(P1.2,H25.1)';
      MANUFTR='BER';
      MANUF_PN='10131762-101LF';
      RD_CMPLS_LVL='EP(V1)';
      CMPLS_LVL='';
      DIP_SMD='DIP';
      FROM_PJ='JG5-ALBERT';
      DATA='BER_10131762-101LF.pdf';
      FP_ECN='';
      EE_CHECK_LIST='';
      CREATOR='';
      CREATEDAY='20180413';
      PSL='';
      STATUS='';
      ESD_CDM='NA';
      ESD_HBM='NA';
      ESD_MM='NA';
      MSD='NA';
      PIN_LENGTH_LONG_PIN='71 MILS';
      PIN_LENGTH_SHORT_PIN='63 MILS';
      PARENT_PART_TYPE='CONN160_10131762101LF';
      PARENT_PPT='CONN160_10131762101LF';
      PARENT_PPT_PART='CONN160_10131762101LF-CONN160_10131762-101LF,THLF,IO,DFHSG0FR007';
  end_body;
end_primitive;
primitive 'CONN1_10165288101LF-CONN1_1016A';
  pin
    'NC1':
      PIN_NUMBER='(SCR_H1)';
      BIDIRECTIONAL='TRUE';
      INPUT_LOAD='(-0.01,0.01)';
      OUTPUT_LOAD='(1.0,-1.0)';
      PINUSE='BI';
  end_pin;
  body
      PART_NAME='CONN1_10165288101LF';
      BODY_NAME='CONN1_10165288101LF';
      PHYS_DES_PREFIX='J';
      CLASS='IO';
      NC_PINS='(H1,H2)';
      STANDARD='';
      LIFECYCLE='';
      JEDEC_TYPE='CON_GUIDE-F1XG';
      DESCRIPTION='CONN DIP HOUSING 3P 1R FR(H14.7)';
      MANUFTR='APL';
      MANUF_PN='10165288-101LF';
      RD_CMPLS_LVL='EP(V1)';
      CMPLS_LVL='';
      DIP_SMD='DIP';
      FROM_PJ='F0T-BOB-JON';
      DATA='APL_10165288-101LF.pdf';
      FP_ECN='10165288-101LF.msg';
      EE_CHECK_LIST='';
      CREATOR='';
      CREATEDAY='20211213';
      PSL='';
      STATUS='';
      ESD_CDM='';
      ESD_HBM='';
      ESD_MM='';
      MSD='';
      PIN_LENGTH_LONG_PIN='158 MILS';
      PIN_LENGTH_SHORT_PIN='158 MILS';
      PARENT_PART_TYPE='CONN1_10165288101LF';
      PARENT_PPT='CONN1_10165288101LF';
      PARENT_PPT_PART='CONN1_10165288101LF-CONN1_10165288-101LF,THLF,IO,DFHS03FR030';
  end_body;
end_primitive;
primitive 'CONN2_AAABAT029Y19-CONN2_AAA-BA';
  pin
    '1':
      PIN_NUMBER='(1)';
      PINUSE='POWER';
      NO_LOAD_CHECK='Both';
      NO_IO_CHECK='Both';
      NO_ASSERT_CHECK='TRUE';
      NO_DIR_CHECK='TRUE';
      ALLOW_CONNECT='TRUE';
    '2':
      PIN_NUMBER='(2)';
      PINUSE='POWER';
      NO_LOAD_CHECK='Both';
      NO_IO_CHECK='Both';
      NO_ASSERT_CHECK='TRUE';
      NO_DIR_CHECK='TRUE';
      ALLOW_CONNECT='TRUE';
  end_pin;
  body
      PART_NAME='CONN2_AAABAT029Y19';
      BODY_NAME='CONN2_AAABAT029Y19';
      PHYS_DES_PREFIX='BT';
      CLASS='IO';
      STANDARD='';
      LIFECYCLE='';
      JEDEC_TYPE='BATTERY_AAA-BAT-029-Y19';
      DESCRIPTION='CONN DIP HOUSING 2P 1R FR(P20,H8.80)';
      MANUFTR='LTS';
      MANUF_PN='AAA-BAT-029-Y19';
      RD_CMPLS_LVL='EP(V1)';
      CMPLS_LVL='EP(V1)';
      DIP_SMD='DIP';
      FROM_PJ='S1L-LI-JYUAN';
      DATA='LTS_AAA-BAT-029-Y19.pdf';
      FP_ECN='AAA-BAT-029-Y19.msg';
      EE_CHECK_LIST='';
      CREATOR='';
      CREATEDAY='20200909';
      PSL='';
      STATUS='';
      ESD_CDM='NA';
      ESD_HBM='NA';
      ESD_MM='NA';
      MSD='NA';
      PIN_LENGTH_LONG_PIN='124 MILS';
      PIN_LENGTH_SHORT_PIN='124 MILS';
      PARENT_PART_TYPE='CONN2_AAABAT029Y19';
      PARENT_PPT='CONN2_AAABAT029Y19';
      PARENT_PPT_PART='CONN2_AAABAT029Y19-CONN2_AAA-BAT-029-Y19,THLF,IO,DFHS02FR062';
  end_body;
end_primitive;
primitive 'CONN3_210HP1030BR1-CONN3_210-HA';
  pin
    '3':
      PIN_NUMBER='(3)';
      BIDIRECTIONAL='TRUE';
      INPUT_LOAD='(-0.01,0.01)';
      OUTPUT_LOAD='(1.0,-1.0)';
      PINUSE='BI';
    '2':
      PIN_NUMBER='(2)';
      BIDIRECTIONAL='TRUE';
      INPUT_LOAD='(-0.01,0.01)';
      OUTPUT_LOAD='(1.0,-1.0)';
      PINUSE='BI';
    '1':
      PIN_NUMBER='(1)';
      BIDIRECTIONAL='TRUE';
      INPUT_LOAD='(-0.01,0.01)';
      OUTPUT_LOAD='(1.0,-1.0)';
      PINUSE='BI';
  end_pin;
  body
      PART_NAME='CONN3_210HP1030BR1';
      BODY_NAME='CONN3_210HP1030BR1';
      PHYS_DES_PREFIX='JP';
      CLASS='IO';
      STANDARD='';
      LIFECYCLE='';
      JEDEC_TYPE='HEADER1X3XG';
      DESCRIPTION='CONN DIP HEADER 3P 1R MS(P2.54,H8.6)';
      MANUFTR='PRX';
      MANUF_PN='210-HP1-030BR1';
      RD_CMPLS_LVL='EP(V1)';
      CMPLS_LVL='EP(V1)';
      DIP_SMD='DIP';
      FROM_PJ='F08-OWEN';
      DATA='PRX_210-HP1-030BR1.pdf';
      FP_ECN='';
      EE_CHECK_LIST='';
      CREATOR='';
      CREATEDAY='20160621';
      PSL='';
      STATUS='';
      ESD_CDM='NA';
      ESD_HBM='NA';
      ESD_MM='NA';
      MSD='NA';
      PIN_LENGTH_LONG_PIN='119 MILS';
      PIN_LENGTH_SHORT_PIN='119 MILS';
      PARENT_PART_TYPE='CONN3_210HP1030BR1';
      PARENT_PPT='CONN3_210HP1030BR1';
      PARENT_PPT_PART='CONN3_210HP1030BR1-CONN3_210-HP1-030BR1,THLF,EMPTY,DFHD03MS213';
  end_body;
end_primitive;
primitive 'CONN3_210HP1030BR1-CONN3_210-HB';
  pin
    '3':
      PIN_NUMBER='(3)';
      BIDIRECTIONAL='TRUE';
      INPUT_LOAD='(-0.01,0.01)';
      OUTPUT_LOAD='(1.0,-1.0)';
      PINUSE='BI';
    '2':
      PIN_NUMBER='(2)';
      BIDIRECTIONAL='TRUE';
      INPUT_LOAD='(-0.01,0.01)';
      OUTPUT_LOAD='(1.0,-1.0)';
      PINUSE='BI';
    '1':
      PIN_NUMBER='(1)';
      BIDIRECTIONAL='TRUE';
      INPUT_LOAD='(-0.01,0.01)';
      OUTPUT_LOAD='(1.0,-1.0)';
      PINUSE='BI';
  end_pin;
  body
      PART_NAME='CONN3_210HP1030BR1';
      BODY_NAME='CONN3_210HP1030BR1';
      PHYS_DES_PREFIX='JP';
      CLASS='IO';
      STANDARD='';
      LIFECYCLE='';
      JEDEC_TYPE='HEADER1X3XG';
      DESCRIPTION='CONN DIP HEADER 3P 1R MS(P2.54,H8.6)';
      MANUFTR='PRX';
      MANUF_PN='210-HP1-030BR1';
      RD_CMPLS_LVL='EP(V1)';
      CMPLS_LVL='EP(V1)';
      DIP_SMD='DIP';
      FROM_PJ='F08-OWEN';
      DATA='PRX_210-HP1-030BR1.pdf';
      FP_ECN='';
      EE_CHECK_LIST='';
      CREATOR='';
      CREATEDAY='20160621';
      PSL='';
      STATUS='';
      ESD_CDM='NA';
      ESD_HBM='NA';
      ESD_MM='NA';
      MSD='NA';
      PIN_LENGTH_LONG_PIN='119 MILS';
      PIN_LENGTH_SHORT_PIN='119 MILS';
      PARENT_PART_TYPE='CONN3_210HP1030BR1';
      PARENT_PPT='CONN3_210HP1030BR1';
      PARENT_PPT_PART='CONN3_210HP1030BR1-CONN3_210-HP1-030BR1,THLF,IO,DFHD03MS213';
  end_body;
end_primitive;
primitive 'CONN60_101062636003K02LF-CONN6A';
  pin
    'A2':
      PIN_NUMBER='(A2)';
      BIDIRECTIONAL='TRUE';
      INPUT_LOAD='(-0.01,0.01)';
      OUTPUT_LOAD='(1.0,-1.0)';
      PINUSE='BI';
    'B2':
      PIN_NUMBER='(B2)';
      BIDIRECTIONAL='TRUE';
      INPUT_LOAD='(-0.01,0.01)';
      OUTPUT_LOAD='(1.0,-1.0)';
      PINUSE='BI';
    'C2':
      PIN_NUMBER='(C2)';
      BIDIRECTIONAL='TRUE';
      INPUT_LOAD='(-0.01,0.01)';
      OUTPUT_LOAD='(1.0,-1.0)';
      PINUSE='BI';
    'D2':
      PIN_NUMBER='(D2)';
      BIDIRECTIONAL='TRUE';
      INPUT_LOAD='(-0.01,0.01)';
      OUTPUT_LOAD='(1.0,-1.0)';
      PINUSE='BI';
    'P1_1':
      PIN_NUMBER='(P1_1)';
      PINUSE='POWER';
      NO_LOAD_CHECK='Both';
      NO_IO_CHECK='Both';
      NO_ASSERT_CHECK='TRUE';
      NO_DIR_CHECK='TRUE';
      ALLOW_CONNECT='TRUE';
    'P1_2':
      PIN_NUMBER='(P1_2)';
      PINUSE='POWER';
      NO_LOAD_CHECK='Both';
      NO_IO_CHECK='Both';
      NO_ASSERT_CHECK='TRUE';
      NO_DIR_CHECK='TRUE';
      ALLOW_CONNECT='TRUE';
    'P1_3':
      PIN_NUMBER='(P1_3)';
      PINUSE='POWER';
      NO_LOAD_CHECK='Both';
      NO_IO_CHECK='Both';
      NO_ASSERT_CHECK='TRUE';
      NO_DIR_CHECK='TRUE';
      ALLOW_CONNECT='TRUE';
    'P1_4':
      PIN_NUMBER='(P1_4)';
      PINUSE='POWER';
      NO_LOAD_CHECK='Both';
      NO_IO_CHECK='Both';
      NO_ASSERT_CHECK='TRUE';
      NO_DIR_CHECK='TRUE';
      ALLOW_CONNECT='TRUE';
    'P1_5':
      PIN_NUMBER='(P1_5)';
      PINUSE='POWER';
      NO_LOAD_CHECK='Both';
      NO_IO_CHECK='Both';
      NO_ASSERT_CHECK='TRUE';
      NO_DIR_CHECK='TRUE';
      ALLOW_CONNECT='TRUE';
    'P1_6':
      PIN_NUMBER='(P1_6)';
      PINUSE='POWER';
      NO_LOAD_CHECK='Both';
      NO_IO_CHECK='Both';
      NO_ASSERT_CHECK='TRUE';
      NO_DIR_CHECK='TRUE';
      ALLOW_CONNECT='TRUE';
    'P1_7':
      PIN_NUMBER='(P1_7)';
      PINUSE='POWER';
      NO_LOAD_CHECK='Both';
      NO_IO_CHECK='Both';
      NO_ASSERT_CHECK='TRUE';
      NO_DIR_CHECK='TRUE';
      ALLOW_CONNECT='TRUE';
    'P1_8':
      PIN_NUMBER='(P1_8)';
      PINUSE='POWER';
      NO_LOAD_CHECK='Both';
      NO_IO_CHECK='Both';
      NO_ASSERT_CHECK='TRUE';
      NO_DIR_CHECK='TRUE';
      ALLOW_CONNECT='TRUE';
    'P2_1':
      PIN_NUMBER='(P2_1)';
      PINUSE='POWER';
      NO_LOAD_CHECK='Both';
      NO_IO_CHECK='Both';
      NO_ASSERT_CHECK='TRUE';
      NO_DIR_CHECK='TRUE';
      ALLOW_CONNECT='TRUE';
    'P2_2':
      PIN_NUMBER='(P2_2)';
      PINUSE='POWER';
      NO_LOAD_CHECK='Both';
      NO_IO_CHECK='Both';
      NO_ASSERT_CHECK='TRUE';
      NO_DIR_CHECK='TRUE';
      ALLOW_CONNECT='TRUE';
    'P2_3':
      PIN_NUMBER='(P2_3)';
      PINUSE='POWER';
      NO_LOAD_CHECK='Both';
      NO_IO_CHECK='Both';
      NO_ASSERT_CHECK='TRUE';
      NO_DIR_CHECK='TRUE';
      ALLOW_CONNECT='TRUE';
    'P2_4':
      PIN_NUMBER='(P2_4)';
      PINUSE='POWER';
      NO_LOAD_CHECK='Both';
      NO_IO_CHECK='Both';
      NO_ASSERT_CHECK='TRUE';
      NO_DIR_CHECK='TRUE';
      ALLOW_CONNECT='TRUE';
    'P2_5':
      PIN_NUMBER='(P2_5)';
      PINUSE='POWER';
      NO_LOAD_CHECK='Both';
      NO_IO_CHECK='Both';
      NO_ASSERT_CHECK='TRUE';
      NO_DIR_CHECK='TRUE';
      ALLOW_CONNECT='TRUE';
    'P2_6':
      PIN_NUMBER='(P2_6)';
      PINUSE='POWER';
      NO_LOAD_CHECK='Both';
      NO_IO_CHECK='Both';
      NO_ASSERT_CHECK='TRUE';
      NO_DIR_CHECK='TRUE';
      ALLOW_CONNECT='TRUE';
    'P2_7':
      PIN_NUMBER='(P2_7)';
      PINUSE='POWER';
      NO_LOAD_CHECK='Both';
      NO_IO_CHECK='Both';
      NO_ASSERT_CHECK='TRUE';
      NO_DIR_CHECK='TRUE';
      ALLOW_CONNECT='TRUE';
    'P2_8':
      PIN_NUMBER='(P2_8)';
      PINUSE='POWER';
      NO_LOAD_CHECK='Both';
      NO_IO_CHECK='Both';
      NO_ASSERT_CHECK='TRUE';
      NO_DIR_CHECK='TRUE';
      ALLOW_CONNECT='TRUE';
    'P4_1':
      PIN_NUMBER='(P4_1)';
      PINUSE='POWER';
      NO_LOAD_CHECK='Both';
      NO_IO_CHECK='Both';
      NO_ASSERT_CHECK='TRUE';
      NO_DIR_CHECK='TRUE';
      ALLOW_CONNECT='TRUE';
    'P4_2':
      PIN_NUMBER='(P4_2)';
      PINUSE='POWER';
      NO_LOAD_CHECK='Both';
      NO_IO_CHECK='Both';
      NO_ASSERT_CHECK='TRUE';
      NO_DIR_CHECK='TRUE';
      ALLOW_CONNECT='TRUE';
    'P4_3':
      PIN_NUMBER='(P4_3)';
      PINUSE='POWER';
      NO_LOAD_CHECK='Both';
      NO_IO_CHECK='Both';
      NO_ASSERT_CHECK='TRUE';
      NO_DIR_CHECK='TRUE';
      ALLOW_CONNECT='TRUE';
    'P4_4':
      PIN_NUMBER='(P4_4)';
      PINUSE='POWER';
      NO_LOAD_CHECK='Both';
      NO_IO_CHECK='Both';
      NO_ASSERT_CHECK='TRUE';
      NO_DIR_CHECK='TRUE';
      ALLOW_CONNECT='TRUE';
    'P4_5':
      PIN_NUMBER='(P4_5)';
      PINUSE='POWER';
      NO_LOAD_CHECK='Both';
      NO_IO_CHECK='Both';
      NO_ASSERT_CHECK='TRUE';
      NO_DIR_CHECK='TRUE';
      ALLOW_CONNECT='TRUE';
    'P4_6':
      PIN_NUMBER='(P4_6)';
      PINUSE='POWER';
      NO_LOAD_CHECK='Both';
      NO_IO_CHECK='Both';
      NO_ASSERT_CHECK='TRUE';
      NO_DIR_CHECK='TRUE';
      ALLOW_CONNECT='TRUE';
    'P4_7':
      PIN_NUMBER='(P4_7)';
      PINUSE='POWER';
      NO_LOAD_CHECK='Both';
      NO_IO_CHECK='Both';
      NO_ASSERT_CHECK='TRUE';
      NO_DIR_CHECK='TRUE';
      ALLOW_CONNECT='TRUE';
    'P4_8':
      PIN_NUMBER='(P4_8)';
      PINUSE='POWER';
      NO_LOAD_CHECK='Both';
      NO_IO_CHECK='Both';
      NO_ASSERT_CHECK='TRUE';
      NO_DIR_CHECK='TRUE';
      ALLOW_CONNECT='TRUE';
    'A1':
      PIN_NUMBER='(A1)';
      BIDIRECTIONAL='TRUE';
      INPUT_LOAD='(-0.01,0.01)';
      OUTPUT_LOAD='(1.0,-1.0)';
      PINUSE='BI';
    'B1':
      PIN_NUMBER='(B1)';
      BIDIRECTIONAL='TRUE';
      INPUT_LOAD='(-0.01,0.01)';
      OUTPUT_LOAD='(1.0,-1.0)';
      PINUSE='BI';
    'C1':
      PIN_NUMBER='(C1)';
      BIDIRECTIONAL='TRUE';
      INPUT_LOAD='(-0.01,0.01)';
      OUTPUT_LOAD='(1.0,-1.0)';
      PINUSE='BI';
    'D1':
      PIN_NUMBER='(D1)';
      BIDIRECTIONAL='TRUE';
      INPUT_LOAD='(-0.01,0.01)';
      OUTPUT_LOAD='(1.0,-1.0)';
      PINUSE='BI';
    'P5_1':
      PIN_NUMBER='(P5_1)';
      PINUSE='POWER';
      NO_LOAD_CHECK='Both';
      NO_IO_CHECK='Both';
      NO_ASSERT_CHECK='TRUE';
      NO_DIR_CHECK='TRUE';
      ALLOW_CONNECT='TRUE';
    'P5_2':
      PIN_NUMBER='(P5_2)';
      PINUSE='POWER';
      NO_LOAD_CHECK='Both';
      NO_IO_CHECK='Both';
      NO_ASSERT_CHECK='TRUE';
      NO_DIR_CHECK='TRUE';
      ALLOW_CONNECT='TRUE';
    'P5_3':
      PIN_NUMBER='(P5_3)';
      PINUSE='POWER';
      NO_LOAD_CHECK='Both';
      NO_IO_CHECK='Both';
      NO_ASSERT_CHECK='TRUE';
      NO_DIR_CHECK='TRUE';
      ALLOW_CONNECT='TRUE';
    'P5_4':
      PIN_NUMBER='(P5_4)';
      PINUSE='POWER';
      NO_LOAD_CHECK='Both';
      NO_IO_CHECK='Both';
      NO_ASSERT_CHECK='TRUE';
      NO_DIR_CHECK='TRUE';
      ALLOW_CONNECT='TRUE';
    'P5_5':
      PIN_NUMBER='(P5_5)';
      PINUSE='POWER';
      NO_LOAD_CHECK='Both';
      NO_IO_CHECK='Both';
      NO_ASSERT_CHECK='TRUE';
      NO_DIR_CHECK='TRUE';
      ALLOW_CONNECT='TRUE';
    'P5_6':
      PIN_NUMBER='(P5_6)';
      PINUSE='POWER';
      NO_LOAD_CHECK='Both';
      NO_IO_CHECK='Both';
      NO_ASSERT_CHECK='TRUE';
      NO_DIR_CHECK='TRUE';
      ALLOW_CONNECT='TRUE';
    'P5_7':
      PIN_NUMBER='(P5_7)';
      PINUSE='POWER';
      NO_LOAD_CHECK='Both';
      NO_IO_CHECK='Both';
      NO_ASSERT_CHECK='TRUE';
      NO_DIR_CHECK='TRUE';
      ALLOW_CONNECT='TRUE';
    'P5_8':
      PIN_NUMBER='(P5_8)';
      PINUSE='POWER';
      NO_LOAD_CHECK='Both';
      NO_IO_CHECK='Both';
      NO_ASSERT_CHECK='TRUE';
      NO_DIR_CHECK='TRUE';
      ALLOW_CONNECT='TRUE';
    'P3_1':
      PIN_NUMBER='(P3_1)';
      PINUSE='POWER';
      NO_LOAD_CHECK='Both';
      NO_IO_CHECK='Both';
      NO_ASSERT_CHECK='TRUE';
      NO_DIR_CHECK='TRUE';
      ALLOW_CONNECT='TRUE';
    'P3_2':
      PIN_NUMBER='(P3_2)';
      PINUSE='POWER';
      NO_LOAD_CHECK='Both';
      NO_IO_CHECK='Both';
      NO_ASSERT_CHECK='TRUE';
      NO_DIR_CHECK='TRUE';
      ALLOW_CONNECT='TRUE';
    'P3_3':
      PIN_NUMBER='(P3_3)';
      PINUSE='POWER';
      NO_LOAD_CHECK='Both';
      NO_IO_CHECK='Both';
      NO_ASSERT_CHECK='TRUE';
      NO_DIR_CHECK='TRUE';
      ALLOW_CONNECT='TRUE';
    'P3_4':
      PIN_NUMBER='(P3_4)';
      PINUSE='POWER';
      NO_LOAD_CHECK='Both';
      NO_IO_CHECK='Both';
      NO_ASSERT_CHECK='TRUE';
      NO_DIR_CHECK='TRUE';
      ALLOW_CONNECT='TRUE';
    'P3_5':
      PIN_NUMBER='(P3_5)';
      PINUSE='POWER';
      NO_LOAD_CHECK='Both';
      NO_IO_CHECK='Both';
      NO_ASSERT_CHECK='TRUE';
      NO_DIR_CHECK='TRUE';
      ALLOW_CONNECT='TRUE';
    'P3_6':
      PIN_NUMBER='(P3_6)';
      PINUSE='POWER';
      NO_LOAD_CHECK='Both';
      NO_IO_CHECK='Both';
      NO_ASSERT_CHECK='TRUE';
      NO_DIR_CHECK='TRUE';
      ALLOW_CONNECT='TRUE';
    'P3_7':
      PIN_NUMBER='(P3_7)';
      PINUSE='POWER';
      NO_LOAD_CHECK='Both';
      NO_IO_CHECK='Both';
      NO_ASSERT_CHECK='TRUE';
      NO_DIR_CHECK='TRUE';
      ALLOW_CONNECT='TRUE';
    'P3_8':
      PIN_NUMBER='(P3_8)';
      PINUSE='POWER';
      NO_LOAD_CHECK='Both';
      NO_IO_CHECK='Both';
      NO_ASSERT_CHECK='TRUE';
      NO_DIR_CHECK='TRUE';
      ALLOW_CONNECT='TRUE';
    'P6_1':
      PIN_NUMBER='(P6_1)';
      PINUSE='POWER';
      NO_LOAD_CHECK='Both';
      NO_IO_CHECK='Both';
      NO_ASSERT_CHECK='TRUE';
      NO_DIR_CHECK='TRUE';
      ALLOW_CONNECT='TRUE';
    'P6_2':
      PIN_NUMBER='(P6_2)';
      PINUSE='POWER';
      NO_LOAD_CHECK='Both';
      NO_IO_CHECK='Both';
      NO_ASSERT_CHECK='TRUE';
      NO_DIR_CHECK='TRUE';
      ALLOW_CONNECT='TRUE';
    'P6_3':
      PIN_NUMBER='(P6_3)';
      PINUSE='POWER';
      NO_LOAD_CHECK='Both';
      NO_IO_CHECK='Both';
      NO_ASSERT_CHECK='TRUE';
      NO_DIR_CHECK='TRUE';
      ALLOW_CONNECT='TRUE';
    'P6_4':
      PIN_NUMBER='(P6_4)';
      PINUSE='POWER';
      NO_LOAD_CHECK='Both';
      NO_IO_CHECK='Both';
      NO_ASSERT_CHECK='TRUE';
      NO_DIR_CHECK='TRUE';
      ALLOW_CONNECT='TRUE';
    'P6_5':
      PIN_NUMBER='(P6_5)';
      PINUSE='POWER';
      NO_LOAD_CHECK='Both';
      NO_IO_CHECK='Both';
      NO_ASSERT_CHECK='TRUE';
      NO_DIR_CHECK='TRUE';
      ALLOW_CONNECT='TRUE';
    'P6_6':
      PIN_NUMBER='(P6_6)';
      PINUSE='POWER';
      NO_LOAD_CHECK='Both';
      NO_IO_CHECK='Both';
      NO_ASSERT_CHECK='TRUE';
      NO_DIR_CHECK='TRUE';
      ALLOW_CONNECT='TRUE';
    'P6_7':
      PIN_NUMBER='(P6_7)';
      PINUSE='POWER';
      NO_LOAD_CHECK='Both';
      NO_IO_CHECK='Both';
      NO_ASSERT_CHECK='TRUE';
      NO_DIR_CHECK='TRUE';
      ALLOW_CONNECT='TRUE';
    'P6_8':
      PIN_NUMBER='(P6_8)';
      PINUSE='POWER';
      NO_LOAD_CHECK='Both';
      NO_IO_CHECK='Both';
      NO_ASSERT_CHECK='TRUE';
      NO_DIR_CHECK='TRUE';
      ALLOW_CONNECT='TRUE';
    'A3':
      PIN_NUMBER='(A3)';
      BIDIRECTIONAL='TRUE';
      INPUT_LOAD='(-0.01,0.01)';
      OUTPUT_LOAD='(1.0,-1.0)';
      PINUSE='BI';
    'B3':
      PIN_NUMBER='(B3)';
      BIDIRECTIONAL='TRUE';
      INPUT_LOAD='(-0.01,0.01)';
      OUTPUT_LOAD='(1.0,-1.0)';
      PINUSE='BI';
    'C3':
      PIN_NUMBER='(C3)';
      BIDIRECTIONAL='TRUE';
      INPUT_LOAD='(-0.01,0.01)';
      OUTPUT_LOAD='(1.0,-1.0)';
      PINUSE='BI';
    'D3':
      PIN_NUMBER='(D3)';
      BIDIRECTIONAL='TRUE';
      INPUT_LOAD='(-0.01,0.01)';
      OUTPUT_LOAD='(1.0,-1.0)';
      PINUSE='BI';
  end_pin;
  body
      PART_NAME='CONN60_101062636003K02LF';
      BODY_NAME='CONN60_101062636003K02LF';
      PHYS_DES_PREFIX='J';
      CLASS='IO';
      NC_PINS='(SCR_H1,SCR_H2)';
      STANDARD='';
      LIFECYCLE='';
      JEDEC_TYPE='HSD_M60D4H2D_P2-54W2-54_LDHXB';
      DESCRIPTION='CONN DIP HEADER 60P 4R MR(P2.54,H12.57)';
      MANUFTR='APL';
      MANUF_PN='10106263-6003K02LF';
      RD_CMPLS_LVL='EP(V1)';
      CMPLS_LVL='';
      DIP_SMD='DIP';
      FROM_PJ='F0T-IVES';
      DATA='APL_10106263-6003K02LF.pdf';
      FP_ECN='10106263-6003K02LF.msg';
      EE_CHECK_LIST='';
      CREATOR='';
      CREATEDAY='20220513';
      PSL='';
      STATUS='';
      ESD_CDM='';
      ESD_HBM='';
      ESD_MM='';
      MSD='';
      PIN_LENGTH_LONG_PIN='136 MILS';
      PIN_LENGTH_SHORT_PIN='136 MILS';
      PARENT_PART_TYPE='CONN60_101062636003K02LF';
      PARENT_PPT='CONN60_101062636003K02LF';
      PARENT_PPT_PART='CONN60_101062636003K02LF-CONN60_10106263-6003K02LF,THLF,IO,DFHD60MR024';
  end_body;
end_primitive;
primitive 'CONN8_210HP1080BR1-CONN8_210-HA';
  pin
    '1':
      PIN_NUMBER='(1)';
      BIDIRECTIONAL='TRUE';
      INPUT_LOAD='(-0.01,0.01)';
      OUTPUT_LOAD='(1.0,-1.0)';
      PINUSE='BI';
    '2':
      PIN_NUMBER='(2)';
      BIDIRECTIONAL='TRUE';
      INPUT_LOAD='(-0.01,0.01)';
      OUTPUT_LOAD='(1.0,-1.0)';
      PINUSE='BI';
    '3':
      PIN_NUMBER='(3)';
      BIDIRECTIONAL='TRUE';
      INPUT_LOAD='(-0.01,0.01)';
      OUTPUT_LOAD='(1.0,-1.0)';
      PINUSE='BI';
    '4':
      PIN_NUMBER='(4)';
      BIDIRECTIONAL='TRUE';
      INPUT_LOAD='(-0.01,0.01)';
      OUTPUT_LOAD='(1.0,-1.0)';
      PINUSE='BI';
    '5':
      PIN_NUMBER='(5)';
      BIDIRECTIONAL='TRUE';
      INPUT_LOAD='(-0.01,0.01)';
      OUTPUT_LOAD='(1.0,-1.0)';
      PINUSE='BI';
    '6':
      PIN_NUMBER='(6)';
      BIDIRECTIONAL='TRUE';
      INPUT_LOAD='(-0.01,0.01)';
      OUTPUT_LOAD='(1.0,-1.0)';
      PINUSE='BI';
    '7':
      PIN_NUMBER='(7)';
      BIDIRECTIONAL='TRUE';
      INPUT_LOAD='(-0.01,0.01)';
      OUTPUT_LOAD='(1.0,-1.0)';
      PINUSE='BI';
    '8':
      PIN_NUMBER='(8)';
      BIDIRECTIONAL='TRUE';
      INPUT_LOAD='(-0.01,0.01)';
      OUTPUT_LOAD='(1.0,-1.0)';
      PINUSE='BI';
  end_pin;
  body
      PART_NAME='CONN8_210HP1080BR1';
      BODY_NAME='CONN8_210HP1080BR1';
      PHYS_DES_PREFIX='J';
      CLASS='IO';
      STANDARD='';
      LIFECYCLE='';
      JEDEC_TYPE='HEADER1X8XE';
      DESCRIPTION='CONN DIP HEADER 8P 1R MS(P2.54,H8.6)';
      MANUFTR='PRX';
      MANUF_PN='210-HP1-080BR1';
      RD_CMPLS_LVL='EP(V1)';
      CMPLS_LVL='EP(V1)';
      DIP_SMD='DIP';
      FROM_PJ='F08-SHERRY';
      DATA='PRX_210-HP1-080BR1.pdf';
      FP_ECN='';
      EE_CHECK_LIST='';
      CREATOR='';
      CREATEDAY='20160406';
      PSL='';
      STATUS='';
      ESD_CDM='';
      ESD_HBM='';
      ESD_MM='';
      MSD='';
      PIN_LENGTH_LONG_PIN='119 MILS';
      PIN_LENGTH_SHORT_PIN='119 MILS';
      PARENT_PART_TYPE='CONN8_210HP1080BR1';
      PARENT_PPT='CONN8_210HP1080BR1';
      PARENT_PPT_PART='CONN8_210HP1080BR1-CONN8_210-HP1-080BR1,THLF,IO,DFHD08MS392';
  end_body;
end_primitive;
primitive 'DIODE_TVS-SMF14A,SMLF,IC,BCSMFA';
  pin
    'A':
      PIN_NUMBER='(A)';
      INPUT_LOAD='(-0.01,0.01)';
      PINUSE='IN';
    'C':
      PIN_NUMBER='(C)';
      OUTPUT_LOAD='(1.0,-1.0)';
      PINUSE='OUT';
  end_pin;
  body
      PART_NAME='DIODE_TVS';
      BODY_NAME='DIODE_TVS';
      PHYS_DES_PREFIX='D';
      CLASS='IC';
      STANDARD='';
      LIFECYCLE='';
      JEDEC_TYPE='SOD123F';
      DESCRIPTION='DIODE SMF14A(14V,8.6A)SOD-123FL';
      MANUFTR='LFI';
      MANUF_PN='SMF14A';
      RD_CMPLS_LVL='EP(V1)';
      CMPLS_LVL='EP(V1)';
      DIP_SMD='';
      FP_ECN='';
      FROM_PJ='F0G-EGBERT';
      DATA='LFI_SMF14A.pdf';
      EE_CHECK_LIST='';
      STATUS='';
      PSL='';
      PREFERENCE='';
      CREATOR='';
      CREATEDAY='20190805';
      PARENT_PART_TYPE='DIODE_TVS';
      PARENT_PPT='DIODE_TVS';
      PARENT_PPT_PART='DIODE_TVS-SMF14A,SMLF,IC,BCSMF14AZ01';
  end_body;
end_primitive;
primitive 'DS125BR111RTWR-DS125BR111RTWR,A';
  pin
    'EQB0||AD3':
      PIN_NUMBER='(1)';
      INPUT_LOAD='(-0.01,0.01)';
      PINUSE='IN';
    'EQB1||AD2':
      PIN_NUMBER='(2)';
      INPUT_LOAD='(-0.01,0.01)';
      PINUSE='IN';
    'ENSMB':
      PIN_NUMBER='(3)';
      INPUT_LOAD='(-0.01,0.01)';
      PINUSE='IN';
    'SDA||VODA_DB':
      PIN_NUMBER='(4)';
      BIDIRECTIONAL='TRUE';
      INPUT_LOAD='(-0.01,0.01)';
      OUTPUT_LOAD='(1.0,-1.0)';
      PINUSE='BI';
    'SCL||VODB_DB':
      PIN_NUMBER='(5)';
      BIDIRECTIONAL='TRUE';
      INPUT_LOAD='(-0.01,0.01)';
      OUTPUT_LOAD='(1.0,-1.0)';
      PINUSE='BI';
    'PWDN':
      PIN_NUMBER='(6)';
      INPUT_LOAD='(-0.01,0.01)';
      PINUSE='IN';
    'OUTA+':
      PIN_NUMBER='(7)';
      OUTPUT_LOAD='(1.0,-1.0)';
      PINUSE='OUT';
    'OUTA-':
      PIN_NUMBER='(8)';
      OUTPUT_LOAD='(1.0,-1.0)';
      PINUSE='OUT';
    'EQA1||AD1':
      PIN_NUMBER='(9)';
      INPUT_LOAD='(-0.01,0.01)';
      PINUSE='IN';
    'EQA0||AD0':
      PIN_NUMBER='(10)';
      INPUT_LOAD='(-0.01,0.01)';
      PINUSE='IN';
    'INB+':
      PIN_NUMBER='(11)';
      INPUT_LOAD='(-0.01,0.01)';
      PINUSE='IN';
    'INB-':
      PIN_NUMBER='(12)';
      INPUT_LOAD='(-0.01,0.01)';
      PINUSE='IN';
    'RES':
      PIN_NUMBER='(13)';
      INPUT_LOAD='(-0.01,0.01)';
      PINUSE='IN';
    'SD_TH':
      PIN_NUMBER='(14)';
      INPUT_LOAD='(-0.01,0.01)';
      PINUSE='IN';
    'VIN':
      PIN_NUMBER='(15)';
      PINUSE='POWER';
      NO_LOAD_CHECK='Both';
      NO_IO_CHECK='Both';
      NO_ASSERT_CHECK='TRUE';
      NO_DIR_CHECK='TRUE';
      ALLOW_CONNECT='TRUE';
    'VDD_SEL':
      PIN_NUMBER='(16)';
      INPUT_LOAD='(-0.01,0.01)';
      PINUSE='IN';
    'VOD_SEL||READEN#':
      PIN_NUMBER='(17)';
      INPUT_LOAD='(-0.01,0.01)';
      PINUSE='IN';
    'RXDET||DONE#':
      PIN_NUMBER='(18)';
      BIDIRECTIONAL='TRUE';
      INPUT_LOAD='(-0.01,0.01)';
      OUTPUT_LOAD='(1.0,-1.0)';
      PINUSE='BI';
    'OUTB-':
      PIN_NUMBER='(19)';
      OUTPUT_LOAD='(1.0,-1.0)';
      PINUSE='OUT';
    'OUTB+':
      PIN_NUMBER='(20)';
      OUTPUT_LOAD='(1.0,-1.0)';
      PINUSE='OUT';
    'VDD_21':
      PIN_NUMBER='(21)';
      PINUSE='POWER';
      NO_LOAD_CHECK='Both';
      NO_IO_CHECK='Both';
      NO_ASSERT_CHECK='TRUE';
      NO_DIR_CHECK='TRUE';
      ALLOW_CONNECT='TRUE';
    'VDD_22':
      PIN_NUMBER='(22)';
      PINUSE='POWER';
      NO_LOAD_CHECK='Both';
      NO_IO_CHECK='Both';
      NO_ASSERT_CHECK='TRUE';
      NO_DIR_CHECK='TRUE';
      ALLOW_CONNECT='TRUE';
    'INA-':
      PIN_NUMBER='(23)';
      INPUT_LOAD='(-0.01,0.01)';
      PINUSE='IN';
    'INA+':
      PIN_NUMBER='(24)';
      INPUT_LOAD='(-0.01,0.01)';
      PINUSE='IN';
    'TH_GND':
      PIN_NUMBER='(25)';
      PINUSE='POWER';
      NO_LOAD_CHECK='Both';
      NO_IO_CHECK='Both';
      NO_ASSERT_CHECK='TRUE';
      NO_DIR_CHECK='TRUE';
      ALLOW_CONNECT='TRUE';
  end_pin;
  body
      PART_NAME='DS125BR111RTWR';
      BODY_NAME='DS125BR111RTWR';
      PHYS_DES_PREFIX='U';
      CLASS='IC';
      STANDARD='';
      LIFECYCLE='';
      JEDEC_TYPE='WQFN24_TH_0-5_4X4XA';
      DESCRIPTION='IC OTHER(24P)DS125BR111RTWR(WQFN)';
      MANUFTR='TIC';
      MANUF_PN='DS125BR111RTWR';
      RD_CMPLS_LVL='EP(V1)';
      CMPLS_LVL='EP(V1)';
      FROM_PJ='F0T-IVES';
      DIP_SMD='';
      DATA='TIC_DS125BR111RTWR.pdf';
      EE_CHECK_LIST='';
      FP_ECN='';
      PSL='';
      CREATOR='';
      STATUS='';
      MSD='';
      ESD_CDM='';
      ESD_HBM='';
      ESD_MM='';
      PIN_LENGTH_SHORT_PIN='0 MILS';
      PIN_LENGTH_LONG_PIN='0 MILS';
      CREATEDAY='20220331';
      PARENT_PART_TYPE='DS125BR111RTWR';
      PARENT_PPT='DS125BR111RTWR';
      PARENT_PPT_PART='DS125BR111RTWR-DS125BR111RTWR,SMLF,EMPTY,AL000125003';
  end_body;
end_primitive;
primitive 'DUMMY_SYMBOL-BATTERY_SYMBOL,MEA';
  pin
    '1':
      PIN_NUMBER='(1)';
      OUTPUT_TYPE='(TS,TS)';
      INPUT_LOAD='(-0.01,0.01)';
      OUTPUT_LOAD='(1.0,-1.0)';
      PINUSE='TRI';
  end_pin;
  body
      PART_NAME='DUMMY_SYMBOL';
      BODY_NAME='DUMMY_SYMBOL';
      PHYS_DES_PREFIX='DM';
      CLASS='IO';
      STANDARD='';
      LIFECYCLE='';
      JEDEC_TYPE='TP30_FOR_BOM';
      DESCRIPTION='BATTERY_SYMBOL';
      MANUFTR='';
      MANUF_PN='';
      RD_CMPLS_LVL='';
      CMPLS_LVL='';
      DIP_SMD='';
      FROM_PJ='';
      DATA='';
      FP_ECN='';
      EE_CHECK_LIST='';
      PSL='';
      PREFERENCE='';
      CREATOR='';
      CREATEDAY='20141104';
      STATUS='';
      PARENT_PART_TYPE='DUMMY_SYMBOL';
      PARENT_PPT='DUMMY_SYMBOL';
      PARENT_PPT_PART='DUMMY_SYMBOL-BATTERY_SYMBOL,MECH,MECH,DUMMY12';
  end_body;
end_primitive;
primitive 'DUMMY_SYMBOL-MECHANIC_SYMBOL,MA';
  pin
    '1':
      PIN_NUMBER='(1)';
      OUTPUT_TYPE='(TS,TS)';
      INPUT_LOAD='(-0.01,0.01)';
      OUTPUT_LOAD='(1.0,-1.0)';
      PINUSE='TRI';
  end_pin;
  body
      PART_NAME='DUMMY_SYMBOL';
      BODY_NAME='DUMMY_SYMBOL';
      PHYS_DES_PREFIX='DM';
      CLASS='IO';
      STANDARD='';
      LIFECYCLE='';
      JEDEC_TYPE='TP30_FOR_BOM';
      DESCRIPTION='MECHANIC_SYMBOL';
      MANUFTR='';
      MANUF_PN='';
      RD_CMPLS_LVL='';
      CMPLS_LVL='';
      DIP_SMD='';
      FROM_PJ='';
      DATA='';
      FP_ECN='';
      EE_CHECK_LIST='';
      PSL='';
      PREFERENCE='';
      CREATOR='';
      CREATEDAY='20141104';
      STATUS='';
      PARENT_PART_TYPE='DUMMY_SYMBOL';
      PARENT_PPT='DUMMY_SYMBOL';
      PARENT_PPT_PART='DUMMY_SYMBOL-MECHANIC_SYMBOL,MECH,MECH,DUMMY10';
  end_body;
end_primitive;
primitive 'EMMITSBURG_REV0P9-GFNOCPU04302A';
  pin
    'RSVD_J23':
      PIN_NUMBER='(J23,0,0,0,0,0,0,0,0,0,0)';
      OUTPUT_TYPE='(TS,TS)';
      INPUT_LOAD='(-0.01,0.01)';
      OUTPUT_LOAD='(1.0,-1.0)';
      PINUSE='TRI';
    'RSVD_H24':
      PIN_NUMBER='(H24,0,0,0,0,0,0,0,0,0,0)';
      OUTPUT_TYPE='(TS,TS)';
      INPUT_LOAD='(-0.01,0.01)';
      OUTPUT_LOAD='(1.0,-1.0)';
      PINUSE='TRI';
    'XCLK_BIASREF':
      PIN_NUMBER='(N29,0,0,0,0,0,0,0,0,0,0)';
      BIDIRECTIONAL='TRUE';
      INPUT_LOAD='(-0.01,0.01)';
      OUTPUT_LOAD='(1.0,-1.0)';
      PINUSE='BI';
    'CLKOUT_SRC_N_0':
      PIN_NUMBER='(A16,0,0,0,0,0,0,0,0,0,0)';
      OUTPUT_LOAD='(1.0,-1.0)';
      PINUSE='OUT';
    'CLKOUT_SRC_N_1':
      PIN_NUMBER='(G23,0,0,0,0,0,0,0,0,0,0)';
      OUTPUT_LOAD='(1.0,-1.0)';
      PINUSE='OUT';
    'CLKOUT_SRC_N_10':
      PIN_NUMBER='(J16,0,0,0,0,0,0,0,0,0,0)';
      OUTPUT_LOAD='(1.0,-1.0)';
      PINUSE='OUT';
    'CLKOUT_SRC_N_11':
      PIN_NUMBER='(G16,0,0,0,0,0,0,0,0,0,0)';
      OUTPUT_LOAD='(1.0,-1.0)';
      PINUSE='OUT';
    'CLKOUT_SRC_N_12':
      PIN_NUMBER='(A10,0,0,0,0,0,0,0,0,0,0)';
      OUTPUT_LOAD='(1.0,-1.0)';
      PINUSE='OUT';
    'CLKOUT_SRC_N_13':
      PIN_NUMBER='(A8,0,0,0,0,0,0,0,0,0,0)';
      OUTPUT_LOAD='(1.0,-1.0)';
      PINUSE='OUT';
    'CLKOUT_SRC_N_14':
      PIN_NUMBER='(B7,0,0,0,0,0,0,0,0,0,0)';
      OUTPUT_LOAD='(1.0,-1.0)';
      PINUSE='OUT';
    'CLKOUT_SRC_N_15':
      PIN_NUMBER='(B5,0,0,0,0,0,0,0,0,0,0)';
      OUTPUT_LOAD='(1.0,-1.0)';
      PINUSE='OUT';
    'CLKOUT_SRC_N_16':
      PIN_NUMBER='(A18,0,0,0,0,0,0,0,0,0,0)';
      OUTPUT_LOAD='(1.0,-1.0)';
      PINUSE='OUT';
    'CLKOUT_SRC_N_2':
      PIN_NUMBER='(H21,0,0,0,0,0,0,0,0,0,0)';
      OUTPUT_LOAD='(1.0,-1.0)';
      PINUSE='OUT';
    'CLKOUT_SRC_N_3':
      PIN_NUMBER='(B17,0,0,0,0,0,0,0,0,0,0)';
      OUTPUT_LOAD='(1.0,-1.0)';
      PINUSE='OUT';
    'CLKOUT_SRC_N_4':
      PIN_NUMBER='(B19,0,0,0,0,0,0,0,0,0,0)';
      OUTPUT_LOAD='(1.0,-1.0)';
      PINUSE='OUT';
    'CLKOUT_SRC_N_5':
      PIN_NUMBER='(A12,0,0,0,0,0,0,0,0,0,0)';
      OUTPUT_LOAD='(1.0,-1.0)';
      PINUSE='OUT';
    'CLKOUT_SRC_N_6':
      PIN_NUMBER='(B11,0,0,0,0,0,0,0,0,0,0)';
      OUTPUT_LOAD='(1.0,-1.0)';
      PINUSE='OUT';
    'CLKOUT_SRC_N_7':
      PIN_NUMBER='(A14,0,0,0,0,0,0,0,0,0,0)';
      OUTPUT_LOAD='(1.0,-1.0)';
      PINUSE='OUT';
    'CLKOUT_SRC_N_8':
      PIN_NUMBER='(F18,0,0,0,0,0,0,0,0,0,0)';
      OUTPUT_LOAD='(1.0,-1.0)';
      PINUSE='OUT';
    'CLKOUT_SRC_N_9':
      PIN_NUMBER='(B15,0,0,0,0,0,0,0,0,0,0)';
      OUTPUT_LOAD='(1.0,-1.0)';
      PINUSE='OUT';
    'CLKOUT_SRC_P_0':
      PIN_NUMBER='(C16,0,0,0,0,0,0,0,0,0,0)';
      OUTPUT_LOAD='(1.0,-1.0)';
      PINUSE='OUT';
    'CLKOUT_SRC_P_1':
      PIN_NUMBER='(F21,0,0,0,0,0,0,0,0,0,0)';
      OUTPUT_LOAD='(1.0,-1.0)';
      PINUSE='OUT';
    'CLKOUT_SRC_P_10':
      PIN_NUMBER='(K18,0,0,0,0,0,0,0,0,0,0)';
      OUTPUT_LOAD='(1.0,-1.0)';
      PINUSE='OUT';
    'CLKOUT_SRC_P_11':
      PIN_NUMBER='(H15,0,0,0,0,0,0,0,0,0,0)';
      OUTPUT_LOAD='(1.0,-1.0)';
      PINUSE='OUT';
    'CLKOUT_SRC_P_12':
      PIN_NUMBER='(C10,0,0,0,0,0,0,0,0,0,0)';
      OUTPUT_LOAD='(1.0,-1.0)';
      PINUSE='OUT';
    'CLKOUT_SRC_P_13':
      PIN_NUMBER='(C8,0,0,0,0,0,0,0,0,0,0)';
      OUTPUT_LOAD='(1.0,-1.0)';
      PINUSE='OUT';
    'CLKOUT_SRC_P_14':
      PIN_NUMBER='(D7,0,0,0,0,0,0,0,0,0,0)';
      OUTPUT_LOAD='(1.0,-1.0)';
      PINUSE='OUT';
    'CLKOUT_SRC_P_15':
      PIN_NUMBER='(C6,0,0,0,0,0,0,0,0,0,0)';
      OUTPUT_LOAD='(1.0,-1.0)';
      PINUSE='OUT';
    'CLKOUT_SRC_P_16':
      PIN_NUMBER='(C18,0,0,0,0,0,0,0,0,0,0)';
      OUTPUT_LOAD='(1.0,-1.0)';
      PINUSE='OUT';
    'CLKOUT_SRC_P_2':
      PIN_NUMBER='(K21,0,0,0,0,0,0,0,0,0,0)';
      OUTPUT_LOAD='(1.0,-1.0)';
      PINUSE='OUT';
    'CLKOUT_SRC_P_3':
      PIN_NUMBER='(D17,0,0,0,0,0,0,0,0,0,0)';
      OUTPUT_LOAD='(1.0,-1.0)';
      PINUSE='OUT';
    'CLKOUT_SRC_P_4':
      PIN_NUMBER='(D19,0,0,0,0,0,0,0,0,0,0)';
      OUTPUT_LOAD='(1.0,-1.0)';
      PINUSE='OUT';
    'CLKOUT_SRC_P_5':
      PIN_NUMBER='(C12,0,0,0,0,0,0,0,0,0,0)';
      OUTPUT_LOAD='(1.0,-1.0)';
      PINUSE='OUT';
    'CLKOUT_SRC_P_6':
      PIN_NUMBER='(D11,0,0,0,0,0,0,0,0,0,0)';
      OUTPUT_LOAD='(1.0,-1.0)';
      PINUSE='OUT';
    'CLKOUT_SRC_P_7':
      PIN_NUMBER='(C14,0,0,0,0,0,0,0,0,0,0)';
      OUTPUT_LOAD='(1.0,-1.0)';
      PINUSE='OUT';
    'CLKOUT_SRC_P_8':
      PIN_NUMBER='(H18,0,0,0,0,0,0,0,0,0,0)';
      OUTPUT_LOAD='(1.0,-1.0)';
      PINUSE='OUT';
    'CLKOUT_SRC_P_9':
      PIN_NUMBER='(D15,0,0,0,0,0,0,0,0,0,0)';
      OUTPUT_LOAD='(1.0,-1.0)';
      PINUSE='OUT';
    'PMSYNC_CLK_N_0':
      PIN_NUMBER='(D27,0,0,0,0,0,0,0,0,0,0)';
      OUTPUT_LOAD='(1.0,-1.0)';
      PINUSE='OUT';
    'PMSYNC_CLK_N_1':
      PIN_NUMBER='(C28,0,0,0,0,0,0,0,0,0,0)';
      OUTPUT_LOAD='(1.0,-1.0)';
      PINUSE='OUT';
    'PMSYNC_CLK_P_0':
      PIN_NUMBER='(B27,0,0,0,0,0,0,0,0,0,0)';
      OUTPUT_LOAD='(1.0,-1.0)';
      PINUSE='OUT';
    'PMSYNC_CLK_P_1':
      PIN_NUMBER='(A28,0,0,0,0,0,0,0,0,0,0)';
      OUTPUT_LOAD='(1.0,-1.0)';
      PINUSE='OUT';
    'REFCLK_INJ_NS_N':
      PIN_NUMBER='(D25,0,0,0,0,0,0,0,0,0,0)';
      INPUT_LOAD='(-0.01,0.01)';
      PINUSE='IN';
    'REFCLK_INJ_NS_P':
      PIN_NUMBER='(B25,0,0,0,0,0,0,0,0,0,0)';
      INPUT_LOAD='(-0.01,0.01)';
      PINUSE='IN';
    'REFCLK_INJ_S_N':
      PIN_NUMBER='(D21,0,0,0,0,0,0,0,0,0,0)';
      INPUT_LOAD='(-0.01,0.01)';
      PINUSE='IN';
    'REFCLK_INJ_S_P':
      PIN_NUMBER='(B21,0,0,0,0,0,0,0,0,0,0)';
      INPUT_LOAD='(-0.01,0.01)';
      PINUSE='IN';
    'RTCX1':
      PIN_NUMBER='(BE6,0,0,0,0,0,0,0,0,0,0)';
      INPUT_LOAD='(-0.01,0.01)';
      PINUSE='IN';
    'RTCX2':
      PIN_NUMBER='(BF7,0,0,0,0,0,0,0,0,0,0)';
      OUTPUT_LOAD='(1.0,-1.0)';
      PINUSE='OUT';
    'RTC_EXTCAP':
      PIN_NUMBER='(BF5,0,0,0,0,0,0,0,0,0,0)';
      BIDIRECTIONAL='TRUE';
      INPUT_LOAD='(-0.01,0.01)';
      OUTPUT_LOAD='(1.0,-1.0)';
      PINUSE='BI';
    'XTAL_IN':
      PIN_NUMBER='(B23,0,0,0,0,0,0,0,0,0,0)';
      INPUT_LOAD='(-0.01,0.01)';
      PINUSE='IN';
    'XTAL_OUT':
      PIN_NUMBER='(D23,0,0,0,0,0,0,0,0,0,0)';
      OUTPUT_LOAD='(1.0,-1.0)';
      PINUSE='OUT';
    'RSVD_BC40':
      PIN_NUMBER='(0,BC40,0,0,0,0,0,0,0,0,0)';
      OUTPUT_TYPE='(TS,TS)';
      INPUT_LOAD='(-0.01,0.01)';
      OUTPUT_LOAD='(1.0,-1.0)';
      PINUSE='TRI';
    'USB2N_0':
      PIN_NUMBER='(0,AR42,0,0,0,0,0,0,0,0,0)';
      BIDIRECTIONAL='TRUE';
      INPUT_LOAD='(-0.01,0.01)';
      OUTPUT_LOAD='(1.0,-1.0)';
      PINUSE='BI';
    'USB2N_1':
      PIN_NUMBER='(0,AP43,0,0,0,0,0,0,0,0,0)';
      BIDIRECTIONAL='TRUE';
      INPUT_LOAD='(-0.01,0.01)';
      OUTPUT_LOAD='(1.0,-1.0)';
      PINUSE='BI';
    'USB2N_10':
      PIN_NUMBER='(0,AY43,0,0,0,0,0,0,0,0,0)';
      BIDIRECTIONAL='TRUE';
      INPUT_LOAD='(-0.01,0.01)';
      OUTPUT_LOAD='(1.0,-1.0)';
      PINUSE='BI';
    'USB2N_11':
      PIN_NUMBER='(0,AH42,0,0,0,0,0,0,0,0,0)';
      BIDIRECTIONAL='TRUE';
      INPUT_LOAD='(-0.01,0.01)';
      OUTPUT_LOAD='(1.0,-1.0)';
      PINUSE='BI';
    'USB2N_12':
      PIN_NUMBER='(0,BA42,0,0,0,0,0,0,0,0,0)';
      BIDIRECTIONAL='TRUE';
      INPUT_LOAD='(-0.01,0.01)';
      OUTPUT_LOAD='(1.0,-1.0)';
      PINUSE='BI';
    'USB2N_13':
      PIN_NUMBER='(0,AG43,0,0,0,0,0,0,0,0,0)';
      BIDIRECTIONAL='TRUE';
      INPUT_LOAD='(-0.01,0.01)';
      OUTPUT_LOAD='(1.0,-1.0)';
      PINUSE='BI';
    'USB2N_2':
      PIN_NUMBER='(0,AT43,0,0,0,0,0,0,0,0,0)';
      BIDIRECTIONAL='TRUE';
      INPUT_LOAD='(-0.01,0.01)';
      OUTPUT_LOAD='(1.0,-1.0)';
      PINUSE='BI';
    'USB2N_3':
      PIN_NUMBER='(0,AN42,0,0,0,0,0,0,0,0,0)';
      BIDIRECTIONAL='TRUE';
      INPUT_LOAD='(-0.01,0.01)';
      OUTPUT_LOAD='(1.0,-1.0)';
      PINUSE='BI';
    'USB2N_4':
      PIN_NUMBER='(0,AU42,0,0,0,0,0,0,0,0,0)';
      BIDIRECTIONAL='TRUE';
      INPUT_LOAD='(-0.01,0.01)';
      OUTPUT_LOAD='(1.0,-1.0)';
      PINUSE='BI';
    'USB2N_5':
      PIN_NUMBER='(0,AL43,0,0,0,0,0,0,0,0,0)';
      BIDIRECTIONAL='TRUE';
      INPUT_LOAD='(-0.01,0.01)';
      OUTPUT_LOAD='(1.0,-1.0)';
      PINUSE='BI';
    'USB2N_6':
      PIN_NUMBER='(0,AV43,0,0,0,0,0,0,0,0,0)';
      BIDIRECTIONAL='TRUE';
      INPUT_LOAD='(-0.01,0.01)';
      OUTPUT_LOAD='(1.0,-1.0)';
      PINUSE='BI';
    'USB2N_7':
      PIN_NUMBER='(0,AK42,0,0,0,0,0,0,0,0,0)';
      BIDIRECTIONAL='TRUE';
      INPUT_LOAD='(-0.01,0.01)';
      OUTPUT_LOAD='(1.0,-1.0)';
      PINUSE='BI';
    'USB2N_8':
      PIN_NUMBER='(0,AW42,0,0,0,0,0,0,0,0,0)';
      BIDIRECTIONAL='TRUE';
      INPUT_LOAD='(-0.01,0.01)';
      OUTPUT_LOAD='(1.0,-1.0)';
      PINUSE='BI';
    'USB2N_9':
      PIN_NUMBER='(0,AJ43,0,0,0,0,0,0,0,0,0)';
      BIDIRECTIONAL='TRUE';
      INPUT_LOAD='(-0.01,0.01)';
      OUTPUT_LOAD='(1.0,-1.0)';
      PINUSE='BI';
    'USB2P_0':
      PIN_NUMBER='(0,AR40,0,0,0,0,0,0,0,0,0)';
      BIDIRECTIONAL='TRUE';
      INPUT_LOAD='(-0.01,0.01)';
      OUTPUT_LOAD='(1.0,-1.0)';
      PINUSE='BI';
    'USB2P_1':
      PIN_NUMBER='(0,AP41,0,0,0,0,0,0,0,0,0)';
      BIDIRECTIONAL='TRUE';
      INPUT_LOAD='(-0.01,0.01)';
      OUTPUT_LOAD='(1.0,-1.0)';
      PINUSE='BI';
    'USB2P_10':
      PIN_NUMBER='(0,AY41,0,0,0,0,0,0,0,0,0)';
      BIDIRECTIONAL='TRUE';
      INPUT_LOAD='(-0.01,0.01)';
      OUTPUT_LOAD='(1.0,-1.0)';
      PINUSE='BI';
    'USB2P_11':
      PIN_NUMBER='(0,AH40,0,0,0,0,0,0,0,0,0)';
      BIDIRECTIONAL='TRUE';
      INPUT_LOAD='(-0.01,0.01)';
      OUTPUT_LOAD='(1.0,-1.0)';
      PINUSE='BI';
    'USB2P_12':
      PIN_NUMBER='(0,BA40,0,0,0,0,0,0,0,0,0)';
      BIDIRECTIONAL='TRUE';
      INPUT_LOAD='(-0.01,0.01)';
      OUTPUT_LOAD='(1.0,-1.0)';
      PINUSE='BI';
    'USB2P_13':
      PIN_NUMBER='(0,AG41,0,0,0,0,0,0,0,0,0)';
      BIDIRECTIONAL='TRUE';
      INPUT_LOAD='(-0.01,0.01)';
      OUTPUT_LOAD='(1.0,-1.0)';
      PINUSE='BI';
    'USB2P_2':
      PIN_NUMBER='(0,AT41,0,0,0,0,0,0,0,0,0)';
      BIDIRECTIONAL='TRUE';
      INPUT_LOAD='(-0.01,0.01)';
      OUTPUT_LOAD='(1.0,-1.0)';
      PINUSE='BI';
    'USB2P_3':
      PIN_NUMBER='(0,AN40,0,0,0,0,0,0,0,0,0)';
      BIDIRECTIONAL='TRUE';
      INPUT_LOAD='(-0.01,0.01)';
      OUTPUT_LOAD='(1.0,-1.0)';
      PINUSE='BI';
    'USB2P_4':
      PIN_NUMBER='(0,AU40,0,0,0,0,0,0,0,0,0)';
      BIDIRECTIONAL='TRUE';
      INPUT_LOAD='(-0.01,0.01)';
      OUTPUT_LOAD='(1.0,-1.0)';
      PINUSE='BI';
    'USB2P_5':
      PIN_NUMBER='(0,AL41,0,0,0,0,0,0,0,0,0)';
      BIDIRECTIONAL='TRUE';
      INPUT_LOAD='(-0.01,0.01)';
      OUTPUT_LOAD='(1.0,-1.0)';
      PINUSE='BI';
    'USB2P_6':
      PIN_NUMBER='(0,AV41,0,0,0,0,0,0,0,0,0)';
      BIDIRECTIONAL='TRUE';
      INPUT_LOAD='(-0.01,0.01)';
      OUTPUT_LOAD='(1.0,-1.0)';
      PINUSE='BI';
    'USB2P_7':
      PIN_NUMBER='(0,AK40,0,0,0,0,0,0,0,0,0)';
      BIDIRECTIONAL='TRUE';
      INPUT_LOAD='(-0.01,0.01)';
      OUTPUT_LOAD='(1.0,-1.0)';
      PINUSE='BI';
    'USB2P_8':
      PIN_NUMBER='(0,AW40,0,0,0,0,0,0,0,0,0)';
      BIDIRECTIONAL='TRUE';
      INPUT_LOAD='(-0.01,0.01)';
      OUTPUT_LOAD='(1.0,-1.0)';
      PINUSE='BI';
    'USB2P_9':
      PIN_NUMBER='(0,AJ41,0,0,0,0,0,0,0,0,0)';
      BIDIRECTIONAL='TRUE';
      INPUT_LOAD='(-0.01,0.01)';
      OUTPUT_LOAD='(1.0,-1.0)';
      PINUSE='BI';
    'USB2_COMP':
      PIN_NUMBER='(0,BB41,0,0,0,0,0,0,0,0,0)';
      BIDIRECTIONAL='TRUE';
      INPUT_LOAD='(-0.01,0.01)';
      OUTPUT_LOAD='(1.0,-1.0)';
      PINUSE='BI';
    'DMI_0_RXN':
      PIN_NUMBER='(0,0,A30,0,0,0,0,0,0,0,0)';
      INPUT_LOAD='(-0.01,0.01)';
      PINUSE='IN';
    'DMI_0_RXP':
      PIN_NUMBER='(0,0,C30,0,0,0,0,0,0,0,0)';
      INPUT_LOAD='(-0.01,0.01)';
      PINUSE='IN';
    'DMI_0_TXN':
      PIN_NUMBER='(0,0,K28,0,0,0,0,0,0,0,0)';
      OUTPUT_LOAD='(1.0,-1.0)';
      PINUSE='OUT';
    'DMI_0_TXP':
      PIN_NUMBER='(0,0,H28,0,0,0,0,0,0,0,0)';
      OUTPUT_LOAD='(1.0,-1.0)';
      PINUSE='OUT';
    'DMI_1_RXN':
      PIN_NUMBER='(0,0,B31,0,0,0,0,0,0,0,0)';
      INPUT_LOAD='(-0.01,0.01)';
      PINUSE='IN';
    'DMI_1_RXP':
      PIN_NUMBER='(0,0,D31,0,0,0,0,0,0,0,0)';
      INPUT_LOAD='(-0.01,0.01)';
      PINUSE='IN';
    'DMI_1_TXN':
      PIN_NUMBER='(0,0,G29,0,0,0,0,0,0,0,0)';
      OUTPUT_LOAD='(1.0,-1.0)';
      PINUSE='OUT';
    'DMI_1_TXP':
      PIN_NUMBER='(0,0,F28,0,0,0,0,0,0,0,0)';
      OUTPUT_LOAD='(1.0,-1.0)';
      PINUSE='OUT';
    'DMI_2_RXN':
      PIN_NUMBER='(0,0,A32,0,0,0,0,0,0,0,0)';
      INPUT_LOAD='(-0.01,0.01)';
      PINUSE='IN';
    'DMI_2_RXP':
      PIN_NUMBER='(0,0,C32,0,0,0,0,0,0,0,0)';
      INPUT_LOAD='(-0.01,0.01)';
      PINUSE='IN';
    'DMI_2_TXN':
      PIN_NUMBER='(0,0,J29,0,0,0,0,0,0,0,0)';
      OUTPUT_LOAD='(1.0,-1.0)';
      PINUSE='OUT';
    'DMI_2_TXP':
      PIN_NUMBER='(0,0,H31,0,0,0,0,0,0,0,0)';
      OUTPUT_LOAD='(1.0,-1.0)';
      PINUSE='OUT';
    'DMI_3_RXN':
      PIN_NUMBER='(0,0,B33,0,0,0,0,0,0,0,0)';
      INPUT_LOAD='(-0.01,0.01)';
      PINUSE='IN';
    'DMI_3_RXP':
      PIN_NUMBER='(0,0,D33,0,0,0,0,0,0,0,0)';
      INPUT_LOAD='(-0.01,0.01)';
      PINUSE='IN';
    'DMI_3_TXN':
      PIN_NUMBER='(0,0,L32,0,0,0,0,0,0,0,0)';
      OUTPUT_LOAD='(1.0,-1.0)';
      PINUSE='OUT';
    'DMI_3_TXP':
      PIN_NUMBER='(0,0,K31,0,0,0,0,0,0,0,0)';
      OUTPUT_LOAD='(1.0,-1.0)';
      PINUSE='OUT';
    'DMI_4_SATA_19_PCIE3_19_RXN':
      PIN_NUMBER='(0,0,A34,0,0,0,0,0,0,0,0)';
      INPUT_LOAD='(-0.01,0.01)';
      PINUSE='IN';
    'DMI_4_SATA_19_PCIE3_19_RXP':
      PIN_NUMBER='(0,0,C34,0,0,0,0,0,0,0,0)';
      INPUT_LOAD='(-0.01,0.01)';
      PINUSE='IN';
    'DMI_4_SATA_19_PCIE3_19_TXN':
      PIN_NUMBER='(0,0,J32,0,0,0,0,0,0,0,0)';
      OUTPUT_LOAD='(1.0,-1.0)';
      PINUSE='OUT';
    'DMI_4_SATA_19_PCIE3_19_TXP':
      PIN_NUMBER='(0,0,G32,0,0,0,0,0,0,0,0)';
      OUTPUT_LOAD='(1.0,-1.0)';
      PINUSE='OUT';
    'DMI_5_SATA_18_PCIE3_18_RXN':
      PIN_NUMBER='(0,0,B35,0,0,0,0,0,0,0,0)';
      INPUT_LOAD='(-0.01,0.01)';
      PINUSE='IN';
    'DMI_5_SATA_18_PCIE3_18_RXP':
      PIN_NUMBER='(0,0,D35,0,0,0,0,0,0,0,0)';
      INPUT_LOAD='(-0.01,0.01)';
      PINUSE='IN';
    'DMI_5_SATA_18_PCIE3_18_TXN':
      PIN_NUMBER='(0,0,G36,0,0,0,0,0,0,0,0)';
      OUTPUT_LOAD='(1.0,-1.0)';
      PINUSE='OUT';
    'DMI_5_SATA_18_PCIE3_18_TXP':
      PIN_NUMBER='(0,0,H34,0,0,0,0,0,0,0,0)';
      OUTPUT_LOAD='(1.0,-1.0)';
      PINUSE='OUT';
    'DMI_6_SATA_17_PCIE3_17_RXN':
      PIN_NUMBER='(0,0,A36,0,0,0,0,0,0,0,0)';
      INPUT_LOAD='(-0.01,0.01)';
      PINUSE='IN';
    'DMI_6_SATA_17_PCIE3_17_RXP':
      PIN_NUMBER='(0,0,C36,0,0,0,0,0,0,0,0)';
      INPUT_LOAD='(-0.01,0.01)';
      PINUSE='IN';
    'DMI_6_SATA_17_PCIE3_17_TXN':
      PIN_NUMBER='(0,0,K37,0,0,0,0,0,0,0,0)';
      OUTPUT_LOAD='(1.0,-1.0)';
      PINUSE='OUT';
    'DMI_6_SATA_17_PCIE3_17_TXP':
      PIN_NUMBER='(0,0,J36,0,0,0,0,0,0,0,0)';
      OUTPUT_LOAD='(1.0,-1.0)';
      PINUSE='OUT';
    'DMI_7_SATA_16_PCIE3_16_RXN':
      PIN_NUMBER='(0,0,B37,0,0,0,0,0,0,0,0)';
      INPUT_LOAD='(-0.01,0.01)';
      PINUSE='IN';
    'DMI_7_SATA_16_PCIE3_16_RXP':
      PIN_NUMBER='(0,0,D37,0,0,0,0,0,0,0,0)';
      INPUT_LOAD='(-0.01,0.01)';
      PINUSE='IN';
    'DMI_7_SATA_16_PCIE3_16_TXN':
      PIN_NUMBER='(0,0,F37,0,0,0,0,0,0,0,0)';
      OUTPUT_LOAD='(1.0,-1.0)';
      PINUSE='OUT';
    'DMI_7_SATA_16_PCIE3_16_TXP':
      PIN_NUMBER='(0,0,H37,0,0,0,0,0,0,0,0)';
      OUTPUT_LOAD='(1.0,-1.0)';
      PINUSE='OUT';
    'PHY_PCIE3_RCOMPN':
      PIN_NUMBER='(0,0,AP31,0,0,0,0,0,0,0,0)';
      BIDIRECTIONAL='TRUE';
      INPUT_LOAD='(-0.01,0.01)';
      OUTPUT_LOAD='(1.0,-1.0)';
      PINUSE='BI';
    'PHY_PCIE3_RCOMPP':
      PIN_NUMBER='(0,0,AR29,0,0,0,0,0,0,0,0)';
      BIDIRECTIONAL='TRUE';
      INPUT_LOAD='(-0.01,0.01)';
      OUTPUT_LOAD='(1.0,-1.0)';
      PINUSE='BI';
    'RSVD_N42':
      PIN_NUMBER='(0,0,N42,0,0,0,0,0,0,0,0)';
      OUTPUT_TYPE='(TS,TS)';
      INPUT_LOAD='(-0.01,0.01)';
      OUTPUT_LOAD='(1.0,-1.0)';
      PINUSE='TRI';
    'RSVD_N40':
      PIN_NUMBER='(0,0,N40,0,0,0,0,0,0,0,0)';
      OUTPUT_TYPE='(TS,TS)';
      INPUT_LOAD='(-0.01,0.01)';
      OUTPUT_LOAD='(1.0,-1.0)';
      PINUSE='TRI';
    'RSVD_D39':
      PIN_NUMBER='(0,0,D39,0,0,0,0,0,0,0,0)';
      OUTPUT_TYPE='(TS,TS)';
      INPUT_LOAD='(-0.01,0.01)';
      OUTPUT_LOAD='(1.0,-1.0)';
      PINUSE='TRI';
    'RSVD_C40':
      PIN_NUMBER='(0,0,C40,0,0,0,0,0,0,0,0)';
      OUTPUT_TYPE='(TS,TS)';
      INPUT_LOAD='(-0.01,0.01)';
      OUTPUT_LOAD='(1.0,-1.0)';
      PINUSE='TRI';
    'SATA_0_PCIE3_0_USB3_0_RXN':
      PIN_NUMBER='(0,0,AE41,0,0,0,0,0,0,0,0)';
      INPUT_LOAD='(-0.01,0.01)';
      PINUSE='IN';
    'SATA_0_PCIE3_0_USB3_0_RXP':
      PIN_NUMBER='(0,0,AE43,0,0,0,0,0,0,0,0)';
      INPUT_LOAD='(-0.01,0.01)';
      PINUSE='IN';
    'SATA_0_PCIE3_0_USB3_0_TXN':
      PIN_NUMBER='(0,0,AL32,0,0,0,0,0,0,0,0)';
      OUTPUT_LOAD='(1.0,-1.0)';
      PINUSE='OUT';
    'SATA_0_PCIE3_0_USB3_0_TXP':
      PIN_NUMBER='(0,0,AK31,0,0,0,0,0,0,0,0)';
      OUTPUT_LOAD='(1.0,-1.0)';
      PINUSE='OUT';
    'SATA_10_PCIE3_10_GBE_0_RXN':
      PIN_NUMBER='(0,0,M41,0,0,0,0,0,0,0,0)';
      INPUT_LOAD='(-0.01,0.01)';
      PINUSE='IN';
    'SATA_10_PCIE3_10_GBE_0_RXP':
      PIN_NUMBER='(0,0,M43,0,0,0,0,0,0,0,0)';
      INPUT_LOAD='(-0.01,0.01)';
      PINUSE='IN';
    'SATA_10_PCIE3_10_GBE_0_TXN':
      PIN_NUMBER='(0,0,W36,0,0,0,0,0,0,0,0)';
      OUTPUT_LOAD='(1.0,-1.0)';
      PINUSE='OUT';
    'SATA_10_PCIE3_10_GBE_0_TXP':
      PIN_NUMBER='(0,0,Y37,0,0,0,0,0,0,0,0)';
      OUTPUT_LOAD='(1.0,-1.0)';
      PINUSE='OUT';
    'SATA_11_PCIE3_11_RXN':
      PIN_NUMBER='(0,0,L40,0,0,0,0,0,0,0,0)';
      INPUT_LOAD='(-0.01,0.01)';
      PINUSE='IN';
    'SATA_11_PCIE3_11_RXP':
      PIN_NUMBER='(0,0,L42,0,0,0,0,0,0,0,0)';
      INPUT_LOAD='(-0.01,0.01)';
      PINUSE='IN';
    'SATA_11_PCIE3_11_TXN':
      PIN_NUMBER='(0,0,T37,0,0,0,0,0,0,0,0)';
      OUTPUT_LOAD='(1.0,-1.0)';
      PINUSE='OUT';
    'SATA_11_PCIE3_11_TXP':
      PIN_NUMBER='(0,0,V37,0,0,0,0,0,0,0,0)';
      OUTPUT_LOAD='(1.0,-1.0)';
      PINUSE='OUT';
    'SATA_12_PCIE3_12_GBE_1_RXN':
      PIN_NUMBER='(0,0,K41,0,0,0,0,0,0,0,0)';
      INPUT_LOAD='(-0.01,0.01)';
      PINUSE='IN';
    'SATA_12_PCIE3_12_GBE_1_RXP':
      PIN_NUMBER='(0,0,K43,0,0,0,0,0,0,0,0)';
      INPUT_LOAD='(-0.01,0.01)';
      PINUSE='IN';
    'SATA_12_PCIE3_12_GBE_1_TXN':
      PIN_NUMBER='(0,0,V34,0,0,0,0,0,0,0,0)';
      OUTPUT_LOAD='(1.0,-1.0)';
      PINUSE='OUT';
    'SATA_12_PCIE3_12_GBE_1_TXP':
      PIN_NUMBER='(0,0,U36,0,0,0,0,0,0,0,0)';
      OUTPUT_LOAD='(1.0,-1.0)';
      PINUSE='OUT';
    'SATA_13_PCIE3_13_RXN':
      PIN_NUMBER='(0,0,J40,0,0,0,0,0,0,0,0)';
      INPUT_LOAD='(-0.01,0.01)';
      PINUSE='IN';
    'SATA_13_PCIE3_13_RXP':
      PIN_NUMBER='(0,0,J42,0,0,0,0,0,0,0,0)';
      INPUT_LOAD='(-0.01,0.01)';
      PINUSE='IN';
    'SATA_13_PCIE3_13_TXN':
      PIN_NUMBER='(0,0,U32,0,0,0,0,0,0,0,0)';
      OUTPUT_LOAD='(1.0,-1.0)';
      PINUSE='OUT';
    'SATA_13_PCIE3_13_TXP':
      PIN_NUMBER='(0,0,W32,0,0,0,0,0,0,0,0)';
      OUTPUT_LOAD='(1.0,-1.0)';
      PINUSE='OUT';
    'SATA_14_PCIE3_14_GBE_2_RXN':
      PIN_NUMBER='(0,0,H41,0,0,0,0,0,0,0,0)';
      INPUT_LOAD='(-0.01,0.01)';
      PINUSE='IN';
    'SATA_14_PCIE3_14_GBE_2_RXP':
      PIN_NUMBER='(0,0,H43,0,0,0,0,0,0,0,0)';
      INPUT_LOAD='(-0.01,0.01)';
      PINUSE='IN';
    'SATA_14_PCIE3_14_GBE_2_TXN':
      PIN_NUMBER='(0,0,R32,0,0,0,0,0,0,0,0)';
      OUTPUT_LOAD='(1.0,-1.0)';
      PINUSE='OUT';
    'SATA_14_PCIE3_14_GBE_2_TXP':
      PIN_NUMBER='(0,0,T34,0,0,0,0,0,0,0,0)';
      OUTPUT_LOAD='(1.0,-1.0)';
      PINUSE='OUT';
    'SATA_15_PCIE3_15_RXN':
      PIN_NUMBER='(0,0,G40,0,0,0,0,0,0,0,0)';
      INPUT_LOAD='(-0.01,0.01)';
      PINUSE='IN';
    'SATA_15_PCIE3_15_RXP':
      PIN_NUMBER='(0,0,G42,0,0,0,0,0,0,0,0)';
      INPUT_LOAD='(-0.01,0.01)';
      PINUSE='IN';
    'SATA_15_PCIE3_15_TXN':
      PIN_NUMBER='(0,0,P34,0,0,0,0,0,0,0,0)';
      OUTPUT_LOAD='(1.0,-1.0)';
      PINUSE='OUT';
    'SATA_15_PCIE3_15_TXP':
      PIN_NUMBER='(0,0,N36,0,0,0,0,0,0,0,0)';
      OUTPUT_LOAD='(1.0,-1.0)';
      PINUSE='OUT';
    'SATA_1_PCIE3_1_USB3_1_RXN':
      PIN_NUMBER='(0,0,AD40,0,0,0,0,0,0,0,0)';
      INPUT_LOAD='(-0.01,0.01)';
      PINUSE='IN';
    'SATA_1_PCIE3_1_USB3_1_RXP':
      PIN_NUMBER='(0,0,AD42,0,0,0,0,0,0,0,0)';
      INPUT_LOAD='(-0.01,0.01)';
      PINUSE='IN';
    'SATA_1_PCIE3_1_USB3_1_TXN':
      PIN_NUMBER='(0,0,AN36,0,0,0,0,0,0,0,0)';
      OUTPUT_LOAD='(1.0,-1.0)';
      PINUSE='OUT';
    'SATA_1_PCIE3_1_USB3_1_TXP':
      PIN_NUMBER='(0,0,AP34,0,0,0,0,0,0,0,0)';
      OUTPUT_LOAD='(1.0,-1.0)';
      PINUSE='OUT';
    'SATA_2_PCIE3_2_USB3_2_RXN':
      PIN_NUMBER='(0,0,AC41,0,0,0,0,0,0,0,0)';
      INPUT_LOAD='(-0.01,0.01)';
      PINUSE='IN';
    'SATA_2_PCIE3_2_USB3_2_RXP':
      PIN_NUMBER='(0,0,AC43,0,0,0,0,0,0,0,0)';
      INPUT_LOAD='(-0.01,0.01)';
      PINUSE='IN';
    'SATA_2_PCIE3_2_USB3_2_TXN':
      PIN_NUMBER='(0,0,AR36,0,0,0,0,0,0,0,0)';
      OUTPUT_LOAD='(1.0,-1.0)';
      PINUSE='OUT';
    'SATA_2_PCIE3_2_USB3_2_TXP':
      PIN_NUMBER='(0,0,AT37,0,0,0,0,0,0,0,0)';
      OUTPUT_LOAD='(1.0,-1.0)';
      PINUSE='OUT';
    'SATA_3_PCIE3_3_USB3_3_RXN':
      PIN_NUMBER='(0,0,AB40,0,0,0,0,0,0,0,0)';
      INPUT_LOAD='(-0.01,0.01)';
      PINUSE='IN';
    'SATA_3_PCIE3_3_USB3_3_RXP':
      PIN_NUMBER='(0,0,AB42,0,0,0,0,0,0,0,0)';
      INPUT_LOAD='(-0.01,0.01)';
      PINUSE='IN';
    'SATA_3_PCIE3_3_USB3_3_TXN':
      PIN_NUMBER='(0,0,AK34,0,0,0,0,0,0,0,0)';
      OUTPUT_LOAD='(1.0,-1.0)';
      PINUSE='OUT';
    'SATA_3_PCIE3_3_USB3_3_TXP':
      PIN_NUMBER='(0,0,AM34,0,0,0,0,0,0,0,0)';
      OUTPUT_LOAD='(1.0,-1.0)';
      PINUSE='OUT';
    'SATA_4_PCIE3_4_USB3_4_RXN':
      PIN_NUMBER='(0,0,AA41,0,0,0,0,0,0,0,0)';
      INPUT_LOAD='(-0.01,0.01)';
      PINUSE='IN';
    'SATA_4_PCIE3_4_USB3_4_RXP':
      PIN_NUMBER='(0,0,AA43,0,0,0,0,0,0,0,0)';
      INPUT_LOAD='(-0.01,0.01)';
      PINUSE='IN';
    'SATA_4_PCIE3_4_USB3_4_TXN':
      PIN_NUMBER='(0,0,AL36,0,0,0,0,0,0,0,0)';
      OUTPUT_LOAD='(1.0,-1.0)';
      PINUSE='OUT';
    'SATA_4_PCIE3_4_USB3_4_TXP':
      PIN_NUMBER='(0,0,AM37,0,0,0,0,0,0,0,0)';
      OUTPUT_LOAD='(1.0,-1.0)';
      PINUSE='OUT';
    'SATA_5_PCIE3_5_USB3_5_RXN':
      PIN_NUMBER='(0,0,Y40,0,0,0,0,0,0,0,0)';
      INPUT_LOAD='(-0.01,0.01)';
      PINUSE='IN';
    'SATA_5_PCIE3_5_USB3_5_RXP':
      PIN_NUMBER='(0,0,Y42,0,0,0,0,0,0,0,0)';
      INPUT_LOAD='(-0.01,0.01)';
      PINUSE='IN';
    'SATA_5_PCIE3_5_USB3_5_TXN':
      PIN_NUMBER='(0,0,AH34,0,0,0,0,0,0,0,0)';
      OUTPUT_LOAD='(1.0,-1.0)';
      PINUSE='OUT';
    'SATA_5_PCIE3_5_USB3_5_TXP':
      PIN_NUMBER='(0,0,AJ32,0,0,0,0,0,0,0,0)';
      OUTPUT_LOAD='(1.0,-1.0)';
      PINUSE='OUT';
    'SATA_6_PCIE3_6_USB3_6_RXN':
      PIN_NUMBER='(0,0,W41,0,0,0,0,0,0,0,0)';
      INPUT_LOAD='(-0.01,0.01)';
      PINUSE='IN';
    'SATA_6_PCIE3_6_USB3_6_RXP':
      PIN_NUMBER='(0,0,W43,0,0,0,0,0,0,0,0)';
      INPUT_LOAD='(-0.01,0.01)';
      PINUSE='IN';
    'SATA_6_PCIE3_6_USB3_6_TXN':
      PIN_NUMBER='(0,0,AF37,0,0,0,0,0,0,0,0)';
      OUTPUT_LOAD='(1.0,-1.0)';
      PINUSE='OUT';
    'SATA_6_PCIE3_6_USB3_6_TXP':
      PIN_NUMBER='(0,0,AH37,0,0,0,0,0,0,0,0)';
      OUTPUT_LOAD='(1.0,-1.0)';
      PINUSE='OUT';
    'SATA_7_PCIE3_7_USB3_7_RXN':
      PIN_NUMBER='(0,0,V40,0,0,0,0,0,0,0,0)';
      INPUT_LOAD='(-0.01,0.01)';
      PINUSE='IN';
    'SATA_7_PCIE3_7_USB3_7_RXP':
      PIN_NUMBER='(0,0,V42,0,0,0,0,0,0,0,0)';
      INPUT_LOAD='(-0.01,0.01)';
      PINUSE='IN';
    'SATA_7_PCIE3_7_USB3_7_TXN':
      PIN_NUMBER='(0,0,AF34,0,0,0,0,0,0,0,0)';
      OUTPUT_LOAD='(1.0,-1.0)';
      PINUSE='OUT';
    'SATA_7_PCIE3_7_USB3_7_TXP':
      PIN_NUMBER='(0,0,AG36,0,0,0,0,0,0,0,0)';
      OUTPUT_LOAD='(1.0,-1.0)';
      PINUSE='OUT';
    'SATA_8_PCIE3_8_USB3_8_RXN':
      PIN_NUMBER='(0,0,U41,0,0,0,0,0,0,0,0)';
      INPUT_LOAD='(-0.01,0.01)';
      PINUSE='IN';
    'SATA_8_PCIE3_8_USB3_8_RXP':
      PIN_NUMBER='(0,0,U43,0,0,0,0,0,0,0,0)';
      INPUT_LOAD='(-0.01,0.01)';
      PINUSE='IN';
    'SATA_8_PCIE3_8_USB3_8_TXN':
      PIN_NUMBER='(0,0,AE36,0,0,0,0,0,0,0,0)';
      OUTPUT_LOAD='(1.0,-1.0)';
      PINUSE='OUT';
    'SATA_8_PCIE3_8_USB3_8_TXP':
      PIN_NUMBER='(0,0,AD37,0,0,0,0,0,0,0,0)';
      OUTPUT_LOAD='(1.0,-1.0)';
      PINUSE='OUT';
    'SATA_9_PCIE3_9_USB3_9_RXN':
      PIN_NUMBER='(0,0,R40,0,0,0,0,0,0,0,0)';
      INPUT_LOAD='(-0.01,0.01)';
      PINUSE='IN';
    'SATA_9_PCIE3_9_USB3_9_RXP':
      PIN_NUMBER='(0,0,R42,0,0,0,0,0,0,0,0)';
      INPUT_LOAD='(-0.01,0.01)';
      PINUSE='IN';
    'SATA_9_PCIE3_9_USB3_9_TXN':
      PIN_NUMBER='(0,0,AE32,0,0,0,0,0,0,0,0)';
      OUTPUT_LOAD='(1.0,-1.0)';
      PINUSE='OUT';
    'SATA_9_PCIE3_9_USB3_9_TXP':
      PIN_NUMBER='(0,0,AG32,0,0,0,0,0,0,0,0)';
      OUTPUT_LOAD='(1.0,-1.0)';
      PINUSE='OUT';
    'ACPRESENT':
      PIN_NUMBER='(0,0,0,AN7,0,0,0,0,0,0,0)';
      INPUT_LOAD='(-0.01,0.01)';
      PINUSE='IN';
    'CPUPWRGD':
      PIN_NUMBER='(0,0,0,G10,0,0,0,0,0,0,0)';
      OUTPUT_LOAD='(1.0,-1.0)';
      PINUSE='OUT';
    'CPU_CATERR_N':
      PIN_NUMBER='(0,0,0,F8,0,0,0,0,0,0,0)';
      INPUT_LOAD='(-0.01,0.01)';
      PINUSE='IN';
    'CPU_ERR0_N':
      PIN_NUMBER='(0,0,0,J7,0,0,0,0,0,0,0)';
      INPUT_LOAD='(-0.01,0.01)';
      PINUSE='IN';
    'CPU_ERR1_N':
      PIN_NUMBER='(0,0,0,G7,0,0,0,0,0,0,0)';
      INPUT_LOAD='(-0.01,0.01)';
      PINUSE='IN';
    'CPU_ERR2_N':
      PIN_NUMBER='(0,0,0,L7,0,0,0,0,0,0,0)';
      INPUT_LOAD='(-0.01,0.01)';
      PINUSE='IN';
    'CPU_MEMTRIP_N':
      PIN_NUMBER='(0,0,0,E4,0,0,0,0,0,0,0)';
      INPUT_LOAD='(-0.01,0.01)';
      PINUSE='IN';
    'CPU_MSMI_N':
      PIN_NUMBER='(0,0,0,F11,0,0,0,0,0,0,0)';
      INPUT_LOAD='(-0.01,0.01)';
      PINUSE='IN';
    'CPU_PWR_DEBUG_N':
      PIN_NUMBER='(0,0,0,F5,0,0,0,0,0,0,0)';
      OUTPUT_LOAD='(1.0,-1.0)';
      PINUSE='OUT';
    'CPU_THRMTRIP_N':
      PIN_NUMBER='(0,0,0,F3,0,0,0,0,0,0,0)';
      INPUT_LOAD='(-0.01,0.01)';
      PINUSE='IN';
    'DBG_PMODE':
      PIN_NUMBER='(0,0,0,BE40,0,0,0,0,0,0,0)';
      OUTPUT_LOAD='(1.0,-1.0)';
      PINUSE='OUT';
    'DSW_PWROK':
      PIN_NUMBER='(0,0,0,BE8,0,0,0,0,0,0,0)';
      INPUT_LOAD='(-0.01,0.01)';
      PINUSE='IN';
    'GPP_O_0':
      PIN_NUMBER='(0,0,0,AN10,0,0,0,0,0,0,0)';
      BIDIRECTIONAL='TRUE';
      INPUT_LOAD='(-0.01,0.01)';
      OUTPUT_LOAD='(1.0,-1.0)';
      PINUSE='BI';
    'GPP_O_7':
      PIN_NUMBER='(0,0,0,AU10,0,0,0,0,0,0,0)';
      BIDIRECTIONAL='TRUE';
      INPUT_LOAD='(-0.01,0.01)';
      OUTPUT_LOAD='(1.0,-1.0)';
      PINUSE='BI';
    'INTRUDER_N':
      PIN_NUMBER='(0,0,0,BG8,0,0,0,0,0,0,0)';
      INPUT_LOAD='(-0.01,0.01)';
      PINUSE='IN';
    'JTAGX':
      PIN_NUMBER='(0,0,0,BD35,0,0,0,0,0,0,0)';
      BIDIRECTIONAL='TRUE';
      INPUT_LOAD='(-0.01,0.01)';
      OUTPUT_LOAD='(1.0,-1.0)';
      PINUSE='BI';
    'JTAG_TCK':
      PIN_NUMBER='(0,0,0,BF35,0,0,0,0,0,0,0)';
      BIDIRECTIONAL='TRUE';
      INPUT_LOAD='(-0.01,0.01)';
      OUTPUT_LOAD='(1.0,-1.0)';
      PINUSE='BI';
    'JTAG_TDI':
      PIN_NUMBER='(0,0,0,BE38,0,0,0,0,0,0,0)';
      BIDIRECTIONAL='TRUE';
      INPUT_LOAD='(-0.01,0.01)';
      OUTPUT_LOAD='(1.0,-1.0)';
      PINUSE='BI';
    'JTAG_TDO':
      PIN_NUMBER='(0,0,0,BE36,0,0,0,0,0,0,0)';
      OUTPUT_LOAD='(1.0,-1.0)';
      PINUSE='OUT';
    'JTAG_TMS':
      PIN_NUMBER='(0,0,0,BD37,0,0,0,0,0,0,0)';
      BIDIRECTIONAL='TRUE';
      INPUT_LOAD='(-0.01,0.01)';
      OUTPUT_LOAD='(1.0,-1.0)';
      PINUSE='BI';
    'LANPHYPC':
      PIN_NUMBER='(0,0,0,AJ7,0,0,0,0,0,0,0)';
      OUTPUT_LOAD='(1.0,-1.0)';
      PINUSE='OUT';
    'LAN_WAKE_N':
      PIN_NUMBER='(0,0,0,AU7,0,0,0,0,0,0,0)';
      INPUT_LOAD='(-0.01,0.01)';
      PINUSE='IN';
    'ME_PECI':
      PIN_NUMBER='(0,0,0,J10,0,0,0,0,0,0,0)';
      BIDIRECTIONAL='TRUE';
      INPUT_LOAD='(-0.01,0.01)';
      OUTPUT_LOAD='(1.0,-1.0)';
      PINUSE='BI';
    'PCH_PWROK':
      PIN_NUMBER='(0,0,0,BE4,0,0,0,0,0,0,0)';
      INPUT_LOAD='(-0.01,0.01)';
      PINUSE='IN';
    'PLTRST_CPU_N':
      PIN_NUMBER='(0,0,0,M8,0,0,0,0,0,0,0)';
      OUTPUT_LOAD='(1.0,-1.0)';
      PINUSE='OUT';
    'PRDY_N':
      PIN_NUMBER='(0,0,0,BB37,0,0,0,0,0,0,0)';
      BIDIRECTIONAL='TRUE';
      INPUT_LOAD='(-0.01,0.01)';
      OUTPUT_LOAD='(1.0,-1.0)';
      PINUSE='BI';
    'PREQ_N':
      PIN_NUMBER='(0,0,0,BF37,0,0,0,0,0,0,0)';
      BIDIRECTIONAL='TRUE';
      INPUT_LOAD='(-0.01,0.01)';
      OUTPUT_LOAD='(1.0,-1.0)';
      PINUSE='BI';
    'PWRBTN_N':
      PIN_NUMBER='(0,0,0,AR10,0,0,0,0,0,0,0)';
      INPUT_LOAD='(-0.01,0.01)';
      PINUSE='IN';
    'RSMRST_N':
      PIN_NUMBER='(0,0,0,BD9,0,0,0,0,0,0,0)';
      INPUT_LOAD='(-0.01,0.01)';
      PINUSE='IN';
    'RSVD_BG36':
      PIN_NUMBER='(0,0,0,BG36,0,0,0,0,0,0,0)';
      OUTPUT_TYPE='(TS,TS)';
      INPUT_LOAD='(-0.01,0.01)';
      OUTPUT_LOAD='(1.0,-1.0)';
      PINUSE='TRI';
    'RSVD_BF39':
      PIN_NUMBER='(0,0,0,BF39,0,0,0,0,0,0,0)';
      OUTPUT_TYPE='(TS,TS)';
      INPUT_LOAD='(-0.01,0.01)';
      OUTPUT_LOAD='(1.0,-1.0)';
      PINUSE='TRI';
    'RSVD_AV21':
      PIN_NUMBER='(0,0,0,AV21,0,0,0,0,0,0,0)';
      OUTPUT_TYPE='(TS,TS)';
      INPUT_LOAD='(-0.01,0.01)';
      OUTPUT_LOAD='(1.0,-1.0)';
      PINUSE='TRI';
    'RSVD_AW23':
      PIN_NUMBER='(0,0,0,AW26,0,0,0,0,0,0,0)';
      OUTPUT_TYPE='(TS,TS)';
      INPUT_LOAD='(-0.01,0.01)';
      OUTPUT_LOAD='(1.0,-1.0)';
      PINUSE='TRI';
    'SLP_A_N':
      PIN_NUMBER='(0,0,0,AM11,0,0,0,0,0,0,0)';
      OUTPUT_LOAD='(1.0,-1.0)';
      PINUSE='OUT';
    'SLP_LAN_N':
      PIN_NUMBER='(0,0,0,AK8,0,0,0,0,0,0,0)';
      OUTPUT_LOAD='(1.0,-1.0)';
      PINUSE='OUT';
    'SLP_S3_N':
      PIN_NUMBER='(0,0,0,AP8,0,0,0,0,0,0,0)';
      OUTPUT_LOAD='(1.0,-1.0)';
      PINUSE='OUT';
    'SLP_S4_N':
      PIN_NUMBER='(0,0,0,AL13,0,0,0,0,0,0,0)';
      OUTPUT_LOAD='(1.0,-1.0)';
      PINUSE='OUT';
    'SLP_S5_N':
      PIN_NUMBER='(0,0,0,AJ13,0,0,0,0,0,0,0)';
      OUTPUT_LOAD='(1.0,-1.0)';
      PINUSE='OUT';
    'SLP_SUS_N':
      PIN_NUMBER='(0,0,0,AL7,0,0,0,0,0,0,0)';
      OUTPUT_LOAD='(1.0,-1.0)';
      PINUSE='OUT';
    'SUSCLK':
      PIN_NUMBER='(0,0,0,AR7,0,0,0,0,0,0,0)';
      OUTPUT_LOAD='(1.0,-1.0)';
      PINUSE='OUT';
    'SYS_PWROK':
      PIN_NUMBER='(0,0,0,AL10,0,0,0,0,0,0,0)';
      INPUT_LOAD='(-0.01,0.01)';
      PINUSE='IN';
    'SYS_RESET_N':
      PIN_NUMBER='(0,0,0,AJ10,0,0,0,0,0,0,0)';
      INPUT_LOAD='(-0.01,0.01)';
      PINUSE='IN';
    'TRIGGER0_N':
      PIN_NUMBER='(0,0,0,H11,0,0,0,0,0,0,0)';
      BIDIRECTIONAL='TRUE';
      INPUT_LOAD='(-0.01,0.01)';
      OUTPUT_LOAD='(1.0,-1.0)';
      PINUSE='BI';
    'TRIGGER1_N':
      PIN_NUMBER='(0,0,0,K8,0,0,0,0,0,0,0)';
      BIDIRECTIONAL='TRUE';
      INPUT_LOAD='(-0.01,0.01)';
      OUTPUT_LOAD='(1.0,-1.0)';
      PINUSE='BI';
    'WAKE_N':
      PIN_NUMBER='(0,0,0,AH11,0,0,0,0,0,0,0)';
      INPUT_LOAD='(-0.01,0.01)';
      PINUSE='IN';
    'GPPC_B_18_HS_UART1_RTS_N':
      PIN_NUMBER='(0,0,0,0,BD25,0,0,0,0,0,0)';
      BIDIRECTIONAL='TRUE';
      INPUT_LOAD='(-0.01,0.01)';
      OUTPUT_LOAD='(1.0,-1.0)';
      PINUSE='BI';
    'GPPC_A_0_ESPI_ALERT0_N':
      PIN_NUMBER='(0,0,0,0,BG20,0,0,0,0,0,0)';
      BIDIRECTIONAL='TRUE';
      INPUT_LOAD='(-0.01,0.01)';
      OUTPUT_LOAD='(1.0,-1.0)';
      PINUSE='BI';
    'GPPC_A_10_SRCCLKREQ_N_0':
      PIN_NUMBER='(0,0,0,0,BD17,0,0,0,0,0,0)';
      BIDIRECTIONAL='TRUE';
      INPUT_LOAD='(-0.01,0.01)';
      OUTPUT_LOAD='(1.0,-1.0)';
      PINUSE='BI';
    'GPPC_A_11_SRCCLKREQ_N_1':
      PIN_NUMBER='(0,0,0,0,BG18,0,0,0,0,0,0)';
      BIDIRECTIONAL='TRUE';
      INPUT_LOAD='(-0.01,0.01)';
      OUTPUT_LOAD='(1.0,-1.0)';
      PINUSE='BI';
    'GPPC_A_12_SRCCLKREQ_N_2':
      PIN_NUMBER='(0,0,0,0,BG16,0,0,0,0,0,0)';
      BIDIRECTIONAL='TRUE';
      INPUT_LOAD='(-0.01,0.01)';
      OUTPUT_LOAD='(1.0,-1.0)';
      PINUSE='BI';
    'GPPC_A_13_SRCCLKREQ_N_3':
      PIN_NUMBER='(0,0,0,0,BF15,0,0,0,0,0,0)';
      BIDIRECTIONAL='TRUE';
      INPUT_LOAD='(-0.01,0.01)';
      OUTPUT_LOAD='(1.0,-1.0)';
      PINUSE='BI';
    'GPPC_A_14_SRCCLKREQ_N_4':
      PIN_NUMBER='(0,0,0,0,BE12,0,0,0,0,0,0)';
      BIDIRECTIONAL='TRUE';
      INPUT_LOAD='(-0.01,0.01)';
      OUTPUT_LOAD='(1.0,-1.0)';
      PINUSE='BI';
    'GPPC_A_15_SRCCLKREQ_N_5':
      PIN_NUMBER='(0,0,0,0,BE14,0,0,0,0,0,0)';
      BIDIRECTIONAL='TRUE';
      INPUT_LOAD='(-0.01,0.01)';
      OUTPUT_LOAD='(1.0,-1.0)';
      PINUSE='BI';
    'GPPC_A_16_SRCCLKREQ_N_6':
      PIN_NUMBER='(0,0,0,0,BD11,0,0,0,0,0,0)';
      BIDIRECTIONAL='TRUE';
      INPUT_LOAD='(-0.01,0.01)';
      OUTPUT_LOAD='(1.0,-1.0)';
      PINUSE='BI';
    'GPPC_A_17_SRCCLKREQ_N_7':
      PIN_NUMBER='(0,0,0,0,BF13,0,0,0,0,0,0)';
      BIDIRECTIONAL='TRUE';
      INPUT_LOAD='(-0.01,0.01)';
      OUTPUT_LOAD='(1.0,-1.0)';
      PINUSE='BI';
    'GPPC_A_18_SRCCLKREQ_N_8':
      PIN_NUMBER='(0,0,0,0,BF11,0,0,0,0,0,0)';
      BIDIRECTIONAL='TRUE';
      INPUT_LOAD='(-0.01,0.01)';
      OUTPUT_LOAD='(1.0,-1.0)';
      PINUSE='BI';
    'GPPC_A_19_SRCCLKREQ_N_9':
      PIN_NUMBER='(0,0,0,0,BG14,0,0,0,0,0,0)';
      BIDIRECTIONAL='TRUE';
      INPUT_LOAD='(-0.01,0.01)';
      OUTPUT_LOAD='(1.0,-1.0)';
      PINUSE='BI';
    'GPPC_A_1_ESPI_ALERT1_N':
      PIN_NUMBER='(0,0,0,0,BD15,0,0,0,0,0,0)';
      BIDIRECTIONAL='TRUE';
      INPUT_LOAD='(-0.01,0.01)';
      OUTPUT_LOAD='(1.0,-1.0)';
      PINUSE='BI';
    'GPPC_A_2_ESPI_IO_0':
      PIN_NUMBER='(0,0,0,0,BG12,0,0,0,0,0,0)';
      BIDIRECTIONAL='TRUE';
      INPUT_LOAD='(-0.01,0.01)';
      OUTPUT_LOAD='(1.0,-1.0)';
      PINUSE='BI';
    'GPPC_A_3_ESPI_IO_1':
      PIN_NUMBER='(0,0,0,0,BF19,0,0,0,0,0,0)';
      BIDIRECTIONAL='TRUE';
      INPUT_LOAD='(-0.01,0.01)';
      OUTPUT_LOAD='(1.0,-1.0)';
      PINUSE='BI';
    'GPPC_A_4_ESPI_IO_2':
      PIN_NUMBER='(0,0,0,0,BE18,0,0,0,0,0,0)';
      BIDIRECTIONAL='TRUE';
      INPUT_LOAD='(-0.01,0.01)';
      OUTPUT_LOAD='(1.0,-1.0)';
      PINUSE='BI';
    'GPPC_A_5_ESPI_IO_3':
      PIN_NUMBER='(0,0,0,0,BD19,0,0,0,0,0,0)';
      BIDIRECTIONAL='TRUE';
      INPUT_LOAD='(-0.01,0.01)';
      OUTPUT_LOAD='(1.0,-1.0)';
      PINUSE='BI';
    'GPPC_A_6_ESPI_CS0_N':
      PIN_NUMBER='(0,0,0,0,BE20,0,0,0,0,0,0)';
      BIDIRECTIONAL='TRUE';
      INPUT_LOAD='(-0.01,0.01)';
      OUTPUT_LOAD='(1.0,-1.0)';
      PINUSE='BI';
    'GPPC_A_7_ESPI_CS1_N':
      PIN_NUMBER='(0,0,0,0,BE16,0,0,0,0,0,0)';
      BIDIRECTIONAL='TRUE';
      INPUT_LOAD='(-0.01,0.01)';
      OUTPUT_LOAD='(1.0,-1.0)';
      PINUSE='BI';
    'GPPC_A_8_ESPI_RESET_N':
      PIN_NUMBER='(0,0,0,0,BF17,0,0,0,0,0,0)';
      BIDIRECTIONAL='TRUE';
      INPUT_LOAD='(-0.01,0.01)';
      OUTPUT_LOAD='(1.0,-1.0)';
      PINUSE='BI';
    'GPPC_A_9_ESPI_CLK':
      PIN_NUMBER='(0,0,0,0,BD13,0,0,0,0,0,0)';
      BIDIRECTIONAL='TRUE';
      INPUT_LOAD='(-0.01,0.01)';
      OUTPUT_LOAD='(1.0,-1.0)';
      PINUSE='BI';
    'GPPC_B_0_GSXDOUT':
      PIN_NUMBER='(0,0,0,0,BD33,0,0,0,0,0,0)';
      BIDIRECTIONAL='TRUE';
      INPUT_LOAD='(-0.01,0.01)';
      OUTPUT_LOAD='(1.0,-1.0)';
      PINUSE='BI';
    'GPPC_B_10_USB2_OCB_5':
      PIN_NUMBER='(0,0,0,0,BG24,0,0,0,0,0,0)';
      BIDIRECTIONAL='TRUE';
      INPUT_LOAD='(-0.01,0.01)';
      OUTPUT_LOAD='(1.0,-1.0)';
      PINUSE='BI';
    'GPPC_B_11_USB2_OCB_6':
      PIN_NUMBER='(0,0,0,0,BG22,0,0,0,0,0,0)';
      BIDIRECTIONAL='TRUE';
      INPUT_LOAD='(-0.01,0.01)';
      OUTPUT_LOAD='(1.0,-1.0)';
      PINUSE='BI';
    'GPPC_B_12_HS_UART0_RXD':
      PIN_NUMBER='(0,0,0,0,BD29,0,0,0,0,0,0)';
      BIDIRECTIONAL='TRUE';
      INPUT_LOAD='(-0.01,0.01)';
      OUTPUT_LOAD='(1.0,-1.0)';
      PINUSE='BI';
    'GPPC_B_13_HS_UART0_TXD':
      PIN_NUMBER='(0,0,0,0,BE28,0,0,0,0,0,0)';
      BIDIRECTIONAL='TRUE';
      INPUT_LOAD='(-0.01,0.01)';
      OUTPUT_LOAD='(1.0,-1.0)';
      PINUSE='BI';
    'GPPC_B_14_HS_UART0_RTS_N':
      PIN_NUMBER='(0,0,0,0,BF29,0,0,0,0,0,0)';
      BIDIRECTIONAL='TRUE';
      INPUT_LOAD='(-0.01,0.01)';
      OUTPUT_LOAD='(1.0,-1.0)';
      PINUSE='BI';
    'GPPC_B_15_HS_UART0_CTS_N':
      PIN_NUMBER='(0,0,0,0,BD27,0,0,0,0,0,0)';
      BIDIRECTIONAL='TRUE';
      INPUT_LOAD='(-0.01,0.01)';
      OUTPUT_LOAD='(1.0,-1.0)';
      PINUSE='BI';
    'GPPC_B_16_HS_UART1_RXD':
      PIN_NUMBER='(0,0,0,0,BE26,0,0,0,0,0,0)';
      BIDIRECTIONAL='TRUE';
      INPUT_LOAD='(-0.01,0.01)';
      OUTPUT_LOAD='(1.0,-1.0)';
      PINUSE='BI';
    'GPPC_B_17_HS_UART1_TXD':
      PIN_NUMBER='(0,0,0,0,BF27,0,0,0,0,0,0)';
      BIDIRECTIONAL='TRUE';
      INPUT_LOAD='(-0.01,0.01)';
      OUTPUT_LOAD='(1.0,-1.0)';
      PINUSE='BI';
    'GPPC_B_19_HS_UART1_CTS_N':
      PIN_NUMBER='(0,0,0,0,BF25,0,0,0,0,0,0)';
      BIDIRECTIONAL='TRUE';
      INPUT_LOAD='(-0.01,0.01)';
      OUTPUT_LOAD='(1.0,-1.0)';
      PINUSE='BI';
    'GPPC_B_1_GSXSLOAD':
      PIN_NUMBER='(0,0,0,0,BE32,0,0,0,0,0,0)';
      BIDIRECTIONAL='TRUE';
      INPUT_LOAD='(-0.01,0.01)';
      OUTPUT_LOAD='(1.0,-1.0)';
      PINUSE='BI';
    'GPPC_B_20':
      PIN_NUMBER='(0,0,0,0,BE24,0,0,0,0,0,0)';
      BIDIRECTIONAL='TRUE';
      INPUT_LOAD='(-0.01,0.01)';
      OUTPUT_LOAD='(1.0,-1.0)';
      PINUSE='BI';
    'GPPC_B_21':
      PIN_NUMBER='(0,0,0,0,BF23,0,0,0,0,0,0)';
      BIDIRECTIONAL='TRUE';
      INPUT_LOAD='(-0.01,0.01)';
      OUTPUT_LOAD='(1.0,-1.0)';
      PINUSE='BI';
    'GPPC_B_22':
      PIN_NUMBER='(0,0,0,0,BE22,0,0,0,0,0,0)';
      BIDIRECTIONAL='TRUE';
      INPUT_LOAD='(-0.01,0.01)';
      OUTPUT_LOAD='(1.0,-1.0)';
      PINUSE='BI';
    'GPPC_B_23':
      PIN_NUMBER='(0,0,0,0,BD23,0,0,0,0,0,0)';
      BIDIRECTIONAL='TRUE';
      INPUT_LOAD='(-0.01,0.01)';
      OUTPUT_LOAD='(1.0,-1.0)';
      PINUSE='BI';
    'GPPC_B_2_GSXDIN':
      PIN_NUMBER='(0,0,0,0,BF33,0,0,0,0,0,0)';
      BIDIRECTIONAL='TRUE';
      INPUT_LOAD='(-0.01,0.01)';
      OUTPUT_LOAD='(1.0,-1.0)';
      PINUSE='BI';
    'GPPC_B_3_GSXRESET_N':
      PIN_NUMBER='(0,0,0,0,BD31,0,0,0,0,0,0)';
      BIDIRECTIONAL='TRUE';
      INPUT_LOAD='(-0.01,0.01)';
      OUTPUT_LOAD='(1.0,-1.0)';
      PINUSE='BI';
    'GPPC_B_4_GSXCLK':
      PIN_NUMBER='(0,0,0,0,BE30,0,0,0,0,0,0)';
      BIDIRECTIONAL='TRUE';
      INPUT_LOAD='(-0.01,0.01)';
      OUTPUT_LOAD='(1.0,-1.0)';
      PINUSE='BI';
    'GPPC_B_5_USB2_OCB_0':
      PIN_NUMBER='(0,0,0,0,BF31,0,0,0,0,0,0)';
      BIDIRECTIONAL='TRUE';
      INPUT_LOAD='(-0.01,0.01)';
      OUTPUT_LOAD='(1.0,-1.0)';
      PINUSE='BI';
    'GPPC_B_6_USB2_OCB_1':
      PIN_NUMBER='(0,0,0,0,BG32,0,0,0,0,0,0)';
      BIDIRECTIONAL='TRUE';
      INPUT_LOAD='(-0.01,0.01)';
      OUTPUT_LOAD='(1.0,-1.0)';
      PINUSE='BI';
    'GPPC_B_7_USB2_OCB_2':
      PIN_NUMBER='(0,0,0,0,BG30,0,0,0,0,0,0)';
      BIDIRECTIONAL='TRUE';
      INPUT_LOAD='(-0.01,0.01)';
      OUTPUT_LOAD='(1.0,-1.0)';
      PINUSE='BI';
    'GPPC_B_8_USB2_OCB_3':
      PIN_NUMBER='(0,0,0,0,BG28,0,0,0,0,0,0)';
      BIDIRECTIONAL='TRUE';
      INPUT_LOAD='(-0.01,0.01)';
      OUTPUT_LOAD='(1.0,-1.0)';
      PINUSE='BI';
    'GPPC_B_9_USB2_OCB_4':
      PIN_NUMBER='(0,0,0,0,BG26,0,0,0,0,0,0)';
      BIDIRECTIONAL='TRUE';
      INPUT_LOAD='(-0.01,0.01)';
      OUTPUT_LOAD='(1.0,-1.0)';
      PINUSE='BI';
    'GPPC_C_0_ME_SML0CLK':
      PIN_NUMBER='(0,0,0,0,BC4,0,0,0,0,0,0)';
      BIDIRECTIONAL='TRUE';
      INPUT_LOAD='(-0.01,0.01)';
      OUTPUT_LOAD='(1.0,-1.0)';
      PINUSE='BI';
    'GPPC_C_10_ME_SML2DATA':
      PIN_NUMBER='(0,0,0,0,AP3,0,0,0,0,0,0)';
      BIDIRECTIONAL='TRUE';
      INPUT_LOAD='(-0.01,0.01)';
      OUTPUT_LOAD='(1.0,-1.0)';
      PINUSE='BI';
    'GPPC_C_11_ME_SML2ALERT_N':
      PIN_NUMBER='(0,0,0,0,AV3,0,0,0,0,0,0)';
      BIDIRECTIONAL='TRUE';
      INPUT_LOAD='(-0.01,0.01)';
      OUTPUT_LOAD='(1.0,-1.0)';
      PINUSE='BI';
    'GPPC_C_12_ME_SML3CLK':
      PIN_NUMBER='(0,0,0,0,AN4,0,0,0,0,0,0)';
      BIDIRECTIONAL='TRUE';
      INPUT_LOAD='(-0.01,0.01)';
      OUTPUT_LOAD='(1.0,-1.0)';
      PINUSE='BI';
    'GPPC_C_13_ME_SML3DATA':
      PIN_NUMBER='(0,0,0,0,AY1,0,0,0,0,0,0)';
      BIDIRECTIONAL='TRUE';
      INPUT_LOAD='(-0.01,0.01)';
      OUTPUT_LOAD='(1.0,-1.0)';
      PINUSE='BI';
    'GPPC_C_14_ME_SML3ALERT_N':
      PIN_NUMBER='(0,0,0,0,AW2,0,0,0,0,0,0)';
      BIDIRECTIONAL='TRUE';
      INPUT_LOAD='(-0.01,0.01)';
      OUTPUT_LOAD='(1.0,-1.0)';
      PINUSE='BI';
    'GPPC_C_15_ME_SML4CLK':
      PIN_NUMBER='(0,0,0,0,BA2,0,0,0,0,0,0)';
      BIDIRECTIONAL='TRUE';
      INPUT_LOAD='(-0.01,0.01)';
      OUTPUT_LOAD='(1.0,-1.0)';
      PINUSE='BI';
    'GPPC_C_16_ME_SML4DATA':
      PIN_NUMBER='(0,0,0,0,AV1,0,0,0,0,0,0)';
      BIDIRECTIONAL='TRUE';
      INPUT_LOAD='(-0.01,0.01)';
      OUTPUT_LOAD='(1.0,-1.0)';
      PINUSE='BI';
    'GPPC_C_17_ME_SML4ALERT_N':
      PIN_NUMBER='(0,0,0,0,AL3,0,0,0,0,0,0)';
      BIDIRECTIONAL='TRUE';
      INPUT_LOAD='(-0.01,0.01)';
      OUTPUT_LOAD='(1.0,-1.0)';
      PINUSE='BI';
    'GPPC_C_18':
      PIN_NUMBER='(0,0,0,0,AL5,0,0,0,0,0,0)';
      BIDIRECTIONAL='TRUE';
      INPUT_LOAD='(-0.01,0.01)';
      OUTPUT_LOAD='(1.0,-1.0)';
      PINUSE='BI';
    'GPPC_C_19_MC_SMBCLK':
      PIN_NUMBER='(0,0,0,0,AL1,0,0,0,0,0,0)';
      BIDIRECTIONAL='TRUE';
      INPUT_LOAD='(-0.01,0.01)';
      OUTPUT_LOAD='(1.0,-1.0)';
      PINUSE='BI';
    'GPPC_C_1_ME_SML0DATA':
      PIN_NUMBER='(0,0,0,0,BA4,0,0,0,0,0,0)';
      BIDIRECTIONAL='TRUE';
      INPUT_LOAD='(-0.01,0.01)';
      OUTPUT_LOAD='(1.0,-1.0)';
      PINUSE='BI';
    'GPPC_C_20_MC_SMBDATA':
      PIN_NUMBER='(0,0,0,0,AT1,0,0,0,0,0,0)';
      BIDIRECTIONAL='TRUE';
      INPUT_LOAD='(-0.01,0.01)';
      OUTPUT_LOAD='(1.0,-1.0)';
      PINUSE='BI';
    'GPPC_C_21_MC_SMBALERT_N':
      PIN_NUMBER='(0,0,0,0,AN2,0,0,0,0,0,0)';
      BIDIRECTIONAL='TRUE';
      INPUT_LOAD='(-0.01,0.01)';
      OUTPUT_LOAD='(1.0,-1.0)';
      PINUSE='BI';
    'GPPC_C_2_ME_SML0ALERT_N':
      PIN_NUMBER='(0,0,0,0,AU2,0,0,0,0,0,0)';
      BIDIRECTIONAL='TRUE';
      INPUT_LOAD='(-0.01,0.01)';
      OUTPUT_LOAD='(1.0,-1.0)';
      PINUSE='BI';
    'GPPC_C_3_ME_SML0BDATA':
      PIN_NUMBER='(0,0,0,0,AU4,0,0,0,0,0,0)';
      BIDIRECTIONAL='TRUE';
      INPUT_LOAD='(-0.01,0.01)';
      OUTPUT_LOAD='(1.0,-1.0)';
      PINUSE='BI';
    'GPPC_C_4_ME_SML0BCLK':
      PIN_NUMBER='(0,0,0,0,BB3,0,0,0,0,0,0)';
      BIDIRECTIONAL='TRUE';
      INPUT_LOAD='(-0.01,0.01)';
      OUTPUT_LOAD='(1.0,-1.0)';
      PINUSE='BI';
    'GPPC_C_5_ME_SML0BALERT_N':
      PIN_NUMBER='(0,0,0,0,AT3,0,0,0,0,0,0)';
      BIDIRECTIONAL='TRUE';
      INPUT_LOAD='(-0.01,0.01)';
      OUTPUT_LOAD='(1.0,-1.0)';
      PINUSE='BI';
    'GPPC_C_6_ME_SML1CLK':
      PIN_NUMBER='(0,0,0,0,AP1,0,0,0,0,0,0)';
      BIDIRECTIONAL='TRUE';
      INPUT_LOAD='(-0.01,0.01)';
      OUTPUT_LOAD='(1.0,-1.0)';
      PINUSE='BI';
    'GPPC_C_7_ME_SML1DATA':
      PIN_NUMBER='(0,0,0,0,AW4,0,0,0,0,0,0)';
      BIDIRECTIONAL='TRUE';
      INPUT_LOAD='(-0.01,0.01)';
      OUTPUT_LOAD='(1.0,-1.0)';
      PINUSE='BI';
    'GPPC_C_8_ME_SML1ALERT_N':
      PIN_NUMBER='(0,0,0,0,AR4,0,0,0,0,0,0)';
      BIDIRECTIONAL='TRUE';
      INPUT_LOAD='(-0.01,0.01)';
      OUTPUT_LOAD='(1.0,-1.0)';
      PINUSE='BI';
    'GPPC_C_9_ME_SML2CLK':
      PIN_NUMBER='(0,0,0,0,AR2,0,0,0,0,0,0)';
      BIDIRECTIONAL='TRUE';
      INPUT_LOAD='(-0.01,0.01)';
      OUTPUT_LOAD='(1.0,-1.0)';
      PINUSE='BI';
    'GPP_D_0_HS_SMBCLK_DMA_SMBCLK':
      PIN_NUMBER='(0,0,0,0,AF2,0,0,0,0,0,0)';
      BIDIRECTIONAL='TRUE';
      INPUT_LOAD='(-0.01,0.01)';
      OUTPUT_LOAD='(1.0,-1.0)';
      PINUSE='BI';
    'GPP_D_10_BM_BUSY_N_SX_EXIT_HOLDOFF_N':
      PIN_NUMBER='(0,0,0,0,AB2,0,0,0,0,0,0)';
      BIDIRECTIONAL='TRUE';
      INPUT_LOAD='(-0.01,0.01)';
      OUTPUT_LOAD='(1.0,-1.0)';
      PINUSE='BI';
    'GPP_D_11_PLTRST_N':
      PIN_NUMBER='(0,0,0,0,AB4,0,0,0,0,0,0)';
      BIDIRECTIONAL='TRUE';
      INPUT_LOAD='(-0.01,0.01)';
      OUTPUT_LOAD='(1.0,-1.0)';
      PINUSE='BI';
    'GPP_D_12_PCHHOT_N':
      PIN_NUMBER='(0,0,0,0,AH2,0,0,0,0,0,0)';
      BIDIRECTIONAL='TRUE';
      INPUT_LOAD='(-0.01,0.01)';
      OUTPUT_LOAD='(1.0,-1.0)';
      PINUSE='BI';
    'GPP_D_13_ADR_COMPLETE':
      PIN_NUMBER='(0,0,0,0,AC1,0,0,0,0,0,0)';
      BIDIRECTIONAL='TRUE';
      INPUT_LOAD='(-0.01,0.01)';
      OUTPUT_LOAD='(1.0,-1.0)';
      PINUSE='BI';
    'GPP_D_14_ADR_TRIGGER_N':
      PIN_NUMBER='(0,0,0,0,AH4,0,0,0,0,0,0)';
      BIDIRECTIONAL='TRUE';
      INPUT_LOAD='(-0.01,0.01)';
      OUTPUT_LOAD='(1.0,-1.0)';
      PINUSE='BI';
    'GPP_D_15_VRALERT_N':
      PIN_NUMBER='(0,0,0,0,AC3,0,0,0,0,0,0)';
      BIDIRECTIONAL='TRUE';
      INPUT_LOAD='(-0.01,0.01)';
      OUTPUT_LOAD='(1.0,-1.0)';
      PINUSE='BI';
    'GPP_D_16_ADR_ACK':
      PIN_NUMBER='(0,0,0,0,AD4,0,0,0,0,0,0)';
      BIDIRECTIONAL='TRUE';
      INPUT_LOAD='(-0.01,0.01)';
      OUTPUT_LOAD='(1.0,-1.0)';
      PINUSE='BI';
    'GPP_D_17_THERMTRIP_N':
      PIN_NUMBER='(0,0,0,0,Y2,0,0,0,0,0,0)';
      BIDIRECTIONAL='TRUE';
      INPUT_LOAD='(-0.01,0.01)';
      OUTPUT_LOAD='(1.0,-1.0)';
      PINUSE='BI';
    'GPP_D_18_MEMTRIP_N':
      PIN_NUMBER='(0,0,0,0,AF4,0,0,0,0,0,0)';
      BIDIRECTIONAL='TRUE';
      INPUT_LOAD='(-0.01,0.01)';
      OUTPUT_LOAD='(1.0,-1.0)';
      PINUSE='BI';
    'GPP_D_19_MSMI_N':
      PIN_NUMBER='(0,0,0,0,Y4,0,0,0,0,0,0)';
      BIDIRECTIONAL='TRUE';
      INPUT_LOAD='(-0.01,0.01)';
      OUTPUT_LOAD='(1.0,-1.0)';
      PINUSE='BI';
    'GPP_D_1_HS_SMBDATA_DMA_SMBDATA':
      PIN_NUMBER='(0,0,0,0,AE1,0,0,0,0,0,0)';
      BIDIRECTIONAL='TRUE';
      INPUT_LOAD='(-0.01,0.01)';
      OUTPUT_LOAD='(1.0,-1.0)';
      PINUSE='BI';
    'GPP_D_20_CATERR_N':
      PIN_NUMBER='(0,0,0,0,AG3,0,0,0,0,0,0)';
      BIDIRECTIONAL='TRUE';
      INPUT_LOAD='(-0.01,0.01)';
      OUTPUT_LOAD='(1.0,-1.0)';
      PINUSE='BI';
    'GPP_D_21_GLB_RST_WARN_N':
      PIN_NUMBER='(0,0,0,0,AA1,0,0,0,0,0,0)';
      BIDIRECTIONAL='TRUE';
      INPUT_LOAD='(-0.01,0.01)';
      OUTPUT_LOAD='(1.0,-1.0)';
      PINUSE='BI';
    'GPP_D_22_USB2_OCB_7':
      PIN_NUMBER='(0,0,0,0,AA3,0,0,0,0,0,0)';
      BIDIRECTIONAL='TRUE';
      INPUT_LOAD='(-0.01,0.01)';
      OUTPUT_LOAD='(1.0,-1.0)';
      PINUSE='BI';
    'GPP_D_23':
      PIN_NUMBER='(0,0,0,0,W1,0,0,0,0,0,0)';
      BIDIRECTIONAL='TRUE';
      INPUT_LOAD='(-0.01,0.01)';
      OUTPUT_LOAD='(1.0,-1.0)';
      PINUSE='BI';
    'GPP_D_2_HS_SMBALERT_N_DMA_SMBALERT_N':
      PIN_NUMBER='(0,0,0,0,AD2,0,0,0,0,0,0)';
      BIDIRECTIONAL='TRUE';
      INPUT_LOAD='(-0.01,0.01)';
      OUTPUT_LOAD='(1.0,-1.0)';
      PINUSE='BI';
    'GPP_D_6':
      PIN_NUMBER='(0,0,0,0,AJ1,0,0,0,0,0,0)';
      BIDIRECTIONAL='TRUE';
      INPUT_LOAD='(-0.01,0.01)';
      OUTPUT_LOAD='(1.0,-1.0)';
      PINUSE='BI';
    'GPP_D_7':
      PIN_NUMBER='(0,0,0,0,AG1,0,0,0,0,0,0)';
      BIDIRECTIONAL='TRUE';
      INPUT_LOAD='(-0.01,0.01)';
      OUTPUT_LOAD='(1.0,-1.0)';
      PINUSE='BI';
    'GPP_D_8_CRASHLOG_TRIG_N':
      PIN_NUMBER='(0,0,0,0,AE3,0,0,0,0,0,0)';
      BIDIRECTIONAL='TRUE';
      INPUT_LOAD='(-0.01,0.01)';
      OUTPUT_LOAD='(1.0,-1.0)';
      PINUSE='BI';
    'GPP_D_9_PME_N':
      PIN_NUMBER='(0,0,0,0,AJ3,0,0,0,0,0,0)';
      BIDIRECTIONAL='TRUE';
      INPUT_LOAD='(-0.01,0.01)';
      OUTPUT_LOAD='(1.0,-1.0)';
      PINUSE='BI';
    'GPPC_H_0':
      PIN_NUMBER='(0,0,0,0,0,G4,0,0,0,0,0)';
      BIDIRECTIONAL='TRUE';
      INPUT_LOAD='(-0.01,0.01)';
      OUTPUT_LOAD='(1.0,-1.0)';
      PINUSE='BI';
    'GPPC_H_1':
      PIN_NUMBER='(0,0,0,0,0,K1,0,0,0,0,0)';
      BIDIRECTIONAL='TRUE';
      INPUT_LOAD='(-0.01,0.01)';
      OUTPUT_LOAD='(1.0,-1.0)';
      PINUSE='BI';
    'GPPC_H_15_FLEX_CLK_OUT_0':
      PIN_NUMBER='(0,0,0,0,0,J2,0,0,0,0,0)';
      BIDIRECTIONAL='TRUE';
      INPUT_LOAD='(-0.01,0.01)';
      OUTPUT_LOAD='(1.0,-1.0)';
      PINUSE='BI';
    'GPPC_H_16_FLEX_CLK_OUT_1':
      PIN_NUMBER='(0,0,0,0,0,G2,0,0,0,0,0)';
      BIDIRECTIONAL='TRUE';
      INPUT_LOAD='(-0.01,0.01)';
      OUTPUT_LOAD='(1.0,-1.0)';
      PINUSE='BI';
    'GPPC_H_17_FLEX_CLK_OUT_2':
      PIN_NUMBER='(0,0,0,0,0,H3,0,0,0,0,0)';
      BIDIRECTIONAL='TRUE';
      INPUT_LOAD='(-0.01,0.01)';
      OUTPUT_LOAD='(1.0,-1.0)';
      PINUSE='BI';
    'GPPC_H_18_PMCALERT_N':
      PIN_NUMBER='(0,0,0,0,0,J4,0,0,0,0,0)';
      BIDIRECTIONAL='TRUE';
      INPUT_LOAD='(-0.01,0.01)';
      OUTPUT_LOAD='(1.0,-1.0)';
      PINUSE='BI';
    'GPPC_H_19':
      PIN_NUMBER='(0,0,0,0,0,L4,0,0,0,0,0)';
      BIDIRECTIONAL='TRUE';
      INPUT_LOAD='(-0.01,0.01)';
      OUTPUT_LOAD='(1.0,-1.0)';
      PINUSE='BI';
    'GPPC_H_6':
      PIN_NUMBER='(0,0,0,0,0,L2,0,0,0,0,0)';
      BIDIRECTIONAL='TRUE';
      INPUT_LOAD='(-0.01,0.01)';
      OUTPUT_LOAD='(1.0,-1.0)';
      PINUSE='BI';
    'GPPC_H_7':
      PIN_NUMBER='(0,0,0,0,0,K3,0,0,0,0,0)';
      BIDIRECTIONAL='TRUE';
      INPUT_LOAD='(-0.01,0.01)';
      OUTPUT_LOAD='(1.0,-1.0)';
      PINUSE='BI';
    'GPP_E_0_SATA1_XPCIE_0':
      PIN_NUMBER='(0,0,0,0,0,BA26,0,0,0,0,0)';
      BIDIRECTIONAL='TRUE';
      INPUT_LOAD='(-0.01,0.01)';
      OUTPUT_LOAD='(1.0,-1.0)';
      PINUSE='BI';
    'GPP_E_10_SATA0_SDATAOUT_SATA0_GP':
      PIN_NUMBER='(0,0,0,0,0,AV31,0,0,0,0,0)';
      BIDIRECTIONAL='TRUE';
      INPUT_LOAD='(-0.01,0.01)';
      OUTPUT_LOAD='(1.0,-1.0)';
      PINUSE='BI';
    'GPP_E_11_SATA1_SCLOCK_SATA1_LED_N':
      PIN_NUMBER='(0,0,0,0,0,AV34,0,0,0,0,0)';
      BIDIRECTIONAL='TRUE';
      INPUT_LOAD='(-0.01,0.01)';
      OUTPUT_LOAD='(1.0,-1.0)';
      PINUSE='BI';
    'GPP_E_12_SATA1_SLOAD_SATA1_GP':
      PIN_NUMBER='(0,0,0,0,0,BB28,0,0,0,0,0)';
      BIDIRECTIONAL='TRUE';
      INPUT_LOAD='(-0.01,0.01)';
      OUTPUT_LOAD='(1.0,-1.0)';
      PINUSE='BI';
    'GPP_E_13_SATA1_SDATAOUT_SATA1_DEVSLP':
      PIN_NUMBER='(0,0,0,0,0,BA32,0,0,0,0,0)';
      BIDIRECTIONAL='TRUE';
      INPUT_LOAD='(-0.01,0.01)';
      OUTPUT_LOAD='(1.0,-1.0)';
      PINUSE='BI';
    'GPP_E_14_SATA2_SCLOCK_SATA2_LED_N':
      PIN_NUMBER='(0,0,0,0,0,BB34,0,0,0,0,0)';
      BIDIRECTIONAL='TRUE';
      INPUT_LOAD='(-0.01,0.01)';
      OUTPUT_LOAD='(1.0,-1.0)';
      PINUSE='BI';
    'GPP_E_15_SATA2_SLOAD_SATA2_GP':
      PIN_NUMBER='(0,0,0,0,0,AW20,0,0,0,0,0)';
      BIDIRECTIONAL='TRUE';
      INPUT_LOAD='(-0.01,0.01)';
      OUTPUT_LOAD='(1.0,-1.0)';
      PINUSE='BI';
    'GPP_E_16_SATA2_SDATAOUT_SATA2_DEVSLP':
      PIN_NUMBER='(0,0,0,0,0,AW29,0,0,0,0,0)';
      BIDIRECTIONAL='TRUE';
      INPUT_LOAD='(-0.01,0.01)';
      OUTPUT_LOAD='(1.0,-1.0)';
      PINUSE='BI';
    'GPP_E_17_ERR0_N':
      PIN_NUMBER='(0,0,0,0,0,BA36,0,0,0,0,0)';
      BIDIRECTIONAL='TRUE';
      INPUT_LOAD='(-0.01,0.01)';
      OUTPUT_LOAD='(1.0,-1.0)';
      PINUSE='BI';
    'GPP_E_18_ERR1_N':
      PIN_NUMBER='(0,0,0,0,0,BA20,0,0,0,0,0)';
      BIDIRECTIONAL='TRUE';
      INPUT_LOAD='(-0.01,0.01)';
      OUTPUT_LOAD='(1.0,-1.0)';
      PINUSE='BI';
    'GPP_E_19_ERR2_N':
      PIN_NUMBER='(0,0,0,0,0,BB31,0,0,0,0,0)';
      BIDIRECTIONAL='TRUE';
      INPUT_LOAD='(-0.01,0.01)';
      OUTPUT_LOAD='(1.0,-1.0)';
      PINUSE='BI';
    'GPP_E_1_SATA1_XPCIE_1':
      PIN_NUMBER='(0,0,0,0,0,BA23,0,0,0,0,0)';
      BIDIRECTIONAL='TRUE';
      INPUT_LOAD='(-0.01,0.01)';
      OUTPUT_LOAD='(1.0,-1.0)';
      PINUSE='BI';
    'GPP_E_2_SATA1_XPCIE_2':
      PIN_NUMBER='(0,0,0,0,0,AW23,0,0,0,0,0)';
      BIDIRECTIONAL='TRUE';
      INPUT_LOAD='(-0.01,0.01)';
      OUTPUT_LOAD='(1.0,-1.0)';
      PINUSE='BI';
    'GPP_E_3_SATA1_XPCIE_3':
      PIN_NUMBER='(0,0,0,0,0,BB21,0,0,0,0,0)';
      BIDIRECTIONAL='TRUE';
      INPUT_LOAD='(-0.01,0.01)';
      OUTPUT_LOAD='(1.0,-1.0)';
      PINUSE='BI';
    'GPP_E_4_SATA0_XPCIE_2':
      PIN_NUMBER='(0,0,0,0,0,AV24,0,0,0,0,0)';
      BIDIRECTIONAL='TRUE';
      INPUT_LOAD='(-0.01,0.01)';
      OUTPUT_LOAD='(1.0,-1.0)';
      PINUSE='BI';
    'GPP_E_5_SATA0_XPCIE_3':
      PIN_NUMBER='(0,0,0,0,0,AV28,0,0,0,0,0)';
      BIDIRECTIONAL='TRUE';
      INPUT_LOAD='(-0.01,0.01)';
      OUTPUT_LOAD='(1.0,-1.0)';
      PINUSE='BI';
    'GPP_E_6_SATA0_USB3_XPCIE_0':
      PIN_NUMBER='(0,0,0,0,0,BB24,0,0,0,0,0)';
      BIDIRECTIONAL='TRUE';
      INPUT_LOAD='(-0.01,0.01)';
      OUTPUT_LOAD='(1.0,-1.0)';
      PINUSE='BI';
    'GPP_E_7_SATA0_USB3_XPCIE_1':
      PIN_NUMBER='(0,0,0,0,0,AW32,0,0,0,0,0)';
      BIDIRECTIONAL='TRUE';
      INPUT_LOAD='(-0.01,0.01)';
      OUTPUT_LOAD='(1.0,-1.0)';
      PINUSE='BI';
    'GPP_E_8_SATA0_SCLOCK_SATA0_LED_N':
      PIN_NUMBER='(0,0,0,0,0,AW36,0,0,0,0,0)';
      BIDIRECTIONAL='TRUE';
      INPUT_LOAD='(-0.01,0.01)';
      OUTPUT_LOAD='(1.0,-1.0)';
      PINUSE='BI';
    'GPP_E_9_SATA0_SLOAD_SATA0_DEVSLP':
      PIN_NUMBER='(0,0,0,0,0,BA29,0,0,0,0,0)';
      BIDIRECTIONAL='TRUE';
      INPUT_LOAD='(-0.01,0.01)';
      OUTPUT_LOAD='(1.0,-1.0)';
      PINUSE='BI';
    'GPP_I_12_HDA_BCLK':
      PIN_NUMBER='(0,0,0,0,0,U3,0,0,0,0,0)';
      BIDIRECTIONAL='TRUE';
      INPUT_LOAD='(-0.01,0.01)';
      OUTPUT_LOAD='(1.0,-1.0)';
      PINUSE='BI';
    'GPP_I_13_HDA_RST_N':
      PIN_NUMBER='(0,0,0,0,0,N2,0,0,0,0,0)';
      BIDIRECTIONAL='TRUE';
      INPUT_LOAD='(-0.01,0.01)';
      OUTPUT_LOAD='(1.0,-1.0)';
      PINUSE='BI';
    'GPP_I_14_HDA_SYNC':
      PIN_NUMBER='(0,0,0,0,0,P1,0,0,0,0,0)';
      BIDIRECTIONAL='TRUE';
      INPUT_LOAD='(-0.01,0.01)';
      OUTPUT_LOAD='(1.0,-1.0)';
      PINUSE='BI';
    'GPP_I_15_HDA_SDO':
      PIN_NUMBER='(0,0,0,0,0,R2,0,0,0,0,0)';
      BIDIRECTIONAL='TRUE';
      INPUT_LOAD='(-0.01,0.01)';
      OUTPUT_LOAD='(1.0,-1.0)';
      PINUSE='BI';
    'GPP_I_16_HDA_SDI_0':
      PIN_NUMBER='(0,0,0,0,0,U1,0,0,0,0,0)';
      BIDIRECTIONAL='TRUE';
      INPUT_LOAD='(-0.01,0.01)';
      OUTPUT_LOAD='(1.0,-1.0)';
      PINUSE='BI';
    'GPP_I_17_HDA_SDI_1':
      PIN_NUMBER='(0,0,0,0,0,V4,0,0,0,0,0)';
      BIDIRECTIONAL='TRUE';
      INPUT_LOAD='(-0.01,0.01)';
      OUTPUT_LOAD='(1.0,-1.0)';
      PINUSE='BI';
    'GPP_I_21':
      PIN_NUMBER='(0,0,0,0,0,N4,0,0,0,0,0)';
      BIDIRECTIONAL='TRUE';
      INPUT_LOAD='(-0.01,0.01)';
      OUTPUT_LOAD='(1.0,-1.0)';
      PINUSE='BI';
    'GPP_I_22':
      PIN_NUMBER='(0,0,0,0,0,P3,0,0,0,0,0)';
      BIDIRECTIONAL='TRUE';
      INPUT_LOAD='(-0.01,0.01)';
      OUTPUT_LOAD='(1.0,-1.0)';
      PINUSE='BI';
    'GPP_I_23':
      PIN_NUMBER='(0,0,0,0,0,R4,0,0,0,0,0)';
      BIDIRECTIONAL='TRUE';
      INPUT_LOAD='(-0.01,0.01)';
      OUTPUT_LOAD='(1.0,-1.0)';
      PINUSE='BI';
    'GPP_L_0_PM_SYNC_0':
      PIN_NUMBER='(0,0,0,0,0,AF8,0,0,0,0,0)';
      BIDIRECTIONAL='TRUE';
      INPUT_LOAD='(-0.01,0.01)';
      OUTPUT_LOAD='(1.0,-1.0)';
      PINUSE='BI';
    'GPP_L_1_PM_DOWN_0':
      PIN_NUMBER='(0,0,0,0,0,AE7,0,0,0,0,0)';
      BIDIRECTIONAL='TRUE';
      INPUT_LOAD='(-0.01,0.01)';
      OUTPUT_LOAD='(1.0,-1.0)';
      PINUSE='BI';
    'GPP_L_2':
      PIN_NUMBER='(0,0,0,0,0,AC10,0,0,0,0,0)';
      BIDIRECTIONAL='TRUE';
      INPUT_LOAD='(-0.01,0.01)';
      OUTPUT_LOAD='(1.0,-1.0)';
      PINUSE='BI';
    'GPP_L_3':
      PIN_NUMBER='(0,0,0,0,0,AF11,0,0,0,0,0)';
      BIDIRECTIONAL='TRUE';
      INPUT_LOAD='(-0.01,0.01)';
      OUTPUT_LOAD='(1.0,-1.0)';
      PINUSE='BI';
    'GPP_L_4':
      PIN_NUMBER='(0,0,0,0,0,AG7,0,0,0,0,0)';
      BIDIRECTIONAL='TRUE';
      INPUT_LOAD='(-0.01,0.01)';
      OUTPUT_LOAD='(1.0,-1.0)';
      PINUSE='BI';
    'GPP_L_5':
      PIN_NUMBER='(0,0,0,0,0,AB8,0,0,0,0,0)';
      BIDIRECTIONAL='TRUE';
      INPUT_LOAD='(-0.01,0.01)';
      OUTPUT_LOAD='(1.0,-1.0)';
      PINUSE='BI';
    'GPP_L_6':
      PIN_NUMBER='(0,0,0,0,0,AG10,0,0,0,0,0)';
      BIDIRECTIONAL='TRUE';
      INPUT_LOAD='(-0.01,0.01)';
      OUTPUT_LOAD='(1.0,-1.0)';
      PINUSE='BI';
    'GPP_L_7':
      PIN_NUMBER='(0,0,0,0,0,AC7,0,0,0,0,0)';
      BIDIRECTIONAL='TRUE';
      INPUT_LOAD='(-0.01,0.01)';
      OUTPUT_LOAD='(1.0,-1.0)';
      PINUSE='BI';
    'GPP_L_8':
      PIN_NUMBER='(0,0,0,0,0,AE10,0,0,0,0,0)';
      BIDIRECTIONAL='TRUE';
      INPUT_LOAD='(-0.01,0.01)';
      OUTPUT_LOAD='(1.0,-1.0)';
      PINUSE='BI';
    'GPP_M_0':
      PIN_NUMBER='(0,0,0,0,0,N7,0,0,0,0,0)';
      BIDIRECTIONAL='TRUE';
      INPUT_LOAD='(-0.01,0.01)';
      OUTPUT_LOAD='(1.0,-1.0)';
      PINUSE='BI';
    'GPP_M_1':
      PIN_NUMBER='(0,0,0,0,0,AA13,0,0,0,0,0)';
      BIDIRECTIONAL='TRUE';
      INPUT_LOAD='(-0.01,0.01)';
      OUTPUT_LOAD='(1.0,-1.0)';
      PINUSE='BI';
    'GPP_M_11':
      PIN_NUMBER='(0,0,0,0,0,R7,0,0,0,0,0)';
      BIDIRECTIONAL='TRUE';
      INPUT_LOAD='(-0.01,0.01)';
      OUTPUT_LOAD='(1.0,-1.0)';
      PINUSE='BI';
    'GPP_M_12':
      PIN_NUMBER='(0,0,0,0,0,U7,0,0,0,0,0)';
      BIDIRECTIONAL='TRUE';
      INPUT_LOAD='(-0.01,0.01)';
      OUTPUT_LOAD='(1.0,-1.0)';
      PINUSE='BI';
    'GPP_M_15':
      PIN_NUMBER='(0,0,0,0,0,T8,0,0,0,0,0)';
      BIDIRECTIONAL='TRUE';
      INPUT_LOAD='(-0.01,0.01)';
      OUTPUT_LOAD='(1.0,-1.0)';
      PINUSE='BI';
    'GPP_M_16':
      PIN_NUMBER='(0,0,0,0,0,N10,0,0,0,0,0)';
      BIDIRECTIONAL='TRUE';
      INPUT_LOAD='(-0.01,0.01)';
      OUTPUT_LOAD='(1.0,-1.0)';
      PINUSE='BI';
    'GPP_M_17':
      PIN_NUMBER='(0,0,0,0,0,W13,0,0,0,0,0)';
      BIDIRECTIONAL='TRUE';
      INPUT_LOAD='(-0.01,0.01)';
      OUTPUT_LOAD='(1.0,-1.0)';
      PINUSE='BI';
    'GPP_M_2':
      PIN_NUMBER='(0,0,0,0,0,AA7,0,0,0,0,0)';
      BIDIRECTIONAL='TRUE';
      INPUT_LOAD='(-0.01,0.01)';
      OUTPUT_LOAD='(1.0,-1.0)';
      PINUSE='BI';
    'GPP_M_3':
      PIN_NUMBER='(0,0,0,0,0,AA10,0,0,0,0,0)';
      BIDIRECTIONAL='TRUE';
      INPUT_LOAD='(-0.01,0.01)';
      OUTPUT_LOAD='(1.0,-1.0)';
      PINUSE='BI';
    'GPP_M_4':
      PIN_NUMBER='(0,0,0,0,0,W7,0,0,0,0,0)';
      BIDIRECTIONAL='TRUE';
      INPUT_LOAD='(-0.01,0.01)';
      OUTPUT_LOAD='(1.0,-1.0)';
      PINUSE='BI';
    'GPP_M_5':
      PIN_NUMBER='(0,0,0,0,0,V8,0,0,0,0,0)';
      BIDIRECTIONAL='TRUE';
      INPUT_LOAD='(-0.01,0.01)';
      OUTPUT_LOAD='(1.0,-1.0)';
      PINUSE='BI';
    'GPP_M_6':
      PIN_NUMBER='(0,0,0,0,0,R10,0,0,0,0,0)';
      BIDIRECTIONAL='TRUE';
      INPUT_LOAD='(-0.01,0.01)';
      OUTPUT_LOAD='(1.0,-1.0)';
      PINUSE='BI';
    'GPP_M_7':
      PIN_NUMBER='(0,0,0,0,0,AB11,0,0,0,0,0)';
      BIDIRECTIONAL='TRUE';
      INPUT_LOAD='(-0.01,0.01)';
      OUTPUT_LOAD='(1.0,-1.0)';
      PINUSE='BI';
    'GPP_M_8':
      PIN_NUMBER='(0,0,0,0,0,W10,0,0,0,0,0)';
      BIDIRECTIONAL='TRUE';
      INPUT_LOAD='(-0.01,0.01)';
      OUTPUT_LOAD='(1.0,-1.0)';
      PINUSE='BI';
    'GPPC_S_0_TIME_SYNC_0':
      PIN_NUMBER='(0,0,0,0,0,0,BB18,0,0,0,0)';
      BIDIRECTIONAL='TRUE';
      INPUT_LOAD='(-0.01,0.01)';
      OUTPUT_LOAD='(1.0,-1.0)';
      PINUSE='BI';
    'GPPC_S_10':
      PIN_NUMBER='(0,0,0,0,0,0,AW10,0,0,0,0)';
      BIDIRECTIONAL='TRUE';
      INPUT_LOAD='(-0.01,0.01)';
      OUTPUT_LOAD='(1.0,-1.0)';
      PINUSE='BI';
    'GPPC_S_11':
      PIN_NUMBER='(0,0,0,0,0,0,BB8,0,0,0,0)';
      BIDIRECTIONAL='TRUE';
      INPUT_LOAD='(-0.01,0.01)';
      OUTPUT_LOAD='(1.0,-1.0)';
      PINUSE='BI';
    'GPPC_S_1_SPKR_TIME_SYNC_1':
      PIN_NUMBER='(0,0,0,0,0,0,AU16,0,0,0,0)';
      BIDIRECTIONAL='TRUE';
      INPUT_LOAD='(-0.01,0.01)';
      OUTPUT_LOAD='(1.0,-1.0)';
      PINUSE='BI';
    'GPPC_S_2_CPU_GP_0':
      PIN_NUMBER='(0,0,0,0,0,0,AR16,0,0,0,0)';
      BIDIRECTIONAL='TRUE';
      INPUT_LOAD='(-0.01,0.01)';
      OUTPUT_LOAD='(1.0,-1.0)';
      PINUSE='BI';
    'GPPC_S_3_CPU_GP_1':
      PIN_NUMBER='(0,0,0,0,0,0,AV11,0,0,0,0)';
      BIDIRECTIONAL='TRUE';
      INPUT_LOAD='(-0.01,0.01)';
      OUTPUT_LOAD='(1.0,-1.0)';
      PINUSE='BI';
    'GPPC_S_4_CPU_GP_2':
      PIN_NUMBER='(0,0,0,0,0,0,AU13,0,0,0,0)';
      BIDIRECTIONAL='TRUE';
      INPUT_LOAD='(-0.01,0.01)';
      OUTPUT_LOAD='(1.0,-1.0)';
      PINUSE='BI';
    'GPPC_S_5_CPU_GP_3':
      PIN_NUMBER='(0,0,0,0,0,0,AT18,0,0,0,0)';
      BIDIRECTIONAL='TRUE';
      INPUT_LOAD='(-0.01,0.01)';
      OUTPUT_LOAD='(1.0,-1.0)';
      PINUSE='BI';
    'GPPC_S_6_SUSWARN_N_SUSPWRDNACK':
      PIN_NUMBER='(0,0,0,0,0,0,AR13,0,0,0,0)';
      BIDIRECTIONAL='TRUE';
      INPUT_LOAD='(-0.01,0.01)';
      OUTPUT_LOAD='(1.0,-1.0)';
      PINUSE='BI';
    'GPPC_S_7_SUSACK_N':
      PIN_NUMBER='(0,0,0,0,0,0,BA7,0,0,0,0)';
      BIDIRECTIONAL='TRUE';
      INPUT_LOAD='(-0.01,0.01)';
      OUTPUT_LOAD='(1.0,-1.0)';
      PINUSE='BI';
    'GPPC_S_8_NMI_N':
      PIN_NUMBER='(0,0,0,0,0,0,AP15,0,0,0,0)';
      BIDIRECTIONAL='TRUE';
      INPUT_LOAD='(-0.01,0.01)';
      OUTPUT_LOAD='(1.0,-1.0)';
      PINUSE='BI';
    'GPPC_S_9_SMI_N':
      PIN_NUMBER='(0,0,0,0,0,0,AV18,0,0,0,0)';
      BIDIRECTIONAL='TRUE';
      INPUT_LOAD='(-0.01,0.01)';
      OUTPUT_LOAD='(1.0,-1.0)';
      PINUSE='BI';
    'GPP_N_1':
      PIN_NUMBER='(0,0,0,0,0,0,T11,0,0,0,0)';
      BIDIRECTIONAL='TRUE';
      INPUT_LOAD='(-0.01,0.01)';
      OUTPUT_LOAD='(1.0,-1.0)';
      PINUSE='BI';
    'GPP_N_4':
      PIN_NUMBER='(0,0,0,0,0,0,V11,0,0,0,0)';
      BIDIRECTIONAL='TRUE';
      INPUT_LOAD='(-0.01,0.01)';
      OUTPUT_LOAD='(1.0,-1.0)';
      PINUSE='BI';
    'NC_CGC_DUT_DETECT_N':
      PIN_NUMBER='(0,0,0,0,0,0,BG3,0,0,0,0)';
      OUTPUT_TYPE='(TS,TS)';
      INPUT_LOAD='(-0.01,0.01)';
      OUTPUT_LOAD='(1.0,-1.0)';
      PINUSE='TRI';
    'RCTRST_N':
      PIN_NUMBER='(0,0,0,0,0,0,BD7,0,0,0,0)';
      INPUT_LOAD='(-0.01,0.01)';
      PINUSE='IN';
    'SPI0_CLK':
      PIN_NUMBER='(0,0,0,0,0,0,BB15,0,0,0,0)';
      OUTPUT_LOAD='(1.0,-1.0)';
      PINUSE='OUT';
    'SPI0_FLASH_0_CS_N':
      PIN_NUMBER='(0,0,0,0,0,0,AW13,0,0,0,0)';
      OUTPUT_LOAD='(1.0,-1.0)';
      PINUSE='OUT';
    'SPI0_FLASH_1_CS_N':
      PIN_NUMBER='(0,0,0,0,0,0,BA10,0,0,0,0)';
      OUTPUT_LOAD='(1.0,-1.0)';
      PINUSE='OUT';
    'SPI0_IO_2':
      PIN_NUMBER='(0,0,0,0,0,0,AV15,0,0,0,0)';
      BIDIRECTIONAL='TRUE';
      INPUT_LOAD='(-0.01,0.01)';
      OUTPUT_LOAD='(1.0,-1.0)';
      PINUSE='BI';
    'SPI0_IO_3':
      PIN_NUMBER='(0,0,0,0,0,0,BA16,0,0,0,0)';
      BIDIRECTIONAL='TRUE';
      INPUT_LOAD='(-0.01,0.01)';
      OUTPUT_LOAD='(1.0,-1.0)';
      PINUSE='BI';
    'SPI0_MOSI_IO_0':
      PIN_NUMBER='(0,0,0,0,0,0,BA13,0,0,0,0)';
      BIDIRECTIONAL='TRUE';
      INPUT_LOAD='(-0.01,0.01)';
      OUTPUT_LOAD='(1.0,-1.0)';
      PINUSE='BI';
    'SPI0_MISO_IO_1':
      PIN_NUMBER='(0,0,0,0,0,0,AW16,0,0,0,0)';
      BIDIRECTIONAL='TRUE';
      INPUT_LOAD='(-0.01,0.01)';
      OUTPUT_LOAD='(1.0,-1.0)';
      PINUSE='BI';
    'SPI0_TPM_CS_N':
      PIN_NUMBER='(0,0,0,0,0,0,BB11,0,0,0,0)';
      OUTPUT_LOAD='(1.0,-1.0)';
      PINUSE='OUT';
    'SRTCRST_N':
      PIN_NUMBER='(0,0,0,0,0,0,BF9,0,0,0,0)';
      INPUT_LOAD='(-0.01,0.01)';
      PINUSE='IN';
    'VSS_A41':
      PIN_NUMBER='(0,0,0,0,0,0,A41,0,0,0,0)';
      PINUSE='POWER';
      NO_LOAD_CHECK='Both';
      NO_IO_CHECK='Both';
      NO_ASSERT_CHECK='TRUE';
      NO_DIR_CHECK='TRUE';
      ALLOW_CONNECT='TRUE';
    'RSVD_AF15':
      PIN_NUMBER='(0,0,0,0,0,0,0,AF15,0,0,0)';
      OUTPUT_TYPE='(TS,TS)';
      INPUT_LOAD='(-0.01,0.01)';
      OUTPUT_LOAD='(1.0,-1.0)';
      PINUSE='TRI';
    'RSVD_AN26':
      PIN_NUMBER='(0,0,0,0,0,0,0,AN26,0,0,0)';
      OUTPUT_TYPE='(TS,TS)';
      INPUT_LOAD='(-0.01,0.01)';
      OUTPUT_LOAD='(1.0,-1.0)';
      PINUSE='TRI';
    'VCCP_1P05_W24':
      PIN_NUMBER='(0,0,0,0,0,0,0,W24,0,0,0)';
      PINUSE='POWER';
      NO_LOAD_CHECK='Both';
      NO_IO_CHECK='Both';
      NO_ASSERT_CHECK='TRUE';
      NO_DIR_CHECK='TRUE';
      ALLOW_CONNECT='TRUE';
    'VCCP_1P05_W22':
      PIN_NUMBER='(0,0,0,0,0,0,0,W22,0,0,0)';
      PINUSE='POWER';
      NO_LOAD_CHECK='Both';
      NO_IO_CHECK='Both';
      NO_ASSERT_CHECK='TRUE';
      NO_DIR_CHECK='TRUE';
      ALLOW_CONNECT='TRUE';
    'VCCP_1P05_W20':
      PIN_NUMBER='(0,0,0,0,0,0,0,W20,0,0,0)';
      PINUSE='POWER';
      NO_LOAD_CHECK='Both';
      NO_IO_CHECK='Both';
      NO_ASSERT_CHECK='TRUE';
      NO_DIR_CHECK='TRUE';
      ALLOW_CONNECT='TRUE';
    'VCCP_1P05_W19':
      PIN_NUMBER='(0,0,0,0,0,0,0,W19,0,0,0)';
      PINUSE='POWER';
      NO_LOAD_CHECK='Both';
      NO_IO_CHECK='Both';
      NO_ASSERT_CHECK='TRUE';
      NO_DIR_CHECK='TRUE';
      ALLOW_CONNECT='TRUE';
    'VCCP_1P05_W17':
      PIN_NUMBER='(0,0,0,0,0,0,0,W17,0,0,0)';
      PINUSE='POWER';
      NO_LOAD_CHECK='Both';
      NO_IO_CHECK='Both';
      NO_ASSERT_CHECK='TRUE';
      NO_DIR_CHECK='TRUE';
      ALLOW_CONNECT='TRUE';
    'VCCP_1P05_AB24':
      PIN_NUMBER='(0,0,0,0,0,0,0,AB24,0,0,0)';
      PINUSE='POWER';
      NO_LOAD_CHECK='Both';
      NO_IO_CHECK='Both';
      NO_ASSERT_CHECK='TRUE';
      NO_DIR_CHECK='TRUE';
      ALLOW_CONNECT='TRUE';
    'VCCP_1P05_AB22':
      PIN_NUMBER='(0,0,0,0,0,0,0,AB22,0,0,0)';
      PINUSE='POWER';
      NO_LOAD_CHECK='Both';
      NO_IO_CHECK='Both';
      NO_ASSERT_CHECK='TRUE';
      NO_DIR_CHECK='TRUE';
      ALLOW_CONNECT='TRUE';
    'VCCP_1P05_AB20':
      PIN_NUMBER='(0,0,0,0,0,0,0,AB20,0,0,0)';
      PINUSE='POWER';
      NO_LOAD_CHECK='Both';
      NO_IO_CHECK='Both';
      NO_ASSERT_CHECK='TRUE';
      NO_DIR_CHECK='TRUE';
      ALLOW_CONNECT='TRUE';
    'VCCP_1P05_AB19':
      PIN_NUMBER='(0,0,0,0,0,0,0,AB19,0,0,0)';
      PINUSE='POWER';
      NO_LOAD_CHECK='Both';
      NO_IO_CHECK='Both';
      NO_ASSERT_CHECK='TRUE';
      NO_DIR_CHECK='TRUE';
      ALLOW_CONNECT='TRUE';
    'VCCP_1P05_AJ27':
      PIN_NUMBER='(0,0,0,0,0,0,0,AJ27,0,0,0)';
      PINUSE='POWER';
      NO_LOAD_CHECK='Both';
      NO_IO_CHECK='Both';
      NO_ASSERT_CHECK='TRUE';
      NO_DIR_CHECK='TRUE';
      ALLOW_CONNECT='TRUE';
    'VCCP_1P05_AJ25':
      PIN_NUMBER='(0,0,0,0,0,0,0,AJ25,0,0,0)';
      PINUSE='POWER';
      NO_LOAD_CHECK='Both';
      NO_IO_CHECK='Both';
      NO_ASSERT_CHECK='TRUE';
      NO_DIR_CHECK='TRUE';
      ALLOW_CONNECT='TRUE';
    'VCCP_1P05_AG27':
      PIN_NUMBER='(0,0,0,0,0,0,0,AG27,0,0,0)';
      PINUSE='POWER';
      NO_LOAD_CHECK='Both';
      NO_IO_CHECK='Both';
      NO_ASSERT_CHECK='TRUE';
      NO_DIR_CHECK='TRUE';
      ALLOW_CONNECT='TRUE';
    'VCCP_1P05_AG25':
      PIN_NUMBER='(0,0,0,0,0,0,0,AG25,0,0,0)';
      PINUSE='POWER';
      NO_LOAD_CHECK='Both';
      NO_IO_CHECK='Both';
      NO_ASSERT_CHECK='TRUE';
      NO_DIR_CHECK='TRUE';
      ALLOW_CONNECT='TRUE';
    'VCCP_1P05_AF27':
      PIN_NUMBER='(0,0,0,0,0,0,0,AF27,0,0,0)';
      PINUSE='POWER';
      NO_LOAD_CHECK='Both';
      NO_IO_CHECK='Both';
      NO_ASSERT_CHECK='TRUE';
      NO_DIR_CHECK='TRUE';
      ALLOW_CONNECT='TRUE';
    'VCCP_1P05_AF25':
      PIN_NUMBER='(0,0,0,0,0,0,0,AF25,0,0,0)';
      PINUSE='POWER';
      NO_LOAD_CHECK='Both';
      NO_IO_CHECK='Both';
      NO_ASSERT_CHECK='TRUE';
      NO_DIR_CHECK='TRUE';
      ALLOW_CONNECT='TRUE';
    'VCCP_1P05_AD27':
      PIN_NUMBER='(0,0,0,0,0,0,0,AD27,0,0,0)';
      PINUSE='POWER';
      NO_LOAD_CHECK='Both';
      NO_IO_CHECK='Both';
      NO_ASSERT_CHECK='TRUE';
      NO_DIR_CHECK='TRUE';
      ALLOW_CONNECT='TRUE';
    'VCCP_1P05_AD25':
      PIN_NUMBER='(0,0,0,0,0,0,0,AD25,0,0,0)';
      PINUSE='POWER';
      NO_LOAD_CHECK='Both';
      NO_IO_CHECK='Both';
      NO_ASSERT_CHECK='TRUE';
      NO_DIR_CHECK='TRUE';
      ALLOW_CONNECT='TRUE';
    'VCCP_1P05_FILTERED_AB27':
      PIN_NUMBER='(0,0,0,0,0,0,0,AB27,0,0,0)';
      PINUSE='POWER';
      NO_LOAD_CHECK='Both';
      NO_IO_CHECK='Both';
      NO_ASSERT_CHECK='TRUE';
      NO_DIR_CHECK='TRUE';
      ALLOW_CONNECT='TRUE';
    'VCCP_1P05_N26':
      PIN_NUMBER='(0,0,0,0,0,0,0,N26,0,0,0)';
      PINUSE='POWER';
      NO_LOAD_CHECK='Both';
      NO_IO_CHECK='Both';
      NO_ASSERT_CHECK='TRUE';
      NO_DIR_CHECK='TRUE';
      ALLOW_CONNECT='TRUE';
    'VCCP_1P05_N23':
      PIN_NUMBER='(0,0,0,0,0,0,0,N23,0,0,0)';
      PINUSE='POWER';
      NO_LOAD_CHECK='Both';
      NO_IO_CHECK='Both';
      NO_ASSERT_CHECK='TRUE';
      NO_DIR_CHECK='TRUE';
      ALLOW_CONNECT='TRUE';
    'VCCP_1P05_AR26':
      PIN_NUMBER='(0,0,0,0,0,0,0,AR26,0,0,0)';
      PINUSE='POWER';
      NO_LOAD_CHECK='Both';
      NO_IO_CHECK='Both';
      NO_ASSERT_CHECK='TRUE';
      NO_DIR_CHECK='TRUE';
      ALLOW_CONNECT='TRUE';
    'VCCP_1P05_M24':
      PIN_NUMBER='(0,0,0,0,0,0,0,M24,0,0,0)';
      PINUSE='POWER';
      NO_LOAD_CHECK='Both';
      NO_IO_CHECK='Both';
      NO_ASSERT_CHECK='TRUE';
      NO_DIR_CHECK='TRUE';
      ALLOW_CONNECT='TRUE';
    'VCCP_1P05_P15':
      PIN_NUMBER='(0,0,0,0,0,0,0,P15,0,0,0)';
      PINUSE='POWER';
      NO_LOAD_CHECK='Both';
      NO_IO_CHECK='Both';
      NO_ASSERT_CHECK='TRUE';
      NO_DIR_CHECK='TRUE';
      ALLOW_CONNECT='TRUE';
    'VCCP_1P05_FILTERED_AL25':
      PIN_NUMBER='(0,0,0,0,0,0,0,AL25,0,0,0)';
      PINUSE='POWER';
      NO_LOAD_CHECK='Both';
      NO_IO_CHECK='Both';
      NO_ASSERT_CHECK='TRUE';
      NO_DIR_CHECK='TRUE';
      ALLOW_CONNECT='TRUE';
    'VCCP_1P05_FILTERED_AG29':
      PIN_NUMBER='(0,0,0,0,0,0,0,AG29,0,0,0)';
      PINUSE='POWER';
      NO_LOAD_CHECK='Both';
      NO_IO_CHECK='Both';
      NO_ASSERT_CHECK='TRUE';
      NO_DIR_CHECK='TRUE';
      ALLOW_CONNECT='TRUE';
    'VCCP_1P05_FILTERED_AE29':
      PIN_NUMBER='(0,0,0,0,0,0,0,AE29,0,0,0)';
      PINUSE='POWER';
      NO_LOAD_CHECK='Both';
      NO_IO_CHECK='Both';
      NO_ASSERT_CHECK='TRUE';
      NO_DIR_CHECK='TRUE';
      ALLOW_CONNECT='TRUE';
    'VCCP_1P05_FILTERED_R29':
      PIN_NUMBER='(0,0,0,0,0,0,0,R29,0,0,0)';
      PINUSE='POWER';
      NO_LOAD_CHECK='Both';
      NO_IO_CHECK='Both';
      NO_ASSERT_CHECK='TRUE';
      NO_DIR_CHECK='TRUE';
      ALLOW_CONNECT='TRUE';
    'VCCP_1P05_FILTERED_U27':
      PIN_NUMBER='(0,0,0,0,0,0,0,U27,0,0,0)';
      PINUSE='POWER';
      NO_LOAD_CHECK='Both';
      NO_IO_CHECK='Both';
      NO_ASSERT_CHECK='TRUE';
      NO_DIR_CHECK='TRUE';
      ALLOW_CONNECT='TRUE';
    'VCCP_1P05_FILTERED_AA29':
      PIN_NUMBER='(0,0,0,0,0,0,0,AA29,0,0,0)';
      PINUSE='POWER';
      NO_LOAD_CHECK='Both';
      NO_IO_CHECK='Both';
      NO_ASSERT_CHECK='TRUE';
      NO_DIR_CHECK='TRUE';
      ALLOW_CONNECT='TRUE';
    'VCCP_1P05_FILTERED_R26':
      PIN_NUMBER='(0,0,0,0,0,0,0,R26,0,0,0)';
      PINUSE='POWER';
      NO_LOAD_CHECK='Both';
      NO_IO_CHECK='Both';
      NO_ASSERT_CHECK='TRUE';
      NO_DIR_CHECK='TRUE';
      ALLOW_CONNECT='TRUE';
    'VCCP_1P05_FILTERED_R23':
      PIN_NUMBER='(0,0,0,0,0,0,0,R23,0,0,0)';
      PINUSE='POWER';
      NO_LOAD_CHECK='Both';
      NO_IO_CHECK='Both';
      NO_ASSERT_CHECK='TRUE';
      NO_DIR_CHECK='TRUE';
      ALLOW_CONNECT='TRUE';
    'VCCP_1P8_N20':
      PIN_NUMBER='(0,0,0,0,0,0,0,N20,0,0,0)';
      PINUSE='POWER';
      NO_LOAD_CHECK='Both';
      NO_IO_CHECK='Both';
      NO_ASSERT_CHECK='TRUE';
      NO_DIR_CHECK='TRUE';
      ALLOW_CONNECT='TRUE';
    'VCCP_1P8_U24':
      PIN_NUMBER='(0,0,0,0,0,0,0,U24,0,0,0)';
      PINUSE='POWER';
      NO_LOAD_CHECK='Both';
      NO_IO_CHECK='Both';
      NO_ASSERT_CHECK='TRUE';
      NO_DIR_CHECK='TRUE';
      ALLOW_CONNECT='TRUE';
    'VCCP_1P8_U22':
      PIN_NUMBER='(0,0,0,0,0,0,0,U22,0,0,0)';
      PINUSE='POWER';
      NO_LOAD_CHECK='Both';
      NO_IO_CHECK='Both';
      NO_ASSERT_CHECK='TRUE';
      NO_DIR_CHECK='TRUE';
      ALLOW_CONNECT='TRUE';
    'VCCP_1P8_U20':
      PIN_NUMBER='(0,0,0,0,0,0,0,U20,0,0,0)';
      PINUSE='POWER';
      NO_LOAD_CHECK='Both';
      NO_IO_CHECK='Both';
      NO_ASSERT_CHECK='TRUE';
      NO_DIR_CHECK='TRUE';
      ALLOW_CONNECT='TRUE';
    'VCCP_1P8_U19':
      PIN_NUMBER='(0,0,0,0,0,0,0,U19,0,0,0)';
      PINUSE='POWER';
      NO_LOAD_CHECK='Both';
      NO_IO_CHECK='Both';
      NO_ASSERT_CHECK='TRUE';
      NO_DIR_CHECK='TRUE';
      ALLOW_CONNECT='TRUE';
    'VCCP_1P8_U17':
      PIN_NUMBER='(0,0,0,0,0,0,0,U17,0,0,0)';
      PINUSE='POWER';
      NO_LOAD_CHECK='Both';
      NO_IO_CHECK='Both';
      NO_ASSERT_CHECK='TRUE';
      NO_DIR_CHECK='TRUE';
      ALLOW_CONNECT='TRUE';
    'VCCP_1P8_FILTERED_AB34':
      PIN_NUMBER='(0,0,0,0,0,0,0,AB34,0,0,0)';
      PINUSE='POWER';
      NO_LOAD_CHECK='Both';
      NO_IO_CHECK='Both';
      NO_ASSERT_CHECK='TRUE';
      NO_DIR_CHECK='TRUE';
      ALLOW_CONNECT='TRUE';
    'VCCP_1P8_FILTERED_W29':
      PIN_NUMBER='(0,0,0,0,0,0,0,W29,0,0,0)';
      PINUSE='POWER';
      NO_LOAD_CHECK='Both';
      NO_IO_CHECK='Both';
      NO_ASSERT_CHECK='TRUE';
      NO_DIR_CHECK='TRUE';
      ALLOW_CONNECT='TRUE';
    'VCCP_1P8_FILTERED_U29':
      PIN_NUMBER='(0,0,0,0,0,0,0,U29,0,0,0)';
      PINUSE='POWER';
      NO_LOAD_CHECK='Both';
      NO_IO_CHECK='Both';
      NO_ASSERT_CHECK='TRUE';
      NO_DIR_CHECK='TRUE';
      ALLOW_CONNECT='TRUE';
    'VCCP_1P8_FILTERED_W27':
      PIN_NUMBER='(0,0,0,0,0,0,0,W27,0,0,0)';
      PINUSE='POWER';
      NO_LOAD_CHECK='Both';
      NO_IO_CHECK='Both';
      NO_ASSERT_CHECK='TRUE';
      NO_DIR_CHECK='TRUE';
      ALLOW_CONNECT='TRUE';
    'VCCP_1P8_FILTERED_AB31':
      PIN_NUMBER='(0,0,0,0,0,0,0,AB31,0,0,0)';
      PINUSE='POWER';
      NO_LOAD_CHECK='Both';
      NO_IO_CHECK='Both';
      NO_ASSERT_CHECK='TRUE';
      NO_DIR_CHECK='TRUE';
      ALLOW_CONNECT='TRUE';
    'VCCP_3P3_P21':
      PIN_NUMBER='(0,0,0,0,0,0,0,P21,0,0,0)';
      PINUSE='POWER';
      NO_LOAD_CHECK='Both';
      NO_IO_CHECK='Both';
      NO_ASSERT_CHECK='TRUE';
      NO_DIR_CHECK='TRUE';
      ALLOW_CONNECT='TRUE';
    'VCCP_3P3_AL17':
      PIN_NUMBER='(0,0,0,0,0,0,0,AL17,0,0,0)';
      PINUSE='POWER';
      NO_LOAD_CHECK='Both';
      NO_IO_CHECK='Both';
      NO_ASSERT_CHECK='TRUE';
      NO_DIR_CHECK='TRUE';
      ALLOW_CONNECT='TRUE';
    'VCCP_3P3_AJ17':
      PIN_NUMBER='(0,0,0,0,0,0,0,AJ17,0,0,0)';
      PINUSE='POWER';
      NO_LOAD_CHECK='Both';
      NO_IO_CHECK='Both';
      NO_ASSERT_CHECK='TRUE';
      NO_DIR_CHECK='TRUE';
      ALLOW_CONNECT='TRUE';
    'VCCP_3P3_AG17':
      PIN_NUMBER='(0,0,0,0,0,0,0,AG17,0,0,0)';
      PINUSE='POWER';
      NO_LOAD_CHECK='Both';
      NO_IO_CHECK='Both';
      NO_ASSERT_CHECK='TRUE';
      NO_DIR_CHECK='TRUE';
      ALLOW_CONNECT='TRUE';
    'VCCP_3P3_AF17':
      PIN_NUMBER='(0,0,0,0,0,0,0,AF17,0,0,0)';
      PINUSE='POWER';
      NO_LOAD_CHECK='Both';
      NO_IO_CHECK='Both';
      NO_ASSERT_CHECK='TRUE';
      NO_DIR_CHECK='TRUE';
      ALLOW_CONNECT='TRUE';
    'VCCP_3P3_AK15':
      PIN_NUMBER='(0,0,0,0,0,0,0,AK15,0,0,0)';
      PINUSE='POWER';
      NO_LOAD_CHECK='Both';
      NO_IO_CHECK='Both';
      NO_ASSERT_CHECK='TRUE';
      NO_DIR_CHECK='TRUE';
      ALLOW_CONNECT='TRUE';
    'VCCP_3P3_DSW_AD15':
      PIN_NUMBER='(0,0,0,0,0,0,0,AD15,0,0,0)';
      PINUSE='POWER';
      NO_LOAD_CHECK='Both';
      NO_IO_CHECK='Both';
      NO_ASSERT_CHECK='TRUE';
      NO_DIR_CHECK='TRUE';
      ALLOW_CONNECT='TRUE';
    'VCCP_3P3_DSW_V15':
      PIN_NUMBER='(0,0,0,0,0,0,0,V15,0,0,0)';
      PINUSE='POWER';
      NO_LOAD_CHECK='Both';
      NO_IO_CHECK='Both';
      NO_ASSERT_CHECK='TRUE';
      NO_DIR_CHECK='TRUE';
      ALLOW_CONNECT='TRUE';
    'VCCP_GPPD_1P8_3P3':
      PIN_NUMBER='(0,0,0,0,0,0,0,T15,0,0,0)';
      PINUSE='POWER';
      NO_LOAD_CHECK='Both';
      NO_IO_CHECK='Both';
      NO_ASSERT_CHECK='TRUE';
      NO_DIR_CHECK='TRUE';
      ALLOW_CONNECT='TRUE';
    'VCCP_GPPE_1P8_3P3':
      PIN_NUMBER='(0,0,0,0,0,0,0,AN20,0,0,0)';
      PINUSE='POWER';
      NO_LOAD_CHECK='Both';
      NO_IO_CHECK='Both';
      NO_ASSERT_CHECK='TRUE';
      NO_DIR_CHECK='TRUE';
      ALLOW_CONNECT='TRUE';
    'VCCP_GPPI_1P8_3P3':
      PIN_NUMBER='(0,0,0,0,0,0,0,AD17,0,0,0)';
      PINUSE='POWER';
      NO_LOAD_CHECK='Both';
      NO_IO_CHECK='Both';
      NO_ASSERT_CHECK='TRUE';
      NO_DIR_CHECK='TRUE';
      ALLOW_CONNECT='TRUE';
    'VCCP_VNN_AR23':
      PIN_NUMBER='(0,0,0,0,0,0,0,AR23,0,0,0)';
      PINUSE='POWER';
      NO_LOAD_CHECK='Both';
      NO_IO_CHECK='Both';
      NO_ASSERT_CHECK='TRUE';
      NO_DIR_CHECK='TRUE';
      ALLOW_CONNECT='TRUE';
    'VCCP_VNN_AP21':
      PIN_NUMBER='(0,0,0,0,0,0,0,AP21,0,0,0)';
      PINUSE='POWER';
      NO_LOAD_CHECK='Both';
      NO_IO_CHECK='Both';
      NO_ASSERT_CHECK='TRUE';
      NO_DIR_CHECK='TRUE';
      ALLOW_CONNECT='TRUE';
    'VCCP_VNN_AN23':
      PIN_NUMBER='(0,0,0,0,0,0,0,AN23,0,0,0)';
      PINUSE='POWER';
      NO_LOAD_CHECK='Both';
      NO_IO_CHECK='Both';
      NO_ASSERT_CHECK='TRUE';
      NO_DIR_CHECK='TRUE';
      ALLOW_CONNECT='TRUE';
    'VCCP_VNN_AL22':
      PIN_NUMBER='(0,0,0,0,0,0,0,AL22,0,0,0)';
      PINUSE='POWER';
      NO_LOAD_CHECK='Both';
      NO_IO_CHECK='Both';
      NO_ASSERT_CHECK='TRUE';
      NO_DIR_CHECK='TRUE';
      ALLOW_CONNECT='TRUE';
    'VCCP_VNN_AL20':
      PIN_NUMBER='(0,0,0,0,0,0,0,AL20,0,0,0)';
      PINUSE='POWER';
      NO_LOAD_CHECK='Both';
      NO_IO_CHECK='Both';
      NO_ASSERT_CHECK='TRUE';
      NO_DIR_CHECK='TRUE';
      ALLOW_CONNECT='TRUE';
    'VCCP_VNN_AJ22':
      PIN_NUMBER='(0,0,0,0,0,0,0,AJ22,0,0,0)';
      PINUSE='POWER';
      NO_LOAD_CHECK='Both';
      NO_IO_CHECK='Both';
      NO_ASSERT_CHECK='TRUE';
      NO_DIR_CHECK='TRUE';
      ALLOW_CONNECT='TRUE';
    'VCCP_VNN_AJ20':
      PIN_NUMBER='(0,0,0,0,0,0,0,AJ20,0,0,0)';
      PINUSE='POWER';
      NO_LOAD_CHECK='Both';
      NO_IO_CHECK='Both';
      NO_ASSERT_CHECK='TRUE';
      NO_DIR_CHECK='TRUE';
      ALLOW_CONNECT='TRUE';
    'VCCP_VNN_AG22':
      PIN_NUMBER='(0,0,0,0,0,0,0,AG22,0,0,0)';
      PINUSE='POWER';
      NO_LOAD_CHECK='Both';
      NO_IO_CHECK='Both';
      NO_ASSERT_CHECK='TRUE';
      NO_DIR_CHECK='TRUE';
      ALLOW_CONNECT='TRUE';
    'VCCP_VNN_AG20':
      PIN_NUMBER='(0,0,0,0,0,0,0,AG20,0,0,0)';
      PINUSE='POWER';
      NO_LOAD_CHECK='Both';
      NO_IO_CHECK='Both';
      NO_ASSERT_CHECK='TRUE';
      NO_DIR_CHECK='TRUE';
      ALLOW_CONNECT='TRUE';
    'VCCP_VNN_AF22':
      PIN_NUMBER='(0,0,0,0,0,0,0,AF22,0,0,0)';
      PINUSE='POWER';
      NO_LOAD_CHECK='Both';
      NO_IO_CHECK='Both';
      NO_ASSERT_CHECK='TRUE';
      NO_DIR_CHECK='TRUE';
      ALLOW_CONNECT='TRUE';
    'VCCP_VNN_AF20':
      PIN_NUMBER='(0,0,0,0,0,0,0,AF20,0,0,0)';
      PINUSE='POWER';
      NO_LOAD_CHECK='Both';
      NO_IO_CHECK='Both';
      NO_ASSERT_CHECK='TRUE';
      NO_DIR_CHECK='TRUE';
      ALLOW_CONNECT='TRUE';
    'VCCRTC':
      PIN_NUMBER='(0,0,0,0,0,0,0,AH15,0,0,0)';
      PINUSE='POWER';
      NO_LOAD_CHECK='Both';
      NO_IO_CHECK='Both';
      NO_ASSERT_CHECK='TRUE';
      NO_DIR_CHECK='TRUE';
      ALLOW_CONNECT='TRUE';
    'VSS_BG40':
      PIN_NUMBER='(0,0,0,0,0,0,0,BG40,0,0,0)';
      PINUSE='POWER';
      NO_LOAD_CHECK='Both';
      NO_IO_CHECK='Both';
      NO_ASSERT_CHECK='TRUE';
      NO_DIR_CHECK='TRUE';
      ALLOW_CONNECT='TRUE';
    'GPIO_RCOMP_1P8_3P3':
      PIN_NUMBER='(0,0,0,0,0,0,0,0,AC13,0,0)';
      INPUT_LOAD='(-0.01,0.01)';
      PINUSE='IN';
    'RSVD_L13':
      PIN_NUMBER='(0,0,0,0,0,0,0,0,L13,0,0)';
      OUTPUT_TYPE='(TS,TS)';
      INPUT_LOAD='(-0.01,0.01)';
      OUTPUT_LOAD='(1.0,-1.0)';
      PINUSE='TRI';
    'RSVD_N13':
      PIN_NUMBER='(0,0,0,0,0,0,0,0,N13,0,0)';
      OUTPUT_TYPE='(TS,TS)';
      INPUT_LOAD='(-0.01,0.01)';
      OUTPUT_LOAD='(1.0,-1.0)';
      PINUSE='TRI';
    'RSVD_BB43':
      PIN_NUMBER='(0,0,0,0,0,0,0,0,BB43,0,0)';
      OUTPUT_TYPE='(TS,TS)';
      INPUT_LOAD='(-0.01,0.01)';
      OUTPUT_LOAD='(1.0,-1.0)';
      PINUSE='TRI';
    'RSVD_P18':
      PIN_NUMBER='(0,0,0,0,0,0,0,0,P18,0,0)';
      OUTPUT_TYPE='(TS,TS)';
      INPUT_LOAD='(-0.01,0.01)';
      OUTPUT_LOAD='(1.0,-1.0)';
      PINUSE='TRI';
    'RSVD_A4':
      PIN_NUMBER='(0,0,0,0,0,0,0,0,A4,0,0)';
      OUTPUT_TYPE='(TS,TS)';
      INPUT_LOAD='(-0.01,0.01)';
      OUTPUT_LOAD='(1.0,-1.0)';
      PINUSE='TRI';
    'RSVD_F1':
      PIN_NUMBER='(0,0,0,0,0,0,0,0,F1,0,0)';
      OUTPUT_TYPE='(TS,TS)';
      INPUT_LOAD='(-0.01,0.01)';
      OUTPUT_LOAD='(1.0,-1.0)';
      PINUSE='TRI';
    'RSVD_H1':
      PIN_NUMBER='(0,0,0,0,0,0,0,0,H1,0,0)';
      OUTPUT_TYPE='(TS,TS)';
      INPUT_LOAD='(-0.01,0.01)';
      OUTPUT_LOAD='(1.0,-1.0)';
      PINUSE='TRI';
    'VSS_Y8':
      PIN_NUMBER='(0,0,0,0,0,0,0,0,0,Y8,0)';
      PINUSE='POWER';
      NO_LOAD_CHECK='Both';
      NO_IO_CHECK='Both';
      NO_ASSERT_CHECK='TRUE';
      NO_DIR_CHECK='TRUE';
      ALLOW_CONNECT='TRUE';
    'VSS_Y34':
      PIN_NUMBER='(0,0,0,0,0,0,0,0,0,Y34,0)';
      PINUSE='POWER';
      NO_LOAD_CHECK='Both';
      NO_IO_CHECK='Both';
      NO_ASSERT_CHECK='TRUE';
      NO_DIR_CHECK='TRUE';
      ALLOW_CONNECT='TRUE';
    'VSS_Y31':
      PIN_NUMBER='(0,0,0,0,0,0,0,0,0,Y31,0)';
      PINUSE='POWER';
      NO_LOAD_CHECK='Both';
      NO_IO_CHECK='Both';
      NO_ASSERT_CHECK='TRUE';
      NO_DIR_CHECK='TRUE';
      ALLOW_CONNECT='TRUE';
    'VSS_Y15':
      PIN_NUMBER='(0,0,0,0,0,0,0,0,0,Y15,0)';
      PINUSE='POWER';
      NO_LOAD_CHECK='Both';
      NO_IO_CHECK='Both';
      NO_ASSERT_CHECK='TRUE';
      NO_DIR_CHECK='TRUE';
      ALLOW_CONNECT='TRUE';
    'VSS_Y11':
      PIN_NUMBER='(0,0,0,0,0,0,0,0,0,Y11,0)';
      PINUSE='POWER';
      NO_LOAD_CHECK='Both';
      NO_IO_CHECK='Both';
      NO_ASSERT_CHECK='TRUE';
      NO_DIR_CHECK='TRUE';
      ALLOW_CONNECT='TRUE';
    'VSS_W5':
      PIN_NUMBER='(0,0,0,0,0,0,0,0,0,W5,0)';
      PINUSE='POWER';
      NO_LOAD_CHECK='Both';
      NO_IO_CHECK='Both';
      NO_ASSERT_CHECK='TRUE';
      NO_DIR_CHECK='TRUE';
      ALLOW_CONNECT='TRUE';
    'VSS_W39':
      PIN_NUMBER='(0,0,0,0,0,0,0,0,0,W39,0)';
      PINUSE='POWER';
      NO_LOAD_CHECK='Both';
      NO_IO_CHECK='Both';
      NO_ASSERT_CHECK='TRUE';
      NO_DIR_CHECK='TRUE';
      ALLOW_CONNECT='TRUE';
    'VSS_W3':
      PIN_NUMBER='(0,0,0,0,0,0,0,0,0,W3,0)';
      PINUSE='POWER';
      NO_LOAD_CHECK='Both';
      NO_IO_CHECK='Both';
      NO_ASSERT_CHECK='TRUE';
      NO_DIR_CHECK='TRUE';
      ALLOW_CONNECT='TRUE';
    'VSS_W25':
      PIN_NUMBER='(0,0,0,0,0,0,0,0,0,W25,0)';
      PINUSE='POWER';
      NO_LOAD_CHECK='Both';
      NO_IO_CHECK='Both';
      NO_ASSERT_CHECK='TRUE';
      NO_DIR_CHECK='TRUE';
      ALLOW_CONNECT='TRUE';
    'VSS_V31':
      PIN_NUMBER='(0,0,0,0,0,0,0,0,0,V31,0)';
      PINUSE='POWER';
      NO_LOAD_CHECK='Both';
      NO_IO_CHECK='Both';
      NO_ASSERT_CHECK='TRUE';
      NO_DIR_CHECK='TRUE';
      ALLOW_CONNECT='TRUE';
    'VSS_V2':
      PIN_NUMBER='(0,0,0,0,0,0,0,0,0,V2,0)';
      PINUSE='POWER';
      NO_LOAD_CHECK='Both';
      NO_IO_CHECK='Both';
      NO_ASSERT_CHECK='TRUE';
      NO_DIR_CHECK='TRUE';
      ALLOW_CONNECT='TRUE';
    'VSS_U5':
      PIN_NUMBER='(0,0,0,0,0,0,0,0,0,U5,0)';
      PINUSE='POWER';
      NO_LOAD_CHECK='Both';
      NO_IO_CHECK='Both';
      NO_ASSERT_CHECK='TRUE';
      NO_DIR_CHECK='TRUE';
      ALLOW_CONNECT='TRUE';
    'VSS_U39':
      PIN_NUMBER='(0,0,0,0,0,0,0,0,0,U39,0)';
      PINUSE='POWER';
      NO_LOAD_CHECK='Both';
      NO_IO_CHECK='Both';
      NO_ASSERT_CHECK='TRUE';
      NO_DIR_CHECK='TRUE';
      ALLOW_CONNECT='TRUE';
    'VSS_U25':
      PIN_NUMBER='(0,0,0,0,0,0,0,0,0,U25,0)';
      PINUSE='POWER';
      NO_LOAD_CHECK='Both';
      NO_IO_CHECK='Both';
      NO_ASSERT_CHECK='TRUE';
      NO_DIR_CHECK='TRUE';
      ALLOW_CONNECT='TRUE';
    'VSS_U13':
      PIN_NUMBER='(0,0,0,0,0,0,0,0,0,U13,0)';
      PINUSE='POWER';
      NO_LOAD_CHECK='Both';
      NO_IO_CHECK='Both';
      NO_ASSERT_CHECK='TRUE';
      NO_DIR_CHECK='TRUE';
      ALLOW_CONNECT='TRUE';
    'VSS_U10':
      PIN_NUMBER='(0,0,0,0,0,0,0,0,0,U10,0)';
      PINUSE='POWER';
      NO_LOAD_CHECK='Both';
      NO_IO_CHECK='Both';
      NO_ASSERT_CHECK='TRUE';
      NO_DIR_CHECK='TRUE';
      ALLOW_CONNECT='TRUE';
    'VSS_T31':
      PIN_NUMBER='(0,0,0,0,0,0,0,0,0,T31,0)';
      PINUSE='POWER';
      NO_LOAD_CHECK='Both';
      NO_IO_CHECK='Both';
      NO_ASSERT_CHECK='TRUE';
      NO_DIR_CHECK='TRUE';
      ALLOW_CONNECT='TRUE';
    'VSS_R36':
      PIN_NUMBER='(0,0,0,0,0,0,0,0,0,R36,0)';
      PINUSE='POWER';
      NO_LOAD_CHECK='Both';
      NO_IO_CHECK='Both';
      NO_ASSERT_CHECK='TRUE';
      NO_DIR_CHECK='TRUE';
      ALLOW_CONNECT='TRUE';
    'VSS_R20':
      PIN_NUMBER='(0,0,0,0,0,0,0,0,0,R20,0)';
      PINUSE='POWER';
      NO_LOAD_CHECK='Both';
      NO_IO_CHECK='Both';
      NO_ASSERT_CHECK='TRUE';
      NO_DIR_CHECK='TRUE';
      ALLOW_CONNECT='TRUE';
    'VSS_R16':
      PIN_NUMBER='(0,0,0,0,0,0,0,0,0,R16,0)';
      PINUSE='POWER';
      NO_LOAD_CHECK='Both';
      NO_IO_CHECK='Both';
      NO_ASSERT_CHECK='TRUE';
      NO_DIR_CHECK='TRUE';
      ALLOW_CONNECT='TRUE';
    'VSS_R13':
      PIN_NUMBER='(0,0,0,0,0,0,0,0,0,R13,0)';
      PINUSE='POWER';
      NO_LOAD_CHECK='Both';
      NO_IO_CHECK='Both';
      NO_ASSERT_CHECK='TRUE';
      NO_DIR_CHECK='TRUE';
      ALLOW_CONNECT='TRUE';
    'VSS_P8':
      PIN_NUMBER='(0,0,0,0,0,0,0,0,0,P8,0)';
      PINUSE='POWER';
      NO_LOAD_CHECK='Both';
      NO_IO_CHECK='Both';
      NO_ASSERT_CHECK='TRUE';
      NO_DIR_CHECK='TRUE';
      ALLOW_CONNECT='TRUE';
    'VSS_P5':
      PIN_NUMBER='(0,0,0,0,0,0,0,0,0,P5,0)';
      PINUSE='POWER';
      NO_LOAD_CHECK='Both';
      NO_IO_CHECK='Both';
      NO_ASSERT_CHECK='TRUE';
      NO_DIR_CHECK='TRUE';
      ALLOW_CONNECT='TRUE';
    'VSS_P43':
      PIN_NUMBER='(0,0,0,0,0,0,0,0,0,P43,0)';
      PINUSE='POWER';
      NO_LOAD_CHECK='Both';
      NO_IO_CHECK='Both';
      NO_ASSERT_CHECK='TRUE';
      NO_DIR_CHECK='TRUE';
      ALLOW_CONNECT='TRUE';
    'VSS_P41':
      PIN_NUMBER='(0,0,0,0,0,0,0,0,0,P41,0)';
      PINUSE='POWER';
      NO_LOAD_CHECK='Both';
      NO_IO_CHECK='Both';
      NO_ASSERT_CHECK='TRUE';
      NO_DIR_CHECK='TRUE';
      ALLOW_CONNECT='TRUE';
    'VSS_P39':
      PIN_NUMBER='(0,0,0,0,0,0,0,0,0,P39,0)';
      PINUSE='POWER';
      NO_LOAD_CHECK='Both';
      NO_IO_CHECK='Both';
      NO_ASSERT_CHECK='TRUE';
      NO_DIR_CHECK='TRUE';
      ALLOW_CONNECT='TRUE';
    'VSS_P37':
      PIN_NUMBER='(0,0,0,0,0,0,0,0,0,P37,0)';
      PINUSE='POWER';
      NO_LOAD_CHECK='Both';
      NO_IO_CHECK='Both';
      NO_ASSERT_CHECK='TRUE';
      NO_DIR_CHECK='TRUE';
      ALLOW_CONNECT='TRUE';
    'VSS_P31':
      PIN_NUMBER='(0,0,0,0,0,0,0,0,0,P31,0)';
      PINUSE='POWER';
      NO_LOAD_CHECK='Both';
      NO_IO_CHECK='Both';
      NO_ASSERT_CHECK='TRUE';
      NO_DIR_CHECK='TRUE';
      ALLOW_CONNECT='TRUE';
    'VSS_P28':
      PIN_NUMBER='(0,0,0,0,0,0,0,0,0,P28,0)';
      PINUSE='POWER';
      NO_LOAD_CHECK='Both';
      NO_IO_CHECK='Both';
      NO_ASSERT_CHECK='TRUE';
      NO_DIR_CHECK='TRUE';
      ALLOW_CONNECT='TRUE';
    'VSS_P24':
      PIN_NUMBER='(0,0,0,0,0,0,0,0,0,P24,0)';
      PINUSE='POWER';
      NO_LOAD_CHECK='Both';
      NO_IO_CHECK='Both';
      NO_ASSERT_CHECK='TRUE';
      NO_DIR_CHECK='TRUE';
      ALLOW_CONNECT='TRUE';
    'VSS_P11':
      PIN_NUMBER='(0,0,0,0,0,0,0,0,0,P11,0)';
      PINUSE='POWER';
      NO_LOAD_CHECK='Both';
      NO_IO_CHECK='Both';
      NO_ASSERT_CHECK='TRUE';
      NO_DIR_CHECK='TRUE';
      ALLOW_CONNECT='TRUE';
    'VSS_N32':
      PIN_NUMBER='(0,0,0,0,0,0,0,0,0,N32,0)';
      PINUSE='POWER';
      NO_LOAD_CHECK='Both';
      NO_IO_CHECK='Both';
      NO_ASSERT_CHECK='TRUE';
      NO_DIR_CHECK='TRUE';
      ALLOW_CONNECT='TRUE';
    'VSS_N16':
      PIN_NUMBER='(0,0,0,0,0,0,0,0,0,N16,0)';
      PINUSE='POWER';
      NO_LOAD_CHECK='Both';
      NO_IO_CHECK='Both';
      NO_ASSERT_CHECK='TRUE';
      NO_DIR_CHECK='TRUE';
      ALLOW_CONNECT='TRUE';
    'VSS_M5':
      PIN_NUMBER='(0,0,0,0,0,0,0,0,0,M5,0)';
      PINUSE='POWER';
      NO_LOAD_CHECK='Both';
      NO_IO_CHECK='Both';
      NO_ASSERT_CHECK='TRUE';
      NO_DIR_CHECK='TRUE';
      ALLOW_CONNECT='TRUE';
    'VSS_M39':
      PIN_NUMBER='(0,0,0,0,0,0,0,0,0,M39,0)';
      PINUSE='POWER';
      NO_LOAD_CHECK='Both';
      NO_IO_CHECK='Both';
      NO_ASSERT_CHECK='TRUE';
      NO_DIR_CHECK='TRUE';
      ALLOW_CONNECT='TRUE';
    'VSS_M37':
      PIN_NUMBER='(0,0,0,0,0,0,0,0,0,M37,0)';
      PINUSE='POWER';
      NO_LOAD_CHECK='Both';
      NO_IO_CHECK='Both';
      NO_ASSERT_CHECK='TRUE';
      NO_DIR_CHECK='TRUE';
      ALLOW_CONNECT='TRUE';
    'VSS_M34':
      PIN_NUMBER='(0,0,0,0,0,0,0,0,0,M34,0)';
      PINUSE='POWER';
      NO_LOAD_CHECK='Both';
      NO_IO_CHECK='Both';
      NO_ASSERT_CHECK='TRUE';
      NO_DIR_CHECK='TRUE';
      ALLOW_CONNECT='TRUE';
    'VSS_M31':
      PIN_NUMBER='(0,0,0,0,0,0,0,0,0,M31,0)';
      PINUSE='POWER';
      NO_LOAD_CHECK='Both';
      NO_IO_CHECK='Both';
      NO_ASSERT_CHECK='TRUE';
      NO_DIR_CHECK='TRUE';
      ALLOW_CONNECT='TRUE';
    'VSS_M3':
      PIN_NUMBER='(0,0,0,0,0,0,0,0,0,M3,0)';
      PINUSE='POWER';
      NO_LOAD_CHECK='Both';
      NO_IO_CHECK='Both';
      NO_ASSERT_CHECK='TRUE';
      NO_DIR_CHECK='TRUE';
      ALLOW_CONNECT='TRUE';
    'VSS_M28':
      PIN_NUMBER='(0,0,0,0,0,0,0,0,0,M28,0)';
      PINUSE='POWER';
      NO_LOAD_CHECK='Both';
      NO_IO_CHECK='Both';
      NO_ASSERT_CHECK='TRUE';
      NO_DIR_CHECK='TRUE';
      ALLOW_CONNECT='TRUE';
    'VSS_M21':
      PIN_NUMBER='(0,0,0,0,0,0,0,0,0,M21,0)';
      PINUSE='POWER';
      NO_LOAD_CHECK='Both';
      NO_IO_CHECK='Both';
      NO_ASSERT_CHECK='TRUE';
      NO_DIR_CHECK='TRUE';
      ALLOW_CONNECT='TRUE';
    'VSS_M18':
      PIN_NUMBER='(0,0,0,0,0,0,0,0,0,M18,0)';
      PINUSE='POWER';
      NO_LOAD_CHECK='Both';
      NO_IO_CHECK='Both';
      NO_ASSERT_CHECK='TRUE';
      NO_DIR_CHECK='TRUE';
      ALLOW_CONNECT='TRUE';
    'VSS_M15':
      PIN_NUMBER='(0,0,0,0,0,0,0,0,0,M15,0)';
      PINUSE='POWER';
      NO_LOAD_CHECK='Both';
      NO_IO_CHECK='Both';
      NO_ASSERT_CHECK='TRUE';
      NO_DIR_CHECK='TRUE';
      ALLOW_CONNECT='TRUE';
    'VSS_M11':
      PIN_NUMBER='(0,0,0,0,0,0,0,0,0,M11,0)';
      PINUSE='POWER';
      NO_LOAD_CHECK='Both';
      NO_IO_CHECK='Both';
      NO_ASSERT_CHECK='TRUE';
      NO_DIR_CHECK='TRUE';
      ALLOW_CONNECT='TRUE';
    'VSS_M1':
      PIN_NUMBER='(0,0,0,0,0,0,0,0,0,M1,0)';
      PINUSE='POWER';
      NO_LOAD_CHECK='Both';
      NO_IO_CHECK='Both';
      NO_ASSERT_CHECK='TRUE';
      NO_DIR_CHECK='TRUE';
      ALLOW_CONNECT='TRUE';
    'VSS_L36':
      PIN_NUMBER='(0,0,0,0,0,0,0,0,0,L36,0)';
      PINUSE='POWER';
      NO_LOAD_CHECK='Both';
      NO_IO_CHECK='Both';
      NO_ASSERT_CHECK='TRUE';
      NO_DIR_CHECK='TRUE';
      ALLOW_CONNECT='TRUE';
    'VSS_L29':
      PIN_NUMBER='(0,0,0,0,0,0,0,0,0,L29,0)';
      PINUSE='POWER';
      NO_LOAD_CHECK='Both';
      NO_IO_CHECK='Both';
      NO_ASSERT_CHECK='TRUE';
      NO_DIR_CHECK='TRUE';
      ALLOW_CONNECT='TRUE';
    'VSS_L26':
      PIN_NUMBER='(0,0,0,0,0,0,0,0,0,L26,0)';
      PINUSE='POWER';
      NO_LOAD_CHECK='Both';
      NO_IO_CHECK='Both';
      NO_ASSERT_CHECK='TRUE';
      NO_DIR_CHECK='TRUE';
      ALLOW_CONNECT='TRUE';
    'VSS_L23':
      PIN_NUMBER='(0,0,0,0,0,0,0,0,0,L23,0)';
      PINUSE='POWER';
      NO_LOAD_CHECK='Both';
      NO_IO_CHECK='Both';
      NO_ASSERT_CHECK='TRUE';
      NO_DIR_CHECK='TRUE';
      ALLOW_CONNECT='TRUE';
    'VSS_L20':
      PIN_NUMBER='(0,0,0,0,0,0,0,0,0,L20,0)';
      PINUSE='POWER';
      NO_LOAD_CHECK='Both';
      NO_IO_CHECK='Both';
      NO_ASSERT_CHECK='TRUE';
      NO_DIR_CHECK='TRUE';
      ALLOW_CONNECT='TRUE';
    'VSS_L16':
      PIN_NUMBER='(0,0,0,0,0,0,0,0,0,L16,0)';
      PINUSE='POWER';
      NO_LOAD_CHECK='Both';
      NO_IO_CHECK='Both';
      NO_ASSERT_CHECK='TRUE';
      NO_DIR_CHECK='TRUE';
      ALLOW_CONNECT='TRUE';
    'VSS_L10':
      PIN_NUMBER='(0,0,0,0,0,0,0,0,0,L10,0)';
      PINUSE='POWER';
      NO_LOAD_CHECK='Both';
      NO_IO_CHECK='Both';
      NO_ASSERT_CHECK='TRUE';
      NO_DIR_CHECK='TRUE';
      ALLOW_CONNECT='TRUE';
    'VSS_K5':
      PIN_NUMBER='(0,0,0,0,0,0,0,0,0,K5,0)';
      PINUSE='POWER';
      NO_LOAD_CHECK='Both';
      NO_IO_CHECK='Both';
      NO_ASSERT_CHECK='TRUE';
      NO_DIR_CHECK='TRUE';
      ALLOW_CONNECT='TRUE';
    'VSS_K39':
      PIN_NUMBER='(0,0,0,0,0,0,0,0,0,K39,0)';
      PINUSE='POWER';
      NO_LOAD_CHECK='Both';
      NO_IO_CHECK='Both';
      NO_ASSERT_CHECK='TRUE';
      NO_DIR_CHECK='TRUE';
      ALLOW_CONNECT='TRUE';
    'VSS_K34':
      PIN_NUMBER='(0,0,0,0,0,0,0,0,0,K34,0)';
      PINUSE='POWER';
      NO_LOAD_CHECK='Both';
      NO_IO_CHECK='Both';
      NO_ASSERT_CHECK='TRUE';
      NO_DIR_CHECK='TRUE';
      ALLOW_CONNECT='TRUE';
    'VSS_K24':
      PIN_NUMBER='(0,0,0,0,0,0,0,0,0,K24,0)';
      PINUSE='POWER';
      NO_LOAD_CHECK='Both';
      NO_IO_CHECK='Both';
      NO_ASSERT_CHECK='TRUE';
      NO_DIR_CHECK='TRUE';
      ALLOW_CONNECT='TRUE';
    'VSS_K15':
      PIN_NUMBER='(0,0,0,0,0,0,0,0,0,K15,0)';
      PINUSE='POWER';
      NO_LOAD_CHECK='Both';
      NO_IO_CHECK='Both';
      NO_ASSERT_CHECK='TRUE';
      NO_DIR_CHECK='TRUE';
      ALLOW_CONNECT='TRUE';
    'VSS_K11':
      PIN_NUMBER='(0,0,0,0,0,0,0,0,0,K11,0)';
      PINUSE='POWER';
      NO_LOAD_CHECK='Both';
      NO_IO_CHECK='Both';
      NO_ASSERT_CHECK='TRUE';
      NO_DIR_CHECK='TRUE';
      ALLOW_CONNECT='TRUE';
    'VSS_J26':
      PIN_NUMBER='(0,0,0,0,0,0,0,0,0,J26,0)';
      PINUSE='POWER';
      NO_LOAD_CHECK='Both';
      NO_IO_CHECK='Both';
      NO_ASSERT_CHECK='TRUE';
      NO_DIR_CHECK='TRUE';
      ALLOW_CONNECT='TRUE';
    'VSS_J20':
      PIN_NUMBER='(0,0,0,0,0,0,0,0,0,J20,0)';
      PINUSE='POWER';
      NO_LOAD_CHECK='Both';
      NO_IO_CHECK='Both';
      NO_ASSERT_CHECK='TRUE';
      NO_DIR_CHECK='TRUE';
      ALLOW_CONNECT='TRUE';
    'VSS_J13':
      PIN_NUMBER='(0,0,0,0,0,0,0,0,0,J13,0)';
      PINUSE='POWER';
      NO_LOAD_CHECK='Both';
      NO_IO_CHECK='Both';
      NO_ASSERT_CHECK='TRUE';
      NO_DIR_CHECK='TRUE';
      ALLOW_CONNECT='TRUE';
    'VSS_H8':
      PIN_NUMBER='(0,0,0,0,0,0,0,0,0,H8,0)';
      PINUSE='POWER';
      NO_LOAD_CHECK='Both';
      NO_IO_CHECK='Both';
      NO_ASSERT_CHECK='TRUE';
      NO_DIR_CHECK='TRUE';
      ALLOW_CONNECT='TRUE';
    'VSS_H5':
      PIN_NUMBER='(0,0,0,0,0,0,0,0,0,H5,0)';
      PINUSE='POWER';
      NO_LOAD_CHECK='Both';
      NO_IO_CHECK='Both';
      NO_ASSERT_CHECK='TRUE';
      NO_DIR_CHECK='TRUE';
      ALLOW_CONNECT='TRUE';
    'VSS_H39':
      PIN_NUMBER='(0,0,0,0,0,0,0,0,0,H39,0)';
      PINUSE='POWER';
      NO_LOAD_CHECK='Both';
      NO_IO_CHECK='Both';
      NO_ASSERT_CHECK='TRUE';
      NO_DIR_CHECK='TRUE';
      ALLOW_CONNECT='TRUE';
    'VSS_G26':
      PIN_NUMBER='(0,0,0,0,0,0,0,0,0,G26,0)';
      PINUSE='POWER';
      NO_LOAD_CHECK='Both';
      NO_IO_CHECK='Both';
      NO_ASSERT_CHECK='TRUE';
      NO_DIR_CHECK='TRUE';
      ALLOW_CONNECT='TRUE';
    'VSS_G20':
      PIN_NUMBER='(0,0,0,0,0,0,0,0,0,G20,0)';
      PINUSE='POWER';
      NO_LOAD_CHECK='Both';
      NO_IO_CHECK='Both';
      NO_ASSERT_CHECK='TRUE';
      NO_DIR_CHECK='TRUE';
      ALLOW_CONNECT='TRUE';
    'VSS_G13':
      PIN_NUMBER='(0,0,0,0,0,0,0,0,0,G13,0)';
      PINUSE='POWER';
      NO_LOAD_CHECK='Both';
      NO_IO_CHECK='Both';
      NO_ASSERT_CHECK='TRUE';
      NO_DIR_CHECK='TRUE';
      ALLOW_CONNECT='TRUE';
    'VSS_F39':
      PIN_NUMBER='(0,0,0,0,0,0,0,0,0,F39,0)';
      PINUSE='POWER';
      NO_LOAD_CHECK='Both';
      NO_IO_CHECK='Both';
      NO_ASSERT_CHECK='TRUE';
      NO_DIR_CHECK='TRUE';
      ALLOW_CONNECT='TRUE';
    'VSS_F34':
      PIN_NUMBER='(0,0,0,0,0,0,0,0,0,F34,0)';
      PINUSE='POWER';
      NO_LOAD_CHECK='Both';
      NO_IO_CHECK='Both';
      NO_ASSERT_CHECK='TRUE';
      NO_DIR_CHECK='TRUE';
      ALLOW_CONNECT='TRUE';
    'VSS_F31':
      PIN_NUMBER='(0,0,0,0,0,0,0,0,0,F31,0)';
      PINUSE='POWER';
      NO_LOAD_CHECK='Both';
      NO_IO_CHECK='Both';
      NO_ASSERT_CHECK='TRUE';
      NO_DIR_CHECK='TRUE';
      ALLOW_CONNECT='TRUE';
    'VSS_F24':
      PIN_NUMBER='(0,0,0,0,0,0,0,0,0,F24,0)';
      PINUSE='POWER';
      NO_LOAD_CHECK='Both';
      NO_IO_CHECK='Both';
      NO_ASSERT_CHECK='TRUE';
      NO_DIR_CHECK='TRUE';
      ALLOW_CONNECT='TRUE';
    'VSS_F15':
      PIN_NUMBER='(0,0,0,0,0,0,0,0,0,F15,0)';
      PINUSE='POWER';
      NO_LOAD_CHECK='Both';
      NO_IO_CHECK='Both';
      NO_ASSERT_CHECK='TRUE';
      NO_DIR_CHECK='TRUE';
      ALLOW_CONNECT='TRUE';
    'VSS_E6':
      PIN_NUMBER='(0,0,0,0,0,0,0,0,0,E6,0)';
      PINUSE='POWER';
      NO_LOAD_CHECK='Both';
      NO_IO_CHECK='Both';
      NO_ASSERT_CHECK='TRUE';
      NO_DIR_CHECK='TRUE';
      ALLOW_CONNECT='TRUE';
    'VSS_E38':
      PIN_NUMBER='(0,0,0,0,0,0,0,0,0,E38,0)';
      PINUSE='POWER';
      NO_LOAD_CHECK='Both';
      NO_IO_CHECK='Both';
      NO_ASSERT_CHECK='TRUE';
      NO_DIR_CHECK='TRUE';
      ALLOW_CONNECT='TRUE';
    'VSS_E36':
      PIN_NUMBER='(0,0,0,0,0,0,0,0,0,E36,0)';
      PINUSE='POWER';
      NO_LOAD_CHECK='Both';
      NO_IO_CHECK='Both';
      NO_ASSERT_CHECK='TRUE';
      NO_DIR_CHECK='TRUE';
      ALLOW_CONNECT='TRUE';
    'VSS_E34':
      PIN_NUMBER='(0,0,0,0,0,0,0,0,0,E34,0)';
      PINUSE='POWER';
      NO_LOAD_CHECK='Both';
      NO_IO_CHECK='Both';
      NO_ASSERT_CHECK='TRUE';
      NO_DIR_CHECK='TRUE';
      ALLOW_CONNECT='TRUE';
    'VSS_E32':
      PIN_NUMBER='(0,0,0,0,0,0,0,0,0,E32,0)';
      PINUSE='POWER';
      NO_LOAD_CHECK='Both';
      NO_IO_CHECK='Both';
      NO_ASSERT_CHECK='TRUE';
      NO_DIR_CHECK='TRUE';
      ALLOW_CONNECT='TRUE';
    'VSS_E30':
      PIN_NUMBER='(0,0,0,0,0,0,0,0,0,E30,0)';
      PINUSE='POWER';
      NO_LOAD_CHECK='Both';
      NO_IO_CHECK='Both';
      NO_ASSERT_CHECK='TRUE';
      NO_DIR_CHECK='TRUE';
      ALLOW_CONNECT='TRUE';
    'VSS_E28':
      PIN_NUMBER='(0,0,0,0,0,0,0,0,0,E28,0)';
      PINUSE='POWER';
      NO_LOAD_CHECK='Both';
      NO_IO_CHECK='Both';
      NO_ASSERT_CHECK='TRUE';
      NO_DIR_CHECK='TRUE';
      ALLOW_CONNECT='TRUE';
    'VSS_E26':
      PIN_NUMBER='(0,0,0,0,0,0,0,0,0,E26,0)';
      PINUSE='POWER';
      NO_LOAD_CHECK='Both';
      NO_IO_CHECK='Both';
      NO_ASSERT_CHECK='TRUE';
      NO_DIR_CHECK='TRUE';
      ALLOW_CONNECT='TRUE';
    'VSS_E24':
      PIN_NUMBER='(0,0,0,0,0,0,0,0,0,E24,0)';
      PINUSE='POWER';
      NO_LOAD_CHECK='Both';
      NO_IO_CHECK='Both';
      NO_ASSERT_CHECK='TRUE';
      NO_DIR_CHECK='TRUE';
      ALLOW_CONNECT='TRUE';
    'VSS_E22':
      PIN_NUMBER='(0,0,0,0,0,0,0,0,0,E22,0)';
      PINUSE='POWER';
      NO_LOAD_CHECK='Both';
      NO_IO_CHECK='Both';
      NO_ASSERT_CHECK='TRUE';
      NO_DIR_CHECK='TRUE';
      ALLOW_CONNECT='TRUE';
    'VSS_E20':
      PIN_NUMBER='(0,0,0,0,0,0,0,0,0,E20,0)';
      PINUSE='POWER';
      NO_LOAD_CHECK='Both';
      NO_IO_CHECK='Both';
      NO_ASSERT_CHECK='TRUE';
      NO_DIR_CHECK='TRUE';
      ALLOW_CONNECT='TRUE';
    'VSS_E18':
      PIN_NUMBER='(0,0,0,0,0,0,0,0,0,E18,0)';
      PINUSE='POWER';
      NO_LOAD_CHECK='Both';
      NO_IO_CHECK='Both';
      NO_ASSERT_CHECK='TRUE';
      NO_DIR_CHECK='TRUE';
      ALLOW_CONNECT='TRUE';
    'VSS_E16':
      PIN_NUMBER='(0,0,0,0,0,0,0,0,0,E16,0)';
      PINUSE='POWER';
      NO_LOAD_CHECK='Both';
      NO_IO_CHECK='Both';
      NO_ASSERT_CHECK='TRUE';
      NO_DIR_CHECK='TRUE';
      ALLOW_CONNECT='TRUE';
    'VSS_E14':
      PIN_NUMBER='(0,0,0,0,0,0,0,0,0,E14,0)';
      PINUSE='POWER';
      NO_LOAD_CHECK='Both';
      NO_IO_CHECK='Both';
      NO_ASSERT_CHECK='TRUE';
      NO_DIR_CHECK='TRUE';
      ALLOW_CONNECT='TRUE';
    'VSS_E12':
      PIN_NUMBER='(0,0,0,0,0,0,0,0,0,E12,0)';
      PINUSE='POWER';
      NO_LOAD_CHECK='Both';
      NO_IO_CHECK='Both';
      NO_ASSERT_CHECK='TRUE';
      NO_DIR_CHECK='TRUE';
      ALLOW_CONNECT='TRUE';
    'VSS_E10':
      PIN_NUMBER='(0,0,0,0,0,0,0,0,0,E10,0)';
      PINUSE='POWER';
      NO_LOAD_CHECK='Both';
      NO_IO_CHECK='Both';
      NO_ASSERT_CHECK='TRUE';
      NO_DIR_CHECK='TRUE';
      ALLOW_CONNECT='TRUE';
    'VSS_D9':
      PIN_NUMBER='(0,0,0,0,0,0,0,0,0,D9,0)';
      PINUSE='POWER';
      NO_LOAD_CHECK='Both';
      NO_IO_CHECK='Both';
      NO_ASSERT_CHECK='TRUE';
      NO_DIR_CHECK='TRUE';
      ALLOW_CONNECT='TRUE';
    'VSS_D5':
      PIN_NUMBER='(0,0,0,0,0,0,0,0,0,D5,0)';
      PINUSE='POWER';
      NO_LOAD_CHECK='Both';
      NO_IO_CHECK='Both';
      NO_ASSERT_CHECK='TRUE';
      NO_DIR_CHECK='TRUE';
      ALLOW_CONNECT='TRUE';
    'VSS_D29':
      PIN_NUMBER='(0,0,0,0,0,0,0,0,0,D29,0)';
      PINUSE='POWER';
      NO_LOAD_CHECK='Both';
      NO_IO_CHECK='Both';
      NO_ASSERT_CHECK='TRUE';
      NO_DIR_CHECK='TRUE';
      ALLOW_CONNECT='TRUE';
    'VSS_D13':
      PIN_NUMBER='(0,0,0,0,0,0,0,0,0,D13,0)';
      PINUSE='POWER';
      NO_LOAD_CHECK='Both';
      NO_IO_CHECK='Both';
      NO_ASSERT_CHECK='TRUE';
      NO_DIR_CHECK='TRUE';
      ALLOW_CONNECT='TRUE';
    'VSS_C4':
      PIN_NUMBER='(0,0,0,0,0,0,0,0,0,C4,0)';
      PINUSE='POWER';
      NO_LOAD_CHECK='Both';
      NO_IO_CHECK='Both';
      NO_ASSERT_CHECK='TRUE';
      NO_DIR_CHECK='TRUE';
      ALLOW_CONNECT='TRUE';
    'VSS_C26':
      PIN_NUMBER='(0,0,0,0,0,0,0,0,0,C26,0)';
      PINUSE='POWER';
      NO_LOAD_CHECK='Both';
      NO_IO_CHECK='Both';
      NO_ASSERT_CHECK='TRUE';
      NO_DIR_CHECK='TRUE';
      ALLOW_CONNECT='TRUE';
    'VSS_C24':
      PIN_NUMBER='(0,0,0,0,0,0,0,0,0,C24,0)';
      PINUSE='POWER';
      NO_LOAD_CHECK='Both';
      NO_IO_CHECK='Both';
      NO_ASSERT_CHECK='TRUE';
      NO_DIR_CHECK='TRUE';
      ALLOW_CONNECT='TRUE';
    'VSS_C22':
      PIN_NUMBER='(0,0,0,0,0,0,0,0,0,C22,0)';
      PINUSE='POWER';
      NO_LOAD_CHECK='Both';
      NO_IO_CHECK='Both';
      NO_ASSERT_CHECK='TRUE';
      NO_DIR_CHECK='TRUE';
      ALLOW_CONNECT='TRUE';
    'VSS_C20':
      PIN_NUMBER='(0,0,0,0,0,0,0,0,0,C20,0)';
      PINUSE='POWER';
      NO_LOAD_CHECK='Both';
      NO_IO_CHECK='Both';
      NO_ASSERT_CHECK='TRUE';
      NO_DIR_CHECK='TRUE';
      ALLOW_CONNECT='TRUE';
    'VSS_BG34':
      PIN_NUMBER='(0,0,0,0,0,0,0,0,0,BG34,0)';
      PINUSE='POWER';
      NO_LOAD_CHECK='Both';
      NO_IO_CHECK='Both';
      NO_ASSERT_CHECK='TRUE';
      NO_DIR_CHECK='TRUE';
      ALLOW_CONNECT='TRUE';
    'VSS_BG10':
      PIN_NUMBER='(0,0,0,0,0,0,0,0,0,BG10,0)';
      PINUSE='POWER';
      NO_LOAD_CHECK='Both';
      NO_IO_CHECK='Both';
      NO_ASSERT_CHECK='TRUE';
      NO_DIR_CHECK='TRUE';
      ALLOW_CONNECT='TRUE';
    'VSS_BF21':
      PIN_NUMBER='(0,0,0,0,0,0,0,0,0,BF21,0)';
      PINUSE='POWER';
      NO_LOAD_CHECK='Both';
      NO_IO_CHECK='Both';
      NO_ASSERT_CHECK='TRUE';
      NO_DIR_CHECK='TRUE';
      ALLOW_CONNECT='TRUE';
    'VSS_BE34':
      PIN_NUMBER='(0,0,0,0,0,0,0,0,0,BE34,0)';
      PINUSE='POWER';
      NO_LOAD_CHECK='Both';
      NO_IO_CHECK='Both';
      NO_ASSERT_CHECK='TRUE';
      NO_DIR_CHECK='TRUE';
      ALLOW_CONNECT='TRUE';
    'VSS_BE10':
      PIN_NUMBER='(0,0,0,0,0,0,0,0,0,BE10,0)';
      PINUSE='POWER';
      NO_LOAD_CHECK='Both';
      NO_IO_CHECK='Both';
      NO_ASSERT_CHECK='TRUE';
      NO_DIR_CHECK='TRUE';
      ALLOW_CONNECT='TRUE';
    'VSS_BD39':
      PIN_NUMBER='(0,0,0,0,0,0,0,0,0,BD39,0)';
      PINUSE='POWER';
      NO_LOAD_CHECK='Both';
      NO_IO_CHECK='Both';
      NO_ASSERT_CHECK='TRUE';
      NO_DIR_CHECK='TRUE';
      ALLOW_CONNECT='TRUE';
    'VSS_BD21':
      PIN_NUMBER='(0,0,0,0,0,0,0,0,0,BD21,0)';
      PINUSE='POWER';
      NO_LOAD_CHECK='Both';
      NO_IO_CHECK='Both';
      NO_ASSERT_CHECK='TRUE';
      NO_DIR_CHECK='TRUE';
      ALLOW_CONNECT='TRUE';
    'VSS_BC8':
      PIN_NUMBER='(0,0,0,0,0,0,0,0,0,BC8,0)';
      PINUSE='POWER';
      NO_LOAD_CHECK='Both';
      NO_IO_CHECK='Both';
      NO_ASSERT_CHECK='TRUE';
      NO_DIR_CHECK='TRUE';
      ALLOW_CONNECT='TRUE';
    'VSS_BC6':
      PIN_NUMBER='(0,0,0,0,0,0,0,0,0,BC6,0)';
      PINUSE='POWER';
      NO_LOAD_CHECK='Both';
      NO_IO_CHECK='Both';
      NO_ASSERT_CHECK='TRUE';
      NO_DIR_CHECK='TRUE';
      ALLOW_CONNECT='TRUE';
    'VSS_BC38':
      PIN_NUMBER='(0,0,0,0,0,0,0,0,0,BC38,0)';
      PINUSE='POWER';
      NO_LOAD_CHECK='Both';
      NO_IO_CHECK='Both';
      NO_ASSERT_CHECK='TRUE';
      NO_DIR_CHECK='TRUE';
      ALLOW_CONNECT='TRUE';
    'VSS_BC34':
      PIN_NUMBER='(0,0,0,0,0,0,0,0,0,BC34,0)';
      PINUSE='POWER';
      NO_LOAD_CHECK='Both';
      NO_IO_CHECK='Both';
      NO_ASSERT_CHECK='TRUE';
      NO_DIR_CHECK='TRUE';
      ALLOW_CONNECT='TRUE';
    'VSS_BC32':
      PIN_NUMBER='(0,0,0,0,0,0,0,0,0,BC32,0)';
      PINUSE='POWER';
      NO_LOAD_CHECK='Both';
      NO_IO_CHECK='Both';
      NO_ASSERT_CHECK='TRUE';
      NO_DIR_CHECK='TRUE';
      ALLOW_CONNECT='TRUE';
    'VSS_BC30':
      PIN_NUMBER='(0,0,0,0,0,0,0,0,0,BC30,0)';
      PINUSE='POWER';
      NO_LOAD_CHECK='Both';
      NO_IO_CHECK='Both';
      NO_ASSERT_CHECK='TRUE';
      NO_DIR_CHECK='TRUE';
      ALLOW_CONNECT='TRUE';
    'VSS_BC28':
      PIN_NUMBER='(0,0,0,0,0,0,0,0,0,BC28,0)';
      PINUSE='POWER';
      NO_LOAD_CHECK='Both';
      NO_IO_CHECK='Both';
      NO_ASSERT_CHECK='TRUE';
      NO_DIR_CHECK='TRUE';
      ALLOW_CONNECT='TRUE';
    'VSS_BC26':
      PIN_NUMBER='(0,0,0,0,0,0,0,0,0,BC26,0)';
      PINUSE='POWER';
      NO_LOAD_CHECK='Both';
      NO_IO_CHECK='Both';
      NO_ASSERT_CHECK='TRUE';
      NO_DIR_CHECK='TRUE';
      ALLOW_CONNECT='TRUE';
    'VSS_BC24':
      PIN_NUMBER='(0,0,0,0,0,0,0,0,0,BC24,0)';
      PINUSE='POWER';
      NO_LOAD_CHECK='Both';
      NO_IO_CHECK='Both';
      NO_ASSERT_CHECK='TRUE';
      NO_DIR_CHECK='TRUE';
      ALLOW_CONNECT='TRUE';
    'VSS_BC22':
      PIN_NUMBER='(0,0,0,0,0,0,0,0,0,BC22,0)';
      PINUSE='POWER';
      NO_LOAD_CHECK='Both';
      NO_IO_CHECK='Both';
      NO_ASSERT_CHECK='TRUE';
      NO_DIR_CHECK='TRUE';
      ALLOW_CONNECT='TRUE';
    'VSS_BC20':
      PIN_NUMBER='(0,0,0,0,0,0,0,0,0,BC20,0)';
      PINUSE='POWER';
      NO_LOAD_CHECK='Both';
      NO_IO_CHECK='Both';
      NO_ASSERT_CHECK='TRUE';
      NO_DIR_CHECK='TRUE';
      ALLOW_CONNECT='TRUE';
    'VSS_BC18':
      PIN_NUMBER='(0,0,0,0,0,0,0,0,0,BC18,0)';
      PINUSE='POWER';
      NO_LOAD_CHECK='Both';
      NO_IO_CHECK='Both';
      NO_ASSERT_CHECK='TRUE';
      NO_DIR_CHECK='TRUE';
      ALLOW_CONNECT='TRUE';
    'VSS_BC16':
      PIN_NUMBER='(0,0,0,0,0,0,0,0,0,BC16,0)';
      PINUSE='POWER';
      NO_LOAD_CHECK='Both';
      NO_IO_CHECK='Both';
      NO_ASSERT_CHECK='TRUE';
      NO_DIR_CHECK='TRUE';
      ALLOW_CONNECT='TRUE';
    'VSS_BC14':
      PIN_NUMBER='(0,0,0,0,0,0,0,0,0,BC14,0)';
      PINUSE='POWER';
      NO_LOAD_CHECK='Both';
      NO_IO_CHECK='Both';
      NO_ASSERT_CHECK='TRUE';
      NO_DIR_CHECK='TRUE';
      ALLOW_CONNECT='TRUE';
    'VSS_BC12':
      PIN_NUMBER='(0,0,0,0,0,0,0,0,0,BC12,0)';
      PINUSE='POWER';
      NO_LOAD_CHECK='Both';
      NO_IO_CHECK='Both';
      NO_ASSERT_CHECK='TRUE';
      NO_DIR_CHECK='TRUE';
      ALLOW_CONNECT='TRUE';
    'VSS_BC10':
      PIN_NUMBER='(0,0,0,0,0,0,0,0,0,BC10,0)';
      PINUSE='POWER';
      NO_LOAD_CHECK='Both';
      NO_IO_CHECK='Both';
      NO_ASSERT_CHECK='TRUE';
      NO_DIR_CHECK='TRUE';
      ALLOW_CONNECT='TRUE';
    'VSS_BB5':
      PIN_NUMBER='(0,0,0,0,0,0,0,0,0,BB5,0)';
      PINUSE='POWER';
      NO_LOAD_CHECK='Both';
      NO_IO_CHECK='Both';
      NO_ASSERT_CHECK='TRUE';
      NO_DIR_CHECK='TRUE';
      ALLOW_CONNECT='TRUE';
    'VSS_BB39':
      PIN_NUMBER='(0,0,0,0,0,0,0,0,0,BB39,0)';
      PINUSE='POWER';
      NO_LOAD_CHECK='Both';
      NO_IO_CHECK='Both';
      NO_ASSERT_CHECK='TRUE';
      NO_DIR_CHECK='TRUE';
      ALLOW_CONNECT='TRUE';
    'VSS_B9':
      PIN_NUMBER='(0,0,0,0,0,0,0,0,0,B9,0)';
      PINUSE='POWER';
      NO_LOAD_CHECK='Both';
      NO_IO_CHECK='Both';
      NO_ASSERT_CHECK='TRUE';
      NO_DIR_CHECK='TRUE';
      ALLOW_CONNECT='TRUE';
    'VSS_B29':
      PIN_NUMBER='(0,0,0,0,0,0,0,0,0,B29,0)';
      PINUSE='POWER';
      NO_LOAD_CHECK='Both';
      NO_IO_CHECK='Both';
      NO_ASSERT_CHECK='TRUE';
      NO_DIR_CHECK='TRUE';
      ALLOW_CONNECT='TRUE';
    'VSS_B13':
      PIN_NUMBER='(0,0,0,0,0,0,0,0,0,B13,0)';
      PINUSE='POWER';
      NO_LOAD_CHECK='Both';
      NO_IO_CHECK='Both';
      NO_ASSERT_CHECK='TRUE';
      NO_DIR_CHECK='TRUE';
      ALLOW_CONNECT='TRUE';
    'VSS_AY8':
      PIN_NUMBER='(0,0,0,0,0,0,0,0,0,AY8,0)';
      PINUSE='POWER';
      NO_LOAD_CHECK='Both';
      NO_IO_CHECK='Both';
      NO_ASSERT_CHECK='TRUE';
      NO_DIR_CHECK='TRUE';
      ALLOW_CONNECT='TRUE';
    'VSS_AY5':
      PIN_NUMBER='(0,0,0,0,0,0,0,0,0,AY5,0)';
      PINUSE='POWER';
      NO_LOAD_CHECK='Both';
      NO_IO_CHECK='Both';
      NO_ASSERT_CHECK='TRUE';
      NO_DIR_CHECK='TRUE';
      ALLOW_CONNECT='TRUE';
    'VSS_AY37':
      PIN_NUMBER='(0,0,0,0,0,0,0,0,0,AY37,0)';
      PINUSE='POWER';
      NO_LOAD_CHECK='Both';
      NO_IO_CHECK='Both';
      NO_ASSERT_CHECK='TRUE';
      NO_DIR_CHECK='TRUE';
      ALLOW_CONNECT='TRUE';
    'VSS_AY34':
      PIN_NUMBER='(0,0,0,0,0,0,0,0,0,AY34,0)';
      PINUSE='POWER';
      NO_LOAD_CHECK='Both';
      NO_IO_CHECK='Both';
      NO_ASSERT_CHECK='TRUE';
      NO_DIR_CHECK='TRUE';
      ALLOW_CONNECT='TRUE';
    'VSS_AY31':
      PIN_NUMBER='(0,0,0,0,0,0,0,0,0,AY31,0)';
      PINUSE='POWER';
      NO_LOAD_CHECK='Both';
      NO_IO_CHECK='Both';
      NO_ASSERT_CHECK='TRUE';
      NO_DIR_CHECK='TRUE';
      ALLOW_CONNECT='TRUE';
    'VSS_AY28':
      PIN_NUMBER='(0,0,0,0,0,0,0,0,0,AY28,0)';
      PINUSE='POWER';
      NO_LOAD_CHECK='Both';
      NO_IO_CHECK='Both';
      NO_ASSERT_CHECK='TRUE';
      NO_DIR_CHECK='TRUE';
      ALLOW_CONNECT='TRUE';
    'VSS_AY39':
      PIN_NUMBER='(0,0,0,0,0,0,0,0,0,AY39,0)';
      PINUSE='POWER';
      NO_LOAD_CHECK='Both';
      NO_IO_CHECK='Both';
      NO_ASSERT_CHECK='TRUE';
      NO_DIR_CHECK='TRUE';
      ALLOW_CONNECT='TRUE';
    'VSS_F41':
      PIN_NUMBER='(0,0,0,0,0,0,0,0,0,F41,0)';
      PINUSE='POWER';
      NO_LOAD_CHECK='Both';
      NO_IO_CHECK='Both';
      NO_ASSERT_CHECK='TRUE';
      NO_DIR_CHECK='TRUE';
      ALLOW_CONNECT='TRUE';
    'VSS_E40':
      PIN_NUMBER='(0,0,0,0,0,0,0,0,0,E40,0)';
      PINUSE='POWER';
      NO_LOAD_CHECK='Both';
      NO_IO_CHECK='Both';
      NO_ASSERT_CHECK='TRUE';
      NO_DIR_CHECK='TRUE';
      ALLOW_CONNECT='TRUE';
    'VSS_BD5':
      PIN_NUMBER='(0,0,0,0,0,0,0,0,0,BD5,0)';
      PINUSE='POWER';
      NO_LOAD_CHECK='Both';
      NO_IO_CHECK='Both';
      NO_ASSERT_CHECK='TRUE';
      NO_DIR_CHECK='TRUE';
      ALLOW_CONNECT='TRUE';
    'VSS_BC36':
      PIN_NUMBER='(0,0,0,0,0,0,0,0,0,BC36,0)';
      PINUSE='POWER';
      NO_LOAD_CHECK='Both';
      NO_IO_CHECK='Both';
      NO_ASSERT_CHECK='TRUE';
      NO_DIR_CHECK='TRUE';
      ALLOW_CONNECT='TRUE';
    'VSS_AY3':
      PIN_NUMBER='(0,0,0,0,0,0,0,0,0,AY3,0)';
      PINUSE='POWER';
      NO_LOAD_CHECK='Both';
      NO_IO_CHECK='Both';
      NO_ASSERT_CHECK='TRUE';
      NO_DIR_CHECK='TRUE';
      ALLOW_CONNECT='TRUE';
    'VSS_C38':
      PIN_NUMBER='(0,0,0,0,0,0,0,0,0,C38,0)';
      PINUSE='POWER';
      NO_LOAD_CHECK='Both';
      NO_IO_CHECK='Both';
      NO_ASSERT_CHECK='TRUE';
      NO_DIR_CHECK='TRUE';
      ALLOW_CONNECT='TRUE';
    'VSS_B39':
      PIN_NUMBER='(0,0,0,0,0,0,0,0,0,B39,0)';
      PINUSE='POWER';
      NO_LOAD_CHECK='Both';
      NO_IO_CHECK='Both';
      NO_ASSERT_CHECK='TRUE';
      NO_DIR_CHECK='TRUE';
      ALLOW_CONNECT='TRUE';
    'VSS_E8':
      PIN_NUMBER='(0,0,0,0,0,0,0,0,0,E8,0)';
      PINUSE='POWER';
      NO_LOAD_CHECK='Both';
      NO_IO_CHECK='Both';
      NO_ASSERT_CHECK='TRUE';
      NO_DIR_CHECK='TRUE';
      ALLOW_CONNECT='TRUE';
    'VSS_D43':
      PIN_NUMBER='(0,0,0,0,0,0,0,0,0,0,D43)';
      PINUSE='POWER';
      NO_LOAD_CHECK='Both';
      NO_IO_CHECK='Both';
      NO_ASSERT_CHECK='TRUE';
      NO_DIR_CHECK='TRUE';
      ALLOW_CONNECT='TRUE';
    'VSS_D1':
      PIN_NUMBER='(0,0,0,0,0,0,0,0,0,0,D1)';
      PINUSE='POWER';
      NO_LOAD_CHECK='Both';
      NO_IO_CHECK='Both';
      NO_ASSERT_CHECK='TRUE';
      NO_DIR_CHECK='TRUE';
      ALLOW_CONNECT='TRUE';
    'VSS_C43':
      PIN_NUMBER='(0,0,0,0,0,0,0,0,0,0,C43)';
      PINUSE='POWER';
      NO_LOAD_CHECK='Both';
      NO_IO_CHECK='Both';
      NO_ASSERT_CHECK='TRUE';
      NO_DIR_CHECK='TRUE';
      ALLOW_CONNECT='TRUE';
    'VSS_C41':
      PIN_NUMBER='(0,0,0,0,0,0,0,0,0,0,C41)';
      PINUSE='POWER';
      NO_LOAD_CHECK='Both';
      NO_IO_CHECK='Both';
      NO_ASSERT_CHECK='TRUE';
      NO_DIR_CHECK='TRUE';
      ALLOW_CONNECT='TRUE';
    'VSS_C3':
      PIN_NUMBER='(0,0,0,0,0,0,0,0,0,0,C3)';
      PINUSE='POWER';
      NO_LOAD_CHECK='Both';
      NO_IO_CHECK='Both';
      NO_ASSERT_CHECK='TRUE';
      NO_DIR_CHECK='TRUE';
      ALLOW_CONNECT='TRUE';
    'VSS_BG41':
      PIN_NUMBER='(0,0,0,0,0,0,0,0,0,0,BG41)';
      PINUSE='POWER';
      NO_LOAD_CHECK='Both';
      NO_IO_CHECK='Both';
      NO_ASSERT_CHECK='TRUE';
      NO_DIR_CHECK='TRUE';
      ALLOW_CONNECT='TRUE';
    'VSS_BE43':
      PIN_NUMBER='(0,0,0,0,0,0,0,0,0,0,BE43)';
      PINUSE='POWER';
      NO_LOAD_CHECK='Both';
      NO_IO_CHECK='Both';
      NO_ASSERT_CHECK='TRUE';
      NO_DIR_CHECK='TRUE';
      ALLOW_CONNECT='TRUE';
    'VSS_BE41':
      PIN_NUMBER='(0,0,0,0,0,0,0,0,0,0,BE41)';
      PINUSE='POWER';
      NO_LOAD_CHECK='Both';
      NO_IO_CHECK='Both';
      NO_ASSERT_CHECK='TRUE';
      NO_DIR_CHECK='TRUE';
      ALLOW_CONNECT='TRUE';
    'VSS_BE3':
      PIN_NUMBER='(0,0,0,0,0,0,0,0,0,0,BE3)';
      PINUSE='POWER';
      NO_LOAD_CHECK='Both';
      NO_IO_CHECK='Both';
      NO_ASSERT_CHECK='TRUE';
      NO_DIR_CHECK='TRUE';
      ALLOW_CONNECT='TRUE';
    'VSS_BE1':
      PIN_NUMBER='(0,0,0,0,0,0,0,0,0,0,BE1)';
      PINUSE='POWER';
      NO_LOAD_CHECK='Both';
      NO_IO_CHECK='Both';
      NO_ASSERT_CHECK='TRUE';
      NO_DIR_CHECK='TRUE';
      ALLOW_CONNECT='TRUE';
    'VSS_BD43':
      PIN_NUMBER='(0,0,0,0,0,0,0,0,0,0,BD43)';
      PINUSE='POWER';
      NO_LOAD_CHECK='Both';
      NO_IO_CHECK='Both';
      NO_ASSERT_CHECK='TRUE';
      NO_DIR_CHECK='TRUE';
      ALLOW_CONNECT='TRUE';
    'VSS_BD1':
      PIN_NUMBER='(0,0,0,0,0,0,0,0,0,0,BD1)';
      PINUSE='POWER';
      NO_LOAD_CHECK='Both';
      NO_IO_CHECK='Both';
      NO_ASSERT_CHECK='TRUE';
      NO_DIR_CHECK='TRUE';
      ALLOW_CONNECT='TRUE';
    'VSS_E42':
      PIN_NUMBER='(0,0,0,0,0,0,0,0,0,0,E42)';
      PINUSE='POWER';
      NO_LOAD_CHECK='Both';
      NO_IO_CHECK='Both';
      NO_ASSERT_CHECK='TRUE';
      NO_DIR_CHECK='TRUE';
      ALLOW_CONNECT='TRUE';
    'VSS_E2':
      PIN_NUMBER='(0,0,0,0,0,0,0,0,0,0,E2)';
      PINUSE='POWER';
      NO_LOAD_CHECK='Both';
      NO_IO_CHECK='Both';
      NO_ASSERT_CHECK='TRUE';
      NO_DIR_CHECK='TRUE';
      ALLOW_CONNECT='TRUE';
    'VSS_D41':
      PIN_NUMBER='(0,0,0,0,0,0,0,0,0,0,D41)';
      PINUSE='POWER';
      NO_LOAD_CHECK='Both';
      NO_IO_CHECK='Both';
      NO_ASSERT_CHECK='TRUE';
      NO_DIR_CHECK='TRUE';
      ALLOW_CONNECT='TRUE';
    'VSS_D3':
      PIN_NUMBER='(0,0,0,0,0,0,0,0,0,0,D3)';
      PINUSE='POWER';
      NO_LOAD_CHECK='Both';
      NO_IO_CHECK='Both';
      NO_ASSERT_CHECK='TRUE';
      NO_DIR_CHECK='TRUE';
      ALLOW_CONNECT='TRUE';
    'VSS_BD41':
      PIN_NUMBER='(0,0,0,0,0,0,0,0,0,0,BD41)';
      PINUSE='POWER';
      NO_LOAD_CHECK='Both';
      NO_IO_CHECK='Both';
      NO_ASSERT_CHECK='TRUE';
      NO_DIR_CHECK='TRUE';
      ALLOW_CONNECT='TRUE';
    'VSS_BD3':
      PIN_NUMBER='(0,0,0,0,0,0,0,0,0,0,BD3)';
      PINUSE='POWER';
      NO_LOAD_CHECK='Both';
      NO_IO_CHECK='Both';
      NO_ASSERT_CHECK='TRUE';
      NO_DIR_CHECK='TRUE';
      ALLOW_CONNECT='TRUE';
    'VSS_BC42':
      PIN_NUMBER='(0,0,0,0,0,0,0,0,0,0,BC42)';
      PINUSE='POWER';
      NO_LOAD_CHECK='Both';
      NO_IO_CHECK='Both';
      NO_ASSERT_CHECK='TRUE';
      NO_DIR_CHECK='TRUE';
      ALLOW_CONNECT='TRUE';
    'VSS_BC2':
      PIN_NUMBER='(0,0,0,0,0,0,0,0,0,0,BC2)';
      PINUSE='POWER';
      NO_LOAD_CHECK='Both';
      NO_IO_CHECK='Both';
      NO_ASSERT_CHECK='TRUE';
      NO_DIR_CHECK='TRUE';
      ALLOW_CONNECT='TRUE';
    'VSS_F43':
      PIN_NUMBER='(0,0,0,0,0,0,0,0,0,0,F43)';
      PINUSE='POWER';
      NO_LOAD_CHECK='Both';
      NO_IO_CHECK='Both';
      NO_ASSERT_CHECK='TRUE';
      NO_DIR_CHECK='TRUE';
      ALLOW_CONNECT='TRUE';
    'VSS_BG6':
      PIN_NUMBER='(0,0,0,0,0,0,0,0,0,0,BG6)';
      PINUSE='POWER';
      NO_LOAD_CHECK='Both';
      NO_IO_CHECK='Both';
      NO_ASSERT_CHECK='TRUE';
      NO_DIR_CHECK='TRUE';
      ALLOW_CONNECT='TRUE';
    'VSS_BG4':
      PIN_NUMBER='(0,0,0,0,0,0,0,0,0,0,BG4)';
      PINUSE='POWER';
      NO_LOAD_CHECK='Both';
      NO_IO_CHECK='Both';
      NO_ASSERT_CHECK='TRUE';
      NO_DIR_CHECK='TRUE';
      ALLOW_CONNECT='TRUE';
    'VSS_BG38':
      PIN_NUMBER='(0,0,0,0,0,0,0,0,0,0,BG38)';
      PINUSE='POWER';
      NO_LOAD_CHECK='Both';
      NO_IO_CHECK='Both';
      NO_ASSERT_CHECK='TRUE';
      NO_DIR_CHECK='TRUE';
      ALLOW_CONNECT='TRUE';
    'VSS_BB1':
      PIN_NUMBER='(0,0,0,0,0,0,0,0,0,0,BB1)';
      PINUSE='POWER';
      NO_LOAD_CHECK='Both';
      NO_IO_CHECK='Both';
      NO_ASSERT_CHECK='TRUE';
      NO_DIR_CHECK='TRUE';
      ALLOW_CONNECT='TRUE';
    'VSS_A6':
      PIN_NUMBER='(0,0,0,0,0,0,0,0,0,0,A6)';
      PINUSE='POWER';
      NO_LOAD_CHECK='Both';
      NO_IO_CHECK='Both';
      NO_ASSERT_CHECK='TRUE';
      NO_DIR_CHECK='TRUE';
      ALLOW_CONNECT='TRUE';
    'VSS_A40':
      PIN_NUMBER='(0,0,0,0,0,0,0,0,0,0,A40)';
      PINUSE='POWER';
      NO_LOAD_CHECK='Both';
      NO_IO_CHECK='Both';
      NO_ASSERT_CHECK='TRUE';
      NO_DIR_CHECK='TRUE';
      ALLOW_CONNECT='TRUE';
    'VSS_A38':
      PIN_NUMBER='(0,0,0,0,0,0,0,0,0,0,A38)';
      PINUSE='POWER';
      NO_LOAD_CHECK='Both';
      NO_IO_CHECK='Both';
      NO_ASSERT_CHECK='TRUE';
      NO_DIR_CHECK='TRUE';
      ALLOW_CONNECT='TRUE';
    'VSS_AY24':
      PIN_NUMBER='(0,0,0,0,0,0,0,0,0,0,AY24)';
      PINUSE='POWER';
      NO_LOAD_CHECK='Both';
      NO_IO_CHECK='Both';
      NO_ASSERT_CHECK='TRUE';
      NO_DIR_CHECK='TRUE';
      ALLOW_CONNECT='TRUE';
    'VSS_AY21':
      PIN_NUMBER='(0,0,0,0,0,0,0,0,0,0,AY21)';
      PINUSE='POWER';
      NO_LOAD_CHECK='Both';
      NO_IO_CHECK='Both';
      NO_ASSERT_CHECK='TRUE';
      NO_DIR_CHECK='TRUE';
      ALLOW_CONNECT='TRUE';
    'VSS_AY18':
      PIN_NUMBER='(0,0,0,0,0,0,0,0,0,0,AY18)';
      PINUSE='POWER';
      NO_LOAD_CHECK='Both';
      NO_IO_CHECK='Both';
      NO_ASSERT_CHECK='TRUE';
      NO_DIR_CHECK='TRUE';
      ALLOW_CONNECT='TRUE';
    'VSS_AY15':
      PIN_NUMBER='(0,0,0,0,0,0,0,0,0,0,AY15)';
      PINUSE='POWER';
      NO_LOAD_CHECK='Both';
      NO_IO_CHECK='Both';
      NO_ASSERT_CHECK='TRUE';
      NO_DIR_CHECK='TRUE';
      ALLOW_CONNECT='TRUE';
    'VSS_AY11':
      PIN_NUMBER='(0,0,0,0,0,0,0,0,0,0,AY11)';
      PINUSE='POWER';
      NO_LOAD_CHECK='Both';
      NO_IO_CHECK='Both';
      NO_ASSERT_CHECK='TRUE';
      NO_DIR_CHECK='TRUE';
      ALLOW_CONNECT='TRUE';
    'VSS_AW7':
      PIN_NUMBER='(0,0,0,0,0,0,0,0,0,0,AW7)';
      PINUSE='POWER';
      NO_LOAD_CHECK='Both';
      NO_IO_CHECK='Both';
      NO_ASSERT_CHECK='TRUE';
      NO_DIR_CHECK='TRUE';
      ALLOW_CONNECT='TRUE';
    'VSS_AV8':
      PIN_NUMBER='(0,0,0,0,0,0,0,0,0,0,AV8)';
      PINUSE='POWER';
      NO_LOAD_CHECK='Both';
      NO_IO_CHECK='Both';
      NO_ASSERT_CHECK='TRUE';
      NO_DIR_CHECK='TRUE';
      ALLOW_CONNECT='TRUE';
    'VSS_AV5':
      PIN_NUMBER='(0,0,0,0,0,0,0,0,0,0,AV5)';
      PINUSE='POWER';
      NO_LOAD_CHECK='Both';
      NO_IO_CHECK='Both';
      NO_ASSERT_CHECK='TRUE';
      NO_DIR_CHECK='TRUE';
      ALLOW_CONNECT='TRUE';
    'VSS_AV39':
      PIN_NUMBER='(0,0,0,0,0,0,0,0,0,0,AV39)';
      PINUSE='POWER';
      NO_LOAD_CHECK='Both';
      NO_IO_CHECK='Both';
      NO_ASSERT_CHECK='TRUE';
      NO_DIR_CHECK='TRUE';
      ALLOW_CONNECT='TRUE';
    'VSS_AV37':
      PIN_NUMBER='(0,0,0,0,0,0,0,0,0,0,AV37)';
      PINUSE='POWER';
      NO_LOAD_CHECK='Both';
      NO_IO_CHECK='Both';
      NO_ASSERT_CHECK='TRUE';
      NO_DIR_CHECK='TRUE';
      ALLOW_CONNECT='TRUE';
    'VSS_AU36':
      PIN_NUMBER='(0,0,0,0,0,0,0,0,0,0,AU36)';
      PINUSE='POWER';
      NO_LOAD_CHECK='Both';
      NO_IO_CHECK='Both';
      NO_ASSERT_CHECK='TRUE';
      NO_DIR_CHECK='TRUE';
      ALLOW_CONNECT='TRUE';
    'VSS_AU32':
      PIN_NUMBER='(0,0,0,0,0,0,0,0,0,0,AU32)';
      PINUSE='POWER';
      NO_LOAD_CHECK='Both';
      NO_IO_CHECK='Both';
      NO_ASSERT_CHECK='TRUE';
      NO_DIR_CHECK='TRUE';
      ALLOW_CONNECT='TRUE';
    'VSS_AU29':
      PIN_NUMBER='(0,0,0,0,0,0,0,0,0,0,AU29)';
      PINUSE='POWER';
      NO_LOAD_CHECK='Both';
      NO_IO_CHECK='Both';
      NO_ASSERT_CHECK='TRUE';
      NO_DIR_CHECK='TRUE';
      ALLOW_CONNECT='TRUE';
    'VSS_AU26':
      PIN_NUMBER='(0,0,0,0,0,0,0,0,0,0,AU26)';
      PINUSE='POWER';
      NO_LOAD_CHECK='Both';
      NO_IO_CHECK='Both';
      NO_ASSERT_CHECK='TRUE';
      NO_DIR_CHECK='TRUE';
      ALLOW_CONNECT='TRUE';
    'VSS_AU23':
      PIN_NUMBER='(0,0,0,0,0,0,0,0,0,0,AU23)';
      PINUSE='POWER';
      NO_LOAD_CHECK='Both';
      NO_IO_CHECK='Both';
      NO_ASSERT_CHECK='TRUE';
      NO_DIR_CHECK='TRUE';
      ALLOW_CONNECT='TRUE';
    'VSS_AU20':
      PIN_NUMBER='(0,0,0,0,0,0,0,0,0,0,AU20)';
      PINUSE='POWER';
      NO_LOAD_CHECK='Both';
      NO_IO_CHECK='Both';
      NO_ASSERT_CHECK='TRUE';
      NO_DIR_CHECK='TRUE';
      ALLOW_CONNECT='TRUE';
    'VSS_AT8':
      PIN_NUMBER='(0,0,0,0,0,0,0,0,0,0,AT8)';
      PINUSE='POWER';
      NO_LOAD_CHECK='Both';
      NO_IO_CHECK='Both';
      NO_ASSERT_CHECK='TRUE';
      NO_DIR_CHECK='TRUE';
      ALLOW_CONNECT='TRUE';
    'VSS_AT5':
      PIN_NUMBER='(0,0,0,0,0,0,0,0,0,0,AT5)';
      PINUSE='POWER';
      NO_LOAD_CHECK='Both';
      NO_IO_CHECK='Both';
      NO_ASSERT_CHECK='TRUE';
      NO_DIR_CHECK='TRUE';
      ALLOW_CONNECT='TRUE';
    'VSS_AT39':
      PIN_NUMBER='(0,0,0,0,0,0,0,0,0,0,AT39)';
      PINUSE='POWER';
      NO_LOAD_CHECK='Both';
      NO_IO_CHECK='Both';
      NO_ASSERT_CHECK='TRUE';
      NO_DIR_CHECK='TRUE';
      ALLOW_CONNECT='TRUE';
    'VSS_AT34':
      PIN_NUMBER='(0,0,0,0,0,0,0,0,0,0,AT34)';
      PINUSE='POWER';
      NO_LOAD_CHECK='Both';
      NO_IO_CHECK='Both';
      NO_ASSERT_CHECK='TRUE';
      NO_DIR_CHECK='TRUE';
      ALLOW_CONNECT='TRUE';
    'VSS_AT31':
      PIN_NUMBER='(0,0,0,0,0,0,0,0,0,0,AT31)';
      PINUSE='POWER';
      NO_LOAD_CHECK='Both';
      NO_IO_CHECK='Both';
      NO_ASSERT_CHECK='TRUE';
      NO_DIR_CHECK='TRUE';
      ALLOW_CONNECT='TRUE';
    'VSS_AT28':
      PIN_NUMBER='(0,0,0,0,0,0,0,0,0,0,AT28)';
      PINUSE='POWER';
      NO_LOAD_CHECK='Both';
      NO_IO_CHECK='Both';
      NO_ASSERT_CHECK='TRUE';
      NO_DIR_CHECK='TRUE';
      ALLOW_CONNECT='TRUE';
    'VSS_AT24':
      PIN_NUMBER='(0,0,0,0,0,0,0,0,0,0,AT24)';
      PINUSE='POWER';
      NO_LOAD_CHECK='Both';
      NO_IO_CHECK='Both';
      NO_ASSERT_CHECK='TRUE';
      NO_DIR_CHECK='TRUE';
      ALLOW_CONNECT='TRUE';
    'VSS_AT21':
      PIN_NUMBER='(0,0,0,0,0,0,0,0,0,0,AT21)';
      PINUSE='POWER';
      NO_LOAD_CHECK='Both';
      NO_IO_CHECK='Both';
      NO_ASSERT_CHECK='TRUE';
      NO_DIR_CHECK='TRUE';
      ALLOW_CONNECT='TRUE';
    'VSS_AT15':
      PIN_NUMBER='(0,0,0,0,0,0,0,0,0,0,AT15)';
      PINUSE='POWER';
      NO_LOAD_CHECK='Both';
      NO_IO_CHECK='Both';
      NO_ASSERT_CHECK='TRUE';
      NO_DIR_CHECK='TRUE';
      ALLOW_CONNECT='TRUE';
    'VSS_AT11':
      PIN_NUMBER='(0,0,0,0,0,0,0,0,0,0,AT11)';
      PINUSE='POWER';
      NO_LOAD_CHECK='Both';
      NO_IO_CHECK='Both';
      NO_ASSERT_CHECK='TRUE';
      NO_DIR_CHECK='TRUE';
      ALLOW_CONNECT='TRUE';
    'VSS_AR32':
      PIN_NUMBER='(0,0,0,0,0,0,0,0,0,0,AR32)';
      PINUSE='POWER';
      NO_LOAD_CHECK='Both';
      NO_IO_CHECK='Both';
      NO_ASSERT_CHECK='TRUE';
      NO_DIR_CHECK='TRUE';
      ALLOW_CONNECT='TRUE';
    'VSS_AR20':
      PIN_NUMBER='(0,0,0,0,0,0,0,0,0,0,AR20)';
      PINUSE='POWER';
      NO_LOAD_CHECK='Both';
      NO_IO_CHECK='Both';
      NO_ASSERT_CHECK='TRUE';
      NO_DIR_CHECK='TRUE';
      ALLOW_CONNECT='TRUE';
    'VSS_AP5':
      PIN_NUMBER='(0,0,0,0,0,0,0,0,0,0,AP5)';
      PINUSE='POWER';
      NO_LOAD_CHECK='Both';
      NO_IO_CHECK='Both';
      NO_ASSERT_CHECK='TRUE';
      NO_DIR_CHECK='TRUE';
      ALLOW_CONNECT='TRUE';
    'VSS_AP39':
      PIN_NUMBER='(0,0,0,0,0,0,0,0,0,0,AP39)';
      PINUSE='POWER';
      NO_LOAD_CHECK='Both';
      NO_IO_CHECK='Both';
      NO_ASSERT_CHECK='TRUE';
      NO_DIR_CHECK='TRUE';
      ALLOW_CONNECT='TRUE';
    'VSS_AP37':
      PIN_NUMBER='(0,0,0,0,0,0,0,0,0,0,AP37)';
      PINUSE='POWER';
      NO_LOAD_CHECK='Both';
      NO_IO_CHECK='Both';
      NO_ASSERT_CHECK='TRUE';
      NO_DIR_CHECK='TRUE';
      ALLOW_CONNECT='TRUE';
    'VSS_AP28':
      PIN_NUMBER='(0,0,0,0,0,0,0,0,0,0,AP28)';
      PINUSE='POWER';
      NO_LOAD_CHECK='Both';
      NO_IO_CHECK='Both';
      NO_ASSERT_CHECK='TRUE';
      NO_DIR_CHECK='TRUE';
      ALLOW_CONNECT='TRUE';
    'VSS_AP24':
      PIN_NUMBER='(0,0,0,0,0,0,0,0,0,0,AP24)';
      PINUSE='POWER';
      NO_LOAD_CHECK='Both';
      NO_IO_CHECK='Both';
      NO_ASSERT_CHECK='TRUE';
      NO_DIR_CHECK='TRUE';
      ALLOW_CONNECT='TRUE';
    'VSS_AP18':
      PIN_NUMBER='(0,0,0,0,0,0,0,0,0,0,AP18)';
      PINUSE='POWER';
      NO_LOAD_CHECK='Both';
      NO_IO_CHECK='Both';
      NO_ASSERT_CHECK='TRUE';
      NO_DIR_CHECK='TRUE';
      ALLOW_CONNECT='TRUE';
    'VSS_AP11':
      PIN_NUMBER='(0,0,0,0,0,0,0,0,0,0,AP11)';
      PINUSE='POWER';
      NO_LOAD_CHECK='Both';
      NO_IO_CHECK='Both';
      NO_ASSERT_CHECK='TRUE';
      NO_DIR_CHECK='TRUE';
      ALLOW_CONNECT='TRUE';
    'VSS_AN32':
      PIN_NUMBER='(0,0,0,0,0,0,0,0,0,0,AN32)';
      PINUSE='POWER';
      NO_LOAD_CHECK='Both';
      NO_IO_CHECK='Both';
      NO_ASSERT_CHECK='TRUE';
      NO_DIR_CHECK='TRUE';
      ALLOW_CONNECT='TRUE';
    'VSS_AN29':
      PIN_NUMBER='(0,0,0,0,0,0,0,0,0,0,AN29)';
      PINUSE='POWER';
      NO_LOAD_CHECK='Both';
      NO_IO_CHECK='Both';
      NO_ASSERT_CHECK='TRUE';
      NO_DIR_CHECK='TRUE';
      ALLOW_CONNECT='TRUE';
    'VSS_AN16':
      PIN_NUMBER='(0,0,0,0,0,0,0,0,0,0,AN16)';
      PINUSE='POWER';
      NO_LOAD_CHECK='Both';
      NO_IO_CHECK='Both';
      NO_ASSERT_CHECK='TRUE';
      NO_DIR_CHECK='TRUE';
      ALLOW_CONNECT='TRUE';
    'VSS_AN13':
      PIN_NUMBER='(0,0,0,0,0,0,0,0,0,0,AN13)';
      PINUSE='POWER';
      NO_LOAD_CHECK='Both';
      NO_IO_CHECK='Both';
      NO_ASSERT_CHECK='TRUE';
      NO_DIR_CHECK='TRUE';
      ALLOW_CONNECT='TRUE';
    'VSS_AM8':
      PIN_NUMBER='(0,0,0,0,0,0,0,0,0,0,AM8)';
      PINUSE='POWER';
      NO_LOAD_CHECK='Both';
      NO_IO_CHECK='Both';
      NO_ASSERT_CHECK='TRUE';
      NO_DIR_CHECK='TRUE';
      ALLOW_CONNECT='TRUE';
    'VSS_AM31':
      PIN_NUMBER='(0,0,0,0,0,0,0,0,0,0,AM31)';
      PINUSE='POWER';
      NO_LOAD_CHECK='Both';
      NO_IO_CHECK='Both';
      NO_ASSERT_CHECK='TRUE';
      NO_DIR_CHECK='TRUE';
      ALLOW_CONNECT='TRUE';
    'VSS_AM15':
      PIN_NUMBER='(0,0,0,0,0,0,0,0,0,0,AM15)';
      PINUSE='POWER';
      NO_LOAD_CHECK='Both';
      NO_IO_CHECK='Both';
      NO_ASSERT_CHECK='TRUE';
      NO_DIR_CHECK='TRUE';
      ALLOW_CONNECT='TRUE';
    'VSS_AL39':
      PIN_NUMBER='(0,0,0,0,0,0,0,0,0,0,AL39)';
      PINUSE='POWER';
      NO_LOAD_CHECK='Both';
      NO_IO_CHECK='Both';
      NO_ASSERT_CHECK='TRUE';
      NO_DIR_CHECK='TRUE';
      ALLOW_CONNECT='TRUE';
    'VSS_AL29':
      PIN_NUMBER='(0,0,0,0,0,0,0,0,0,0,AL29)';
      PINUSE='POWER';
      NO_LOAD_CHECK='Both';
      NO_IO_CHECK='Both';
      NO_ASSERT_CHECK='TRUE';
      NO_DIR_CHECK='TRUE';
      ALLOW_CONNECT='TRUE';
    'VSS_AL27':
      PIN_NUMBER='(0,0,0,0,0,0,0,0,0,0,AL27)';
      PINUSE='POWER';
      NO_LOAD_CHECK='Both';
      NO_IO_CHECK='Both';
      NO_ASSERT_CHECK='TRUE';
      NO_DIR_CHECK='TRUE';
      ALLOW_CONNECT='TRUE';
    'VSS_AL24':
      PIN_NUMBER='(0,0,0,0,0,0,0,0,0,0,AL24)';
      PINUSE='POWER';
      NO_LOAD_CHECK='Both';
      NO_IO_CHECK='Both';
      NO_ASSERT_CHECK='TRUE';
      NO_DIR_CHECK='TRUE';
      ALLOW_CONNECT='TRUE';
    'VSS_AL19':
      PIN_NUMBER='(0,0,0,0,0,0,0,0,0,0,AL19)';
      PINUSE='POWER';
      NO_LOAD_CHECK='Both';
      NO_IO_CHECK='Both';
      NO_ASSERT_CHECK='TRUE';
      NO_DIR_CHECK='TRUE';
      ALLOW_CONNECT='TRUE';
    'VSS_AK4':
      PIN_NUMBER='(0,0,0,0,0,0,0,0,0,0,AK4)';
      PINUSE='POWER';
      NO_LOAD_CHECK='Both';
      NO_IO_CHECK='Both';
      NO_ASSERT_CHECK='TRUE';
      NO_DIR_CHECK='TRUE';
      ALLOW_CONNECT='TRUE';
    'VSS_AK37':
      PIN_NUMBER='(0,0,0,0,0,0,0,0,0,0,AK37)';
      PINUSE='POWER';
      NO_LOAD_CHECK='Both';
      NO_IO_CHECK='Both';
      NO_ASSERT_CHECK='TRUE';
      NO_DIR_CHECK='TRUE';
      ALLOW_CONNECT='TRUE';
    'VSS_AK2':
      PIN_NUMBER='(0,0,0,0,0,0,0,0,0,0,AK2)';
      PINUSE='POWER';
      NO_LOAD_CHECK='Both';
      NO_IO_CHECK='Both';
      NO_ASSERT_CHECK='TRUE';
      NO_DIR_CHECK='TRUE';
      ALLOW_CONNECT='TRUE';
    'VSS_AK11':
      PIN_NUMBER='(0,0,0,0,0,0,0,0,0,0,AK11)';
      PINUSE='POWER';
      NO_LOAD_CHECK='Both';
      NO_IO_CHECK='Both';
      NO_ASSERT_CHECK='TRUE';
      NO_DIR_CHECK='TRUE';
      ALLOW_CONNECT='TRUE';
    'VSS_AJ5':
      PIN_NUMBER='(0,0,0,0,0,0,0,0,0,0,AJ5)';
      PINUSE='POWER';
      NO_LOAD_CHECK='Both';
      NO_IO_CHECK='Both';
      NO_ASSERT_CHECK='TRUE';
      NO_DIR_CHECK='TRUE';
      ALLOW_CONNECT='TRUE';
    'VSS_AJ39':
      PIN_NUMBER='(0,0,0,0,0,0,0,0,0,0,AJ39)';
      PINUSE='POWER';
      NO_LOAD_CHECK='Both';
      NO_IO_CHECK='Both';
      NO_ASSERT_CHECK='TRUE';
      NO_DIR_CHECK='TRUE';
      ALLOW_CONNECT='TRUE';
    'VSS_AJ36':
      PIN_NUMBER='(0,0,0,0,0,0,0,0,0,0,AJ36)';
      PINUSE='POWER';
      NO_LOAD_CHECK='Both';
      NO_IO_CHECK='Both';
      NO_ASSERT_CHECK='TRUE';
      NO_DIR_CHECK='TRUE';
      ALLOW_CONNECT='TRUE';
    'VSS_AJ29':
      PIN_NUMBER='(0,0,0,0,0,0,0,0,0,0,AJ29)';
      PINUSE='POWER';
      NO_LOAD_CHECK='Both';
      NO_IO_CHECK='Both';
      NO_ASSERT_CHECK='TRUE';
      NO_DIR_CHECK='TRUE';
      ALLOW_CONNECT='TRUE';
    'VSS_AJ24':
      PIN_NUMBER='(0,0,0,0,0,0,0,0,0,0,AJ24)';
      PINUSE='POWER';
      NO_LOAD_CHECK='Both';
      NO_IO_CHECK='Both';
      NO_ASSERT_CHECK='TRUE';
      NO_DIR_CHECK='TRUE';
      ALLOW_CONNECT='TRUE';
    'VSS_AJ19':
      PIN_NUMBER='(0,0,0,0,0,0,0,0,0,0,AJ19)';
      PINUSE='POWER';
      NO_LOAD_CHECK='Both';
      NO_IO_CHECK='Both';
      NO_ASSERT_CHECK='TRUE';
      NO_DIR_CHECK='TRUE';
      ALLOW_CONNECT='TRUE';
    'VSS_AH8':
      PIN_NUMBER='(0,0,0,0,0,0,0,0,0,0,AH8)';
      PINUSE='POWER';
      NO_LOAD_CHECK='Both';
      NO_IO_CHECK='Both';
      NO_ASSERT_CHECK='TRUE';
      NO_DIR_CHECK='TRUE';
      ALLOW_CONNECT='TRUE';
    'VSS_AH31':
      PIN_NUMBER='(0,0,0,0,0,0,0,0,0,0,AH31)';
      PINUSE='POWER';
      NO_LOAD_CHECK='Both';
      NO_IO_CHECK='Both';
      NO_ASSERT_CHECK='TRUE';
      NO_DIR_CHECK='TRUE';
      ALLOW_CONNECT='TRUE';
    'VSS_AG5':
      PIN_NUMBER='(0,0,0,0,0,0,0,0,0,0,AG5)';
      PINUSE='POWER';
      NO_LOAD_CHECK='Both';
      NO_IO_CHECK='Both';
      NO_ASSERT_CHECK='TRUE';
      NO_DIR_CHECK='TRUE';
      ALLOW_CONNECT='TRUE';
    'VSS_AG39':
      PIN_NUMBER='(0,0,0,0,0,0,0,0,0,0,AG39)';
      PINUSE='POWER';
      NO_LOAD_CHECK='Both';
      NO_IO_CHECK='Both';
      NO_ASSERT_CHECK='TRUE';
      NO_DIR_CHECK='TRUE';
      ALLOW_CONNECT='TRUE';
    'VSS_AG24':
      PIN_NUMBER='(0,0,0,0,0,0,0,0,0,0,AG24)';
      PINUSE='POWER';
      NO_LOAD_CHECK='Both';
      NO_IO_CHECK='Both';
      NO_ASSERT_CHECK='TRUE';
      NO_DIR_CHECK='TRUE';
      ALLOW_CONNECT='TRUE';
    'VSS_AG19':
      PIN_NUMBER='(0,0,0,0,0,0,0,0,0,0,AG19)';
      PINUSE='POWER';
      NO_LOAD_CHECK='Both';
      NO_IO_CHECK='Both';
      NO_ASSERT_CHECK='TRUE';
      NO_DIR_CHECK='TRUE';
      ALLOW_CONNECT='TRUE';
    'VSS_AG13':
      PIN_NUMBER='(0,0,0,0,0,0,0,0,0,0,AG13)';
      PINUSE='POWER';
      NO_LOAD_CHECK='Both';
      NO_IO_CHECK='Both';
      NO_ASSERT_CHECK='TRUE';
      NO_DIR_CHECK='TRUE';
      ALLOW_CONNECT='TRUE';
    'VSS_AF42':
      PIN_NUMBER='(0,0,0,0,0,0,0,0,0,0,AF42)';
      PINUSE='POWER';
      NO_LOAD_CHECK='Both';
      NO_IO_CHECK='Both';
      NO_ASSERT_CHECK='TRUE';
      NO_DIR_CHECK='TRUE';
      ALLOW_CONNECT='TRUE';
    'VSS_AF40':
      PIN_NUMBER='(0,0,0,0,0,0,0,0,0,0,AF40)';
      PINUSE='POWER';
      NO_LOAD_CHECK='Both';
      NO_IO_CHECK='Both';
      NO_ASSERT_CHECK='TRUE';
      NO_DIR_CHECK='TRUE';
      ALLOW_CONNECT='TRUE';
    'VSS_AF31':
      PIN_NUMBER='(0,0,0,0,0,0,0,0,0,0,AF31)';
      PINUSE='POWER';
      NO_LOAD_CHECK='Both';
      NO_IO_CHECK='Both';
      NO_ASSERT_CHECK='TRUE';
      NO_DIR_CHECK='TRUE';
      ALLOW_CONNECT='TRUE';
    'VSS_AF24':
      PIN_NUMBER='(0,0,0,0,0,0,0,0,0,0,AF24)';
      PINUSE='POWER';
      NO_LOAD_CHECK='Both';
      NO_IO_CHECK='Both';
      NO_ASSERT_CHECK='TRUE';
      NO_DIR_CHECK='TRUE';
      ALLOW_CONNECT='TRUE';
    'VSS_AF19':
      PIN_NUMBER='(0,0,0,0,0,0,0,0,0,0,AF19)';
      PINUSE='POWER';
      NO_LOAD_CHECK='Both';
      NO_IO_CHECK='Both';
      NO_ASSERT_CHECK='TRUE';
      NO_DIR_CHECK='TRUE';
      ALLOW_CONNECT='TRUE';
    'VSS_AE5':
      PIN_NUMBER='(0,0,0,0,0,0,0,0,0,0,AE5)';
      PINUSE='POWER';
      NO_LOAD_CHECK='Both';
      NO_IO_CHECK='Both';
      NO_ASSERT_CHECK='TRUE';
      NO_DIR_CHECK='TRUE';
      ALLOW_CONNECT='TRUE';
    'VSS_AE39':
      PIN_NUMBER='(0,0,0,0,0,0,0,0,0,0,AE39)';
      PINUSE='POWER';
      NO_LOAD_CHECK='Both';
      NO_IO_CHECK='Both';
      NO_ASSERT_CHECK='TRUE';
      NO_DIR_CHECK='TRUE';
      ALLOW_CONNECT='TRUE';
    'VSS_AE13':
      PIN_NUMBER='(0,0,0,0,0,0,0,0,0,0,AE13)';
      PINUSE='POWER';
      NO_LOAD_CHECK='Both';
      NO_IO_CHECK='Both';
      NO_ASSERT_CHECK='TRUE';
      NO_DIR_CHECK='TRUE';
      ALLOW_CONNECT='TRUE';
    'VSS_AD8':
      PIN_NUMBER='(0,0,0,0,0,0,0,0,0,0,AD8)';
      PINUSE='POWER';
      NO_LOAD_CHECK='Both';
      NO_IO_CHECK='Both';
      NO_ASSERT_CHECK='TRUE';
      NO_DIR_CHECK='TRUE';
      ALLOW_CONNECT='TRUE';
    'VSS_AD34':
      PIN_NUMBER='(0,0,0,0,0,0,0,0,0,0,AD34)';
      PINUSE='POWER';
      NO_LOAD_CHECK='Both';
      NO_IO_CHECK='Both';
      NO_ASSERT_CHECK='TRUE';
      NO_DIR_CHECK='TRUE';
      ALLOW_CONNECT='TRUE';
    'VSS_AD31':
      PIN_NUMBER='(0,0,0,0,0,0,0,0,0,0,AD31)';
      PINUSE='POWER';
      NO_LOAD_CHECK='Both';
      NO_IO_CHECK='Both';
      NO_ASSERT_CHECK='TRUE';
      NO_DIR_CHECK='TRUE';
      ALLOW_CONNECT='TRUE';
    'VSS_AD24':
      PIN_NUMBER='(0,0,0,0,0,0,0,0,0,0,AD24)';
      PINUSE='POWER';
      NO_LOAD_CHECK='Both';
      NO_IO_CHECK='Both';
      NO_ASSERT_CHECK='TRUE';
      NO_DIR_CHECK='TRUE';
      ALLOW_CONNECT='TRUE';
    'VSS_AD22':
      PIN_NUMBER='(0,0,0,0,0,0,0,0,0,0,AD22)';
      PINUSE='POWER';
      NO_LOAD_CHECK='Both';
      NO_IO_CHECK='Both';
      NO_ASSERT_CHECK='TRUE';
      NO_DIR_CHECK='TRUE';
      ALLOW_CONNECT='TRUE';
    'VSS_AD20':
      PIN_NUMBER='(0,0,0,0,0,0,0,0,0,0,AD20)';
      PINUSE='POWER';
      NO_LOAD_CHECK='Both';
      NO_IO_CHECK='Both';
      NO_ASSERT_CHECK='TRUE';
      NO_DIR_CHECK='TRUE';
      ALLOW_CONNECT='TRUE';
    'VSS_AD19':
      PIN_NUMBER='(0,0,0,0,0,0,0,0,0,0,AD19)';
      PINUSE='POWER';
      NO_LOAD_CHECK='Both';
      NO_IO_CHECK='Both';
      NO_ASSERT_CHECK='TRUE';
      NO_DIR_CHECK='TRUE';
      ALLOW_CONNECT='TRUE';
    'VSS_AD11':
      PIN_NUMBER='(0,0,0,0,0,0,0,0,0,0,AD11)';
      PINUSE='POWER';
      NO_LOAD_CHECK='Both';
      NO_IO_CHECK='Both';
      NO_ASSERT_CHECK='TRUE';
      NO_DIR_CHECK='TRUE';
      ALLOW_CONNECT='TRUE';
    'VSS_AC5':
      PIN_NUMBER='(0,0,0,0,0,0,0,0,0,0,AC5)';
      PINUSE='POWER';
      NO_LOAD_CHECK='Both';
      NO_IO_CHECK='Both';
      NO_ASSERT_CHECK='TRUE';
      NO_DIR_CHECK='TRUE';
      ALLOW_CONNECT='TRUE';
    'VSS_AC39':
      PIN_NUMBER='(0,0,0,0,0,0,0,0,0,0,AC39)';
      PINUSE='POWER';
      NO_LOAD_CHECK='Both';
      NO_IO_CHECK='Both';
      NO_ASSERT_CHECK='TRUE';
      NO_DIR_CHECK='TRUE';
      ALLOW_CONNECT='TRUE';
    'VSS_AC36':
      PIN_NUMBER='(0,0,0,0,0,0,0,0,0,0,AC36)';
      PINUSE='POWER';
      NO_LOAD_CHECK='Both';
      NO_IO_CHECK='Both';
      NO_ASSERT_CHECK='TRUE';
      NO_DIR_CHECK='TRUE';
      ALLOW_CONNECT='TRUE';
    'VSS_AC32':
      PIN_NUMBER='(0,0,0,0,0,0,0,0,0,0,AC32)';
      PINUSE='POWER';
      NO_LOAD_CHECK='Both';
      NO_IO_CHECK='Both';
      NO_ASSERT_CHECK='TRUE';
      NO_DIR_CHECK='TRUE';
      ALLOW_CONNECT='TRUE';
    'VSS_AC29':
      PIN_NUMBER='(0,0,0,0,0,0,0,0,0,0,AC29)';
      PINUSE='POWER';
      NO_LOAD_CHECK='Both';
      NO_IO_CHECK='Both';
      NO_ASSERT_CHECK='TRUE';
      NO_DIR_CHECK='TRUE';
      ALLOW_CONNECT='TRUE';
    'VSS_AB37':
      PIN_NUMBER='(0,0,0,0,0,0,0,0,0,0,AB37)';
      PINUSE='POWER';
      NO_LOAD_CHECK='Both';
      NO_IO_CHECK='Both';
      NO_ASSERT_CHECK='TRUE';
      NO_DIR_CHECK='TRUE';
      ALLOW_CONNECT='TRUE';
    'VSS_AB25':
      PIN_NUMBER='(0,0,0,0,0,0,0,0,0,0,AB25)';
      PINUSE='POWER';
      NO_LOAD_CHECK='Both';
      NO_IO_CHECK='Both';
      NO_ASSERT_CHECK='TRUE';
      NO_DIR_CHECK='TRUE';
      ALLOW_CONNECT='TRUE';
    'VSS_AB17':
      PIN_NUMBER='(0,0,0,0,0,0,0,0,0,0,AB17)';
      PINUSE='POWER';
      NO_LOAD_CHECK='Both';
      NO_IO_CHECK='Both';
      NO_ASSERT_CHECK='TRUE';
      NO_DIR_CHECK='TRUE';
      ALLOW_CONNECT='TRUE';
    'VSS_AB15':
      PIN_NUMBER='(0,0,0,0,0,0,0,0,0,0,AB15)';
      PINUSE='POWER';
      NO_LOAD_CHECK='Both';
      NO_IO_CHECK='Both';
      NO_ASSERT_CHECK='TRUE';
      NO_DIR_CHECK='TRUE';
      ALLOW_CONNECT='TRUE';
    'VSS_AA5':
      PIN_NUMBER='(0,0,0,0,0,0,0,0,0,0,AA5)';
      PINUSE='POWER';
      NO_LOAD_CHECK='Both';
      NO_IO_CHECK='Both';
      NO_ASSERT_CHECK='TRUE';
      NO_DIR_CHECK='TRUE';
      ALLOW_CONNECT='TRUE';
    'VSS_AA39':
      PIN_NUMBER='(0,0,0,0,0,0,0,0,0,0,AA39)';
      PINUSE='POWER';
      NO_LOAD_CHECK='Both';
      NO_IO_CHECK='Both';
      NO_ASSERT_CHECK='TRUE';
      NO_DIR_CHECK='TRUE';
      ALLOW_CONNECT='TRUE';
    'VSS_AA36':
      PIN_NUMBER='(0,0,0,0,0,0,0,0,0,0,AA36)';
      PINUSE='POWER';
      NO_LOAD_CHECK='Both';
      NO_IO_CHECK='Both';
      NO_ASSERT_CHECK='TRUE';
      NO_DIR_CHECK='TRUE';
      ALLOW_CONNECT='TRUE';
    'VSS_AA32':
      PIN_NUMBER='(0,0,0,0,0,0,0,0,0,0,AA32)';
      PINUSE='POWER';
      NO_LOAD_CHECK='Both';
      NO_IO_CHECK='Both';
      NO_ASSERT_CHECK='TRUE';
      NO_DIR_CHECK='TRUE';
      ALLOW_CONNECT='TRUE';
    'VSS_AA27':
      PIN_NUMBER='(0,0,0,0,0,0,0,0,0,0,AA27)';
      PINUSE='POWER';
      NO_LOAD_CHECK='Both';
      NO_IO_CHECK='Both';
      NO_ASSERT_CHECK='TRUE';
      NO_DIR_CHECK='TRUE';
      ALLOW_CONNECT='TRUE';
    'VSS_AA25':
      PIN_NUMBER='(0,0,0,0,0,0,0,0,0,0,AA25)';
      PINUSE='POWER';
      NO_LOAD_CHECK='Both';
      NO_IO_CHECK='Both';
      NO_ASSERT_CHECK='TRUE';
      NO_DIR_CHECK='TRUE';
      ALLOW_CONNECT='TRUE';
    'VSS_AA24':
      PIN_NUMBER='(0,0,0,0,0,0,0,0,0,0,AA24)';
      PINUSE='POWER';
      NO_LOAD_CHECK='Both';
      NO_IO_CHECK='Both';
      NO_ASSERT_CHECK='TRUE';
      NO_DIR_CHECK='TRUE';
      ALLOW_CONNECT='TRUE';
    'VSS_AA22':
      PIN_NUMBER='(0,0,0,0,0,0,0,0,0,0,AA22)';
      PINUSE='POWER';
      NO_LOAD_CHECK='Both';
      NO_IO_CHECK='Both';
      NO_ASSERT_CHECK='TRUE';
      NO_DIR_CHECK='TRUE';
      ALLOW_CONNECT='TRUE';
    'VSS_AA20':
      PIN_NUMBER='(0,0,0,0,0,0,0,0,0,0,AA20)';
      PINUSE='POWER';
      NO_LOAD_CHECK='Both';
      NO_IO_CHECK='Both';
      NO_ASSERT_CHECK='TRUE';
      NO_DIR_CHECK='TRUE';
      ALLOW_CONNECT='TRUE';
    'VSS_AA19':
      PIN_NUMBER='(0,0,0,0,0,0,0,0,0,0,AA19)';
      PINUSE='POWER';
      NO_LOAD_CHECK='Both';
      NO_IO_CHECK='Both';
      NO_ASSERT_CHECK='TRUE';
      NO_DIR_CHECK='TRUE';
      ALLOW_CONNECT='TRUE';
    'VSS_AA17':
      PIN_NUMBER='(0,0,0,0,0,0,0,0,0,0,AA17)';
      PINUSE='POWER';
      NO_LOAD_CHECK='Both';
      NO_IO_CHECK='Both';
      NO_ASSERT_CHECK='TRUE';
      NO_DIR_CHECK='TRUE';
      ALLOW_CONNECT='TRUE';
    'VSS_A26':
      PIN_NUMBER='(0,0,0,0,0,0,0,0,0,0,A26)';
      PINUSE='POWER';
      NO_LOAD_CHECK='Both';
      NO_IO_CHECK='Both';
      NO_ASSERT_CHECK='TRUE';
      NO_DIR_CHECK='TRUE';
      ALLOW_CONNECT='TRUE';
    'VSS_A24':
      PIN_NUMBER='(0,0,0,0,0,0,0,0,0,0,A24)';
      PINUSE='POWER';
      NO_LOAD_CHECK='Both';
      NO_IO_CHECK='Both';
      NO_ASSERT_CHECK='TRUE';
      NO_DIR_CHECK='TRUE';
      ALLOW_CONNECT='TRUE';
    'VSS_A22':
      PIN_NUMBER='(0,0,0,0,0,0,0,0,0,0,A22)';
      PINUSE='POWER';
      NO_LOAD_CHECK='Both';
      NO_IO_CHECK='Both';
      NO_ASSERT_CHECK='TRUE';
      NO_DIR_CHECK='TRUE';
      ALLOW_CONNECT='TRUE';
    'VSS_A20':
      PIN_NUMBER='(0,0,0,0,0,0,0,0,0,0,A20)';
      PINUSE='POWER';
      NO_LOAD_CHECK='Both';
      NO_IO_CHECK='Both';
      NO_ASSERT_CHECK='TRUE';
      NO_DIR_CHECK='TRUE';
      ALLOW_CONNECT='TRUE';
  end_pin;
  body
      PART_NAME='EMMITSBURG_REV0P9';
      BODY_NAME='EMMITSBURG_REV0P9';
      PHYS_DES_PREFIX='U';
      CLASS='IC';
      STANDARD='';
      LIFECYCLE='';
      JEDEC_TYPE='BGA749_22X23';
      DESCRIPTION='IC CTRL(749P)EMMITSBURG-QV2N(FCBGA)';
      MANUFTR='INT';
      MANUF_PN='GFNOCPU04302300-QV2N-MM#99A1WT';
      RD_CMPLS_LVL='';
      CMPLS_LVL='';
      FROM_PJ='S6X-SANDY';
      DIP_SMD='';
      DATA='INT_emmitsburg-eds-606161-rev0-4.pdf';
      EE_CHECK_LIST='';
      FP_ECN='Emmitsburg_rev0p9.msg';
      PSL='';
      CREATOR='';
      STATUS='';
      MSD='NA';
      ESD_CDM='N/A';
      ESD_HBM='N/A';
      ESD_MM='N/A';
      PIN_LENGTH_SHORT_PIN='0 MILS';
      PIN_LENGTH_LONG_PIN='0 MILS';
      CREATEDAY='20191211';
      PARENT_PART_TYPE='EMMITSBURG_REV0P9';
      PARENT_PPT='EMMITSBURG_REV0P9';
      PARENT_PPT_PART='EMMITSBURG_REV0P9-GFNOCPU04302300-QV2N-MM#99A1WT,SMLF,IC,AJ0QV2N0T00';
  end_body;
end_primitive;
primitive 'GL852GOHY60-GL852G-OHY60,SMLF,A';
  pin
    'X1':
      PIN_NUMBER='(10)';
      INPUT_LOAD='(-0.01,0.01)';
      PINUSE='IN';
    'X2':
      PIN_NUMBER='(11)';
      OUTPUT_LOAD='(1.0,-1.0)';
      PINUSE='OUT';
    'TEST||SCL':
      PIN_NUMBER='(18)';
      BIDIRECTIONAL='TRUE';
      INPUT_LOAD='(-0.01,0.01)';
      OUTPUT_LOAD='(1.0,-1.0)';
      PINUSE='BI';
    'SDA':
      PIN_NUMBER='(26)';
      BIDIRECTIONAL='TRUE';
      INPUT_LOAD='(-0.01,0.01)';
      OUTPUT_LOAD='(1.0,-1.0)';
      PINUSE='BI';
    'V5':
      PIN_NUMBER='(27)';
      PINUSE='POWER';
      NO_LOAD_CHECK='Both';
      NO_IO_CHECK='Both';
      NO_ASSERT_CHECK='TRUE';
      NO_DIR_CHECK='TRUE';
      ALLOW_CONNECT='TRUE';
    'V33':
      PIN_NUMBER='(28)';
      PINUSE='POWER';
      NO_LOAD_CHECK='Both';
      NO_IO_CHECK='Both';
      NO_ASSERT_CHECK='TRUE';
      NO_DIR_CHECK='TRUE';
      ALLOW_CONNECT='TRUE';
    'AVDD'<0>:
      PIN_NUMBER='(5)';
      PINUSE='POWER';
      NO_LOAD_CHECK='Both';
      NO_IO_CHECK='Both';
      NO_ASSERT_CHECK='TRUE';
      NO_DIR_CHECK='TRUE';
      ALLOW_CONNECT='TRUE';
    'AVDD'<1>:
      PIN_NUMBER='(9)';
      PINUSE='POWER';
      NO_LOAD_CHECK='Both';
      NO_IO_CHECK='Both';
      NO_ASSERT_CHECK='TRUE';
      NO_DIR_CHECK='TRUE';
      ALLOW_CONNECT='TRUE';
    'AVDD'<2>:
      PIN_NUMBER='(14)';
      PINUSE='POWER';
      NO_LOAD_CHECK='Both';
      NO_IO_CHECK='Both';
      NO_ASSERT_CHECK='TRUE';
      NO_DIR_CHECK='TRUE';
      ALLOW_CONNECT='TRUE';
    'DVDD':
      PIN_NUMBER='(21)';
      PINUSE='POWER';
      NO_LOAD_CHECK='Both';
      NO_IO_CHECK='Both';
      NO_ASSERT_CHECK='TRUE';
      NO_DIR_CHECK='TRUE';
      ALLOW_CONNECT='TRUE';
    'TH':
      PIN_NUMBER='(TH)';
      PINUSE='POWER';
      NO_LOAD_CHECK='Both';
      NO_IO_CHECK='Both';
      NO_ASSERT_CHECK='TRUE';
      NO_DIR_CHECK='TRUE';
      ALLOW_CONNECT='TRUE';
    'OVCUR1#||SMC':
      PIN_NUMBER='(25)';
      INPUT_LOAD='(-0.01,0.01)';
      PINUSE='IN';
    'OVCUR2#||SMD':
      PIN_NUMBER='(24)';
      BIDIRECTIONAL='TRUE';
      INPUT_LOAD='(-0.01,0.01)';
      OUTPUT_LOAD='(1.0,-1.0)';
      PINUSE='BI';
    'OVCUR3#':
      PIN_NUMBER='(20)';
      INPUT_LOAD='(-0.01,0.01)';
      PINUSE='IN';
    'OVCUR4#':
      PIN_NUMBER='(19)';
      INPUT_LOAD='(-0.01,0.01)';
      PINUSE='IN';
    'RESET#':
      PIN_NUMBER='(17)';
      INPUT_LOAD='(-0.01,0.01)';
      PINUSE='IN';
    'PGANG':
      PIN_NUMBER='(23)';
      BIDIRECTIONAL='TRUE';
      INPUT_LOAD='(-0.01,0.01)';
      OUTPUT_LOAD='(1.0,-1.0)';
      PINUSE='BI';
    'PSELF':
      PIN_NUMBER='(22)';
      INPUT_LOAD='(-0.01,0.01)';
      PINUSE='IN';
    'RREF':
      PIN_NUMBER='(8)';
      INPUT_LOAD='(-0.01,0.01)';
      PINUSE='IN';
    'DP0':
      PIN_NUMBER='(2)';
      BIDIRECTIONAL='TRUE';
      INPUT_LOAD='(-0.01,0.01)';
      OUTPUT_LOAD='(1.0,-1.0)';
      PINUSE='BI';
    'DM0':
      PIN_NUMBER='(1)';
      BIDIRECTIONAL='TRUE';
      INPUT_LOAD='(-0.01,0.01)';
      OUTPUT_LOAD='(1.0,-1.0)';
      PINUSE='BI';
    'DP1':
      PIN_NUMBER='(4)';
      BIDIRECTIONAL='TRUE';
      INPUT_LOAD='(-0.01,0.01)';
      OUTPUT_LOAD='(1.0,-1.0)';
      PINUSE='BI';
    'DM1':
      PIN_NUMBER='(3)';
      BIDIRECTIONAL='TRUE';
      INPUT_LOAD='(-0.01,0.01)';
      OUTPUT_LOAD='(1.0,-1.0)';
      PINUSE='BI';
    'DP2':
      PIN_NUMBER='(7)';
      BIDIRECTIONAL='TRUE';
      INPUT_LOAD='(-0.01,0.01)';
      OUTPUT_LOAD='(1.0,-1.0)';
      PINUSE='BI';
    'DM2':
      PIN_NUMBER='(6)';
      BIDIRECTIONAL='TRUE';
      INPUT_LOAD='(-0.01,0.01)';
      OUTPUT_LOAD='(1.0,-1.0)';
      PINUSE='BI';
    'DP3':
      PIN_NUMBER='(13)';
      BIDIRECTIONAL='TRUE';
      INPUT_LOAD='(-0.01,0.01)';
      OUTPUT_LOAD='(1.0,-1.0)';
      PINUSE='BI';
    'DM3':
      PIN_NUMBER='(12)';
      BIDIRECTIONAL='TRUE';
      INPUT_LOAD='(-0.01,0.01)';
      OUTPUT_LOAD='(1.0,-1.0)';
      PINUSE='BI';
    'DP4':
      PIN_NUMBER='(16)';
      BIDIRECTIONAL='TRUE';
      INPUT_LOAD='(-0.01,0.01)';
      OUTPUT_LOAD='(1.0,-1.0)';
      PINUSE='BI';
    'DM4':
      PIN_NUMBER='(15)';
      BIDIRECTIONAL='TRUE';
      INPUT_LOAD='(-0.01,0.01)';
      OUTPUT_LOAD='(1.0,-1.0)';
      PINUSE='BI';
  end_pin;
  body
      PART_NAME='GL852GOHY60';
      BODY_NAME='GL852GOHY60';
      PHYS_DES_PREFIX='U';
      CLASS='IC';
      STANDARD='';
      LIFECYCLE='';
      JEDEC_TYPE='QFN28_THXL';
      DESCRIPTION='IC CTRL(28P) GL852G-OHY60(QFN)';
      MANUFTR='GSL';
      MANUF_PN='GL852G-OHY60';
      RD_CMPLS_LVL='EP(V1)';
      CMPLS_LVL='EP(V1)';
      FROM_PJ='T6UA-CART';
      DIP_SMD='';
      DATA='GSL_GL852G-OHY60.pdf';
      EE_CHECK_LIST='';
      FP_ECN='GL852G-OHY60.msg';
      PSL='';
      CREATOR='';
      STATUS='';
      MSD='';
      ESD_CDM='';
      ESD_HBM='';
      ESD_MM='';
      PIN_LENGTH_SHORT_PIN='0 MILS';
      PIN_LENGTH_LONG_PIN='0 MILS';
      CREATEDAY='20210927';
      PARENT_PART_TYPE='GL852GOHY60';
      PARENT_PPT='GL852GOHY60';
      PARENT_PPT_PART='GL852GOHY60-GL852G-OHY60,SMLF,IC,AL000852001';
  end_body;
end_primitive;
primitive 'GL852GOHY60-GL852G-OHY60,SMLF,B';
  pin
    'X1':
      PIN_NUMBER='(10)';
      INPUT_LOAD='(-0.01,0.01)';
      PINUSE='IN';
    'X2':
      PIN_NUMBER='(11)';
      OUTPUT_LOAD='(1.0,-1.0)';
      PINUSE='OUT';
    'TEST||SCL':
      PIN_NUMBER='(18)';
      BIDIRECTIONAL='TRUE';
      INPUT_LOAD='(-0.01,0.01)';
      OUTPUT_LOAD='(1.0,-1.0)';
      PINUSE='BI';
    'SDA':
      PIN_NUMBER='(26)';
      BIDIRECTIONAL='TRUE';
      INPUT_LOAD='(-0.01,0.01)';
      OUTPUT_LOAD='(1.0,-1.0)';
      PINUSE='BI';
    'V5':
      PIN_NUMBER='(27)';
      PINUSE='POWER';
      NO_LOAD_CHECK='Both';
      NO_IO_CHECK='Both';
      NO_ASSERT_CHECK='TRUE';
      NO_DIR_CHECK='TRUE';
      ALLOW_CONNECT='TRUE';
    'V33':
      PIN_NUMBER='(28)';
      PINUSE='POWER';
      NO_LOAD_CHECK='Both';
      NO_IO_CHECK='Both';
      NO_ASSERT_CHECK='TRUE';
      NO_DIR_CHECK='TRUE';
      ALLOW_CONNECT='TRUE';
    'AVDD'<0>:
      PIN_NUMBER='(5)';
      PINUSE='POWER';
      NO_LOAD_CHECK='Both';
      NO_IO_CHECK='Both';
      NO_ASSERT_CHECK='TRUE';
      NO_DIR_CHECK='TRUE';
      ALLOW_CONNECT='TRUE';
    'AVDD'<1>:
      PIN_NUMBER='(9)';
      PINUSE='POWER';
      NO_LOAD_CHECK='Both';
      NO_IO_CHECK='Both';
      NO_ASSERT_CHECK='TRUE';
      NO_DIR_CHECK='TRUE';
      ALLOW_CONNECT='TRUE';
    'AVDD'<2>:
      PIN_NUMBER='(14)';
      PINUSE='POWER';
      NO_LOAD_CHECK='Both';
      NO_IO_CHECK='Both';
      NO_ASSERT_CHECK='TRUE';
      NO_DIR_CHECK='TRUE';
      ALLOW_CONNECT='TRUE';
    'DVDD':
      PIN_NUMBER='(21)';
      PINUSE='POWER';
      NO_LOAD_CHECK='Both';
      NO_IO_CHECK='Both';
      NO_ASSERT_CHECK='TRUE';
      NO_DIR_CHECK='TRUE';
      ALLOW_CONNECT='TRUE';
    'TH':
      PIN_NUMBER='(TH)';
      PINUSE='POWER';
      NO_LOAD_CHECK='Both';
      NO_IO_CHECK='Both';
      NO_ASSERT_CHECK='TRUE';
      NO_DIR_CHECK='TRUE';
      ALLOW_CONNECT='TRUE';
    'OVCUR1#||SMC':
      PIN_NUMBER='(25)';
      INPUT_LOAD='(-0.01,0.01)';
      PINUSE='IN';
    'OVCUR2#||SMD':
      PIN_NUMBER='(24)';
      BIDIRECTIONAL='TRUE';
      INPUT_LOAD='(-0.01,0.01)';
      OUTPUT_LOAD='(1.0,-1.0)';
      PINUSE='BI';
    'OVCUR3#':
      PIN_NUMBER='(20)';
      INPUT_LOAD='(-0.01,0.01)';
      PINUSE='IN';
    'OVCUR4#':
      PIN_NUMBER='(19)';
      INPUT_LOAD='(-0.01,0.01)';
      PINUSE='IN';
    'RESET#':
      PIN_NUMBER='(17)';
      INPUT_LOAD='(-0.01,0.01)';
      PINUSE='IN';
    'PGANG':
      PIN_NUMBER='(23)';
      BIDIRECTIONAL='TRUE';
      INPUT_LOAD='(-0.01,0.01)';
      OUTPUT_LOAD='(1.0,-1.0)';
      PINUSE='BI';
    'PSELF':
      PIN_NUMBER='(22)';
      INPUT_LOAD='(-0.01,0.01)';
      PINUSE='IN';
    'RREF':
      PIN_NUMBER='(8)';
      INPUT_LOAD='(-0.01,0.01)';
      PINUSE='IN';
    'DP0':
      PIN_NUMBER='(2)';
      BIDIRECTIONAL='TRUE';
      INPUT_LOAD='(-0.01,0.01)';
      OUTPUT_LOAD='(1.0,-1.0)';
      PINUSE='BI';
    'DM0':
      PIN_NUMBER='(1)';
      BIDIRECTIONAL='TRUE';
      INPUT_LOAD='(-0.01,0.01)';
      OUTPUT_LOAD='(1.0,-1.0)';
      PINUSE='BI';
    'DP1':
      PIN_NUMBER='(4)';
      BIDIRECTIONAL='TRUE';
      INPUT_LOAD='(-0.01,0.01)';
      OUTPUT_LOAD='(1.0,-1.0)';
      PINUSE='BI';
    'DM1':
      PIN_NUMBER='(3)';
      BIDIRECTIONAL='TRUE';
      INPUT_LOAD='(-0.01,0.01)';
      OUTPUT_LOAD='(1.0,-1.0)';
      PINUSE='BI';
    'DP2':
      PIN_NUMBER='(7)';
      BIDIRECTIONAL='TRUE';
      INPUT_LOAD='(-0.01,0.01)';
      OUTPUT_LOAD='(1.0,-1.0)';
      PINUSE='BI';
    'DM2':
      PIN_NUMBER='(6)';
      BIDIRECTIONAL='TRUE';
      INPUT_LOAD='(-0.01,0.01)';
      OUTPUT_LOAD='(1.0,-1.0)';
      PINUSE='BI';
    'DP3':
      PIN_NUMBER='(13)';
      BIDIRECTIONAL='TRUE';
      INPUT_LOAD='(-0.01,0.01)';
      OUTPUT_LOAD='(1.0,-1.0)';
      PINUSE='BI';
    'DM3':
      PIN_NUMBER='(12)';
      BIDIRECTIONAL='TRUE';
      INPUT_LOAD='(-0.01,0.01)';
      OUTPUT_LOAD='(1.0,-1.0)';
      PINUSE='BI';
    'DP4':
      PIN_NUMBER='(16)';
      BIDIRECTIONAL='TRUE';
      INPUT_LOAD='(-0.01,0.01)';
      OUTPUT_LOAD='(1.0,-1.0)';
      PINUSE='BI';
    'DM4':
      PIN_NUMBER='(15)';
      BIDIRECTIONAL='TRUE';
      INPUT_LOAD='(-0.01,0.01)';
      OUTPUT_LOAD='(1.0,-1.0)';
      PINUSE='BI';
  end_pin;
  body
      PART_NAME='GL852GOHY60';
      BODY_NAME='GL852GOHY60';
      PHYS_DES_PREFIX='U';
      CLASS='IC';
      STANDARD='';
      LIFECYCLE='';
      JEDEC_TYPE='QFN28_THXL';
      DESCRIPTION='IC CTRL(28P) GL852G-OHY60(QFN)';
      MANUFTR='GSL';
      MANUF_PN='GL852G-OHY60';
      RD_CMPLS_LVL='EP(V1)';
      CMPLS_LVL='EP(V1)';
      FROM_PJ='T6UA-CART';
      DIP_SMD='';
      DATA='GSL_GL852G-OHY60.pdf';
      EE_CHECK_LIST='';
      FP_ECN='GL852G-OHY60.msg';
      PSL='';
      CREATOR='';
      STATUS='';
      MSD='';
      ESD_CDM='';
      ESD_HBM='';
      ESD_MM='';
      PIN_LENGTH_SHORT_PIN='0 MILS';
      PIN_LENGTH_LONG_PIN='0 MILS';
      CREATEDAY='20210927';
      PARENT_PART_TYPE='GL852GOHY60';
      PARENT_PPT='GL852GOHY60';
      PARENT_PPT_PART='GL852GOHY60-GL852G-OHY60,SMLF,EMPTY,AL000852001';
  end_body;
end_primitive;
primitive 'GND_HOLE_TH-EMPTY,GND_HOLE140';
  pin
    'GND3':
      PIN_NUMBER='(3)';
      PINUSE='POWER';
    'GND2':
      PIN_NUMBER='(2)';
      PINUSE='POWER';
    'GND9':
      PIN_NUMBER='(9)';
      PINUSE='POWER';
    'GND8':
      PIN_NUMBER='(8)';
      PINUSE='POWER';
    'GND7':
      PIN_NUMBER='(7)';
      PINUSE='POWER';
    'GND6':
      PIN_NUMBER='(6)';
      PINUSE='POWER';
    'GND5':
      PIN_NUMBER='(5)';
      PINUSE='POWER';
    'GND4':
      PIN_NUMBER='(4)';
      PINUSE='POWER';
  end_pin;
  body
      NC_PINS='(1)';
      CLASS='IO';
      PART_NAME='GND_HOLE';
      PHYS_DES_PREFIX='H';
      STANDARD='';
      LIFECYCLE='';
      JEDEC_TYPE='GND_C10D5-5B10';
      DESCRIPTION='GNDHOLE_8PIN_C10D5-5B10';
      COMPONENT_TYPE='';
      LEAD_LENGTH='';
      DFM_EXCLUSION='';
      PARENT_PART_TYPE='GND_HOLE';
      PARENT_PPT='GND_HOLE';
      PARENT_PPT_PART='GND_HOLE_TH-EMPTY,GND_HOLE140';
  end_body;
end_primitive;
primitive 'GND_HOLE_TH-EMPTY,GND_HOLE514';
  pin
    'GND3':
      PIN_NUMBER='(3)';
      PINUSE='POWER';
    'GND2':
      PIN_NUMBER='(2)';
      PINUSE='POWER';
    'GND9':
      PIN_NUMBER='(9)';
      PINUSE='POWER';
    'GND8':
      PIN_NUMBER='(8)';
      PINUSE='POWER';
    'GND7':
      PIN_NUMBER='(7)';
      PINUSE='POWER';
    'GND6':
      PIN_NUMBER='(6)';
      PINUSE='POWER';
    'GND5':
      PIN_NUMBER='(5)';
      PINUSE='POWER';
    'GND4':
      PIN_NUMBER='(4)';
      PINUSE='POWER';
  end_pin;
  body
      NC_PINS='(1)';
      CLASS='IO';
      PART_NAME='GND_HOLE';
      PHYS_DES_PREFIX='H';
      STANDARD='';
      LIFECYCLE='';
      JEDEC_TYPE='GND_C10D6-5B10_NPM_RB_NSP';
      DESCRIPTION='GND_C10D6-5B10_NPM_RB_NSP';
      COMPONENT_TYPE='';
      LEAD_LENGTH='';
      DFM_EXCLUSION='';
      PARENT_PART_TYPE='GND_HOLE';
      PARENT_PPT='GND_HOLE';
      PARENT_PPT_PART='GND_HOLE_TH-EMPTY,GND_HOLE514';
  end_body;
end_primitive;
primitive 'GND_HOLE_TH-EMPTY,TMP-QGND_HOLA';
  pin
    'GND3':
      PIN_NUMBER='(3)';
      PINUSE='POWER';
    'GND2':
      PIN_NUMBER='(2)';
      PINUSE='POWER';
    'GND9':
      PIN_NUMBER='(9)';
      PINUSE='POWER';
    'GND8':
      PIN_NUMBER='(8)';
      PINUSE='POWER';
    'GND7':
      PIN_NUMBER='(7)';
      PINUSE='POWER';
    'GND6':
      PIN_NUMBER='(6)';
      PINUSE='POWER';
    'GND5':
      PIN_NUMBER='(5)';
      PINUSE='POWER';
    'GND4':
      PIN_NUMBER='(4)';
      PINUSE='POWER';
  end_pin;
  body
      NC_PINS='(1)';
      CLASS='IO';
      PART_NAME='GND_HOLE';
      PHYS_DES_PREFIX='H';
      STANDARD='';
      LIFECYCLE='';
      JEDEC_TYPE='GND_C8D4B8';
      DESCRIPTION='GND_C8D4B8';
      COMPONENT_TYPE='';
      LEAD_LENGTH='';
      DFM_EXCLUSION='';
      PARENT_PART_TYPE='GND_HOLE';
      PARENT_PPT='GND_HOLE';
      PARENT_PPT_PART='GND_HOLE_TH-EMPTY,TMP-QGND_HOLE12';
  end_body;
end_primitive;
primitive 'GTL2014PW-GTL2014PW,SMLF,IC,ALA';
  pin
    'B0':
      PIN_NUMBER='(2)';
      BIDIRECTIONAL='TRUE';
      INPUT_LOAD='(-0.01,0.01)';
      OUTPUT_LOAD='(1.0,-1.0)';
      PINUSE='BI';
    'B1':
      PIN_NUMBER='(3)';
      BIDIRECTIONAL='TRUE';
      INPUT_LOAD='(-0.01,0.01)';
      OUTPUT_LOAD='(1.0,-1.0)';
      PINUSE='BI';
    'B2':
      PIN_NUMBER='(5)';
      BIDIRECTIONAL='TRUE';
      INPUT_LOAD='(-0.01,0.01)';
      OUTPUT_LOAD='(1.0,-1.0)';
      PINUSE='BI';
    'B3':
      PIN_NUMBER='(6)';
      BIDIRECTIONAL='TRUE';
      INPUT_LOAD='(-0.01,0.01)';
      OUTPUT_LOAD='(1.0,-1.0)';
      PINUSE='BI';
    'GND_2':
      PIN_NUMBER='(11)';
      PINUSE='POWER';
      NO_LOAD_CHECK='Both';
      NO_IO_CHECK='Both';
      NO_ASSERT_CHECK='TRUE';
      NO_DIR_CHECK='TRUE';
      ALLOW_CONNECT='TRUE';
    'GND_1':
      PIN_NUMBER='(8)';
      PINUSE='POWER';
      NO_LOAD_CHECK='Both';
      NO_IO_CHECK='Both';
      NO_ASSERT_CHECK='TRUE';
      NO_DIR_CHECK='TRUE';
      ALLOW_CONNECT='TRUE';
    'GND_0':
      PIN_NUMBER='(7)';
      PINUSE='POWER';
      NO_LOAD_CHECK='Both';
      NO_IO_CHECK='Both';
      NO_ASSERT_CHECK='TRUE';
      NO_DIR_CHECK='TRUE';
      ALLOW_CONNECT='TRUE';
    'A3':
      PIN_NUMBER='(9)';
      BIDIRECTIONAL='TRUE';
      INPUT_LOAD='(-0.01,0.01)';
      OUTPUT_LOAD='(1.0,-1.0)';
      PINUSE='BI';
    'A2':
      PIN_NUMBER='(10)';
      BIDIRECTIONAL='TRUE';
      INPUT_LOAD='(-0.01,0.01)';
      OUTPUT_LOAD='(1.0,-1.0)';
      PINUSE='BI';
    'A1':
      PIN_NUMBER='(12)';
      BIDIRECTIONAL='TRUE';
      INPUT_LOAD='(-0.01,0.01)';
      OUTPUT_LOAD='(1.0,-1.0)';
      PINUSE='BI';
    'A0':
      PIN_NUMBER='(13)';
      BIDIRECTIONAL='TRUE';
      INPUT_LOAD='(-0.01,0.01)';
      OUTPUT_LOAD='(1.0,-1.0)';
      PINUSE='BI';
    'DIR':
      PIN_NUMBER='(1)';
      INPUT_LOAD='(-0.01,0.01)';
      PINUSE='IN';
    'VREF':
      PIN_NUMBER='(4)';
      PINUSE='POWER';
      NO_LOAD_CHECK='Both';
      NO_IO_CHECK='Both';
      NO_ASSERT_CHECK='TRUE';
      NO_DIR_CHECK='TRUE';
      ALLOW_CONNECT='TRUE';
    'VCC':
      PIN_NUMBER='(14)';
      PINUSE='POWER';
      NO_LOAD_CHECK='Both';
      NO_IO_CHECK='Both';
      NO_ASSERT_CHECK='TRUE';
      NO_DIR_CHECK='TRUE';
      ALLOW_CONNECT='TRUE';
  end_pin;
  body
      PART_NAME='GTL2014PW';
      BODY_NAME='GTL2014PW';
      PHYS_DES_PREFIX='U';
      CLASS='IC';
      STANDARD='';
      LIFECYCLE='';
      JEDEC_TYPE='TSSOP14';
      DESCRIPTION='IC OTHER(14P) GTL2014PW(TSSOP)';
      MANUFTR='NXP';
      MANUF_PN='GTL2014PW';
      RD_CMPLS_LVL='EP(V1)';
      CMPLS_LVL='EP(V1)';
      FROM_PJ='S2B-YU-LIN';
      DIP_SMD='';
      DATA='NXP_GTL2014.pdf';
      EE_CHECK_LIST='';
      FP_ECN='';
      PSL='';
      CREATOR='';
      STATUS='';
      CREATEDAY='20120731';
      PARENT_PART_TYPE='GTL2014PW';
      PARENT_PPT='GTL2014PW';
      PARENT_PPT_PART='GTL2014PW-GTL2014PW,SMLF,IC,AL002014K01';
  end_body;
end_primitive;
primitive 'HOLE_TH-EMPTY,DUMMY50';
  pin
    '1':
      PIN_NUMBER='(1)';
      INPUT_LOAD='(-0.01,0.01)';
      OUTPUT_LOAD='(1.0,-1.0)';
      BIDIRECTIONAL='TRUE';
      PINUSE='BI';
  end_pin;
  body
      CLASS='IO';
      PART_NAME='HOLE';
      PHYS_DES_PREFIX='H';
      STANDARD='';
      LIFECYCLE='';
      JEDEC_TYPE='HOLE_TOOLINGD125N_T2-0';
      DESCRIPTION='HOLE_TOOLINGD125N_T2-0';
      COMPONENT_TYPE='';
      LEAD_LENGTH='';
      DFM_EXCLUSION='';
      PARENT_PART_TYPE='HOLE';
      PARENT_PPT='HOLE';
      PARENT_PPT_PART='HOLE_TH-EMPTY,DUMMY50';
  end_body;
end_primitive;
primitive 'HOLE_TH-EMPTY,HOLE1079';
  pin
    '1':
      PIN_NUMBER='(1)';
      INPUT_LOAD='(-0.01,0.01)';
      OUTPUT_LOAD='(1.0,-1.0)';
      BIDIRECTIONAL='TRUE';
      PINUSE='BI';
  end_pin;
  body
      CLASS='IO';
      PART_NAME='HOLE';
      PHYS_DES_PREFIX='H';
      STANDARD='';
      LIFECYCLE='';
      JEDEC_TYPE='HOLE_D3-429N';
      DESCRIPTION='HOLE_D3-429N';
      COMPONENT_TYPE='';
      LEAD_LENGTH='';
      DFM_EXCLUSION='';
      PARENT_PART_TYPE='HOLE';
      PARENT_PPT='HOLE';
      PARENT_PPT_PART='HOLE_TH-EMPTY,HOLE1079';
  end_body;
end_primitive;
primitive 'HOLE_TH-EMPTY,HOLE1187';
  pin
    '1':
      PIN_NUMBER='(1)';
      INPUT_LOAD='(-0.01,0.01)';
      OUTPUT_LOAD='(1.0,-1.0)';
      BIDIRECTIONAL='TRUE';
      PINUSE='BI';
  end_pin;
  body
      CLASS='IO';
      PART_NAME='HOLE';
      PHYS_DES_PREFIX='H';
      STANDARD='';
      LIFECYCLE='';
      JEDEC_TYPE='HOLE_R4-2X5D2B4_IX0-1T_NPM_RB';
      DESCRIPTION='HOLE_R4-2X5D2B4_IX0-1T_NPM_RB';
      COMPONENT_TYPE='';
      LEAD_LENGTH='';
      DFM_EXCLUSION='';
      PARENT_PART_TYPE='HOLE';
      PARENT_PPT='HOLE';
      PARENT_PPT_PART='HOLE_TH-EMPTY,HOLE1187';
  end_body;
end_primitive;
primitive 'HOLE_TH-EMPTY,HOLE1195';
  pin
    '1':
      PIN_NUMBER='(1)';
      INPUT_LOAD='(-0.01,0.01)';
      OUTPUT_LOAD='(1.0,-1.0)';
      BIDIRECTIONAL='TRUE';
      PINUSE='BI';
  end_pin;
  body
      CLASS='IO';
      PART_NAME='HOLE';
      PHYS_DES_PREFIX='H';
      STANDARD='';
      LIFECYCLE='';
      JEDEC_TYPE='HOLE_C8D4-2B8_NPB';
      DESCRIPTION='HOLE_C8D4-2B8_NPB';
      COMPONENT_TYPE='';
      LEAD_LENGTH='';
      DFM_EXCLUSION='';
      PARENT_PART_TYPE='HOLE';
      PARENT_PPT='HOLE';
      PARENT_PPT_PART='HOLE_TH-EMPTY,HOLE1195';
  end_body;
end_primitive;
primitive 'HOLE_TH-EMPTY,HOLE1247';
  pin
    '1':
      PIN_NUMBER='(1)';
      INPUT_LOAD='(-0.01,0.01)';
      OUTPUT_LOAD='(1.0,-1.0)';
      BIDIRECTIONAL='TRUE';
      PINUSE='BI';
  end_pin;
  body
      CLASS='IO';
      PART_NAME='HOLE';
      PHYS_DES_PREFIX='H';
      STANDARD='';
      LIFECYCLE='';
      JEDEC_TYPE='H_OB6-4X8OBD3-2X4-8B6-4X8N_RO6X7-6_NPM';
      DESCRIPTION='HOLE_OB6-4X8OBD3-2X4-8B6-4X8N_RO6X7-6_NPM';
      COMPONENT_TYPE='';
      LEAD_LENGTH='';
      DFM_EXCLUSION='';
      PARENT_PART_TYPE='HOLE';
      PARENT_PPT='HOLE';
      PARENT_PPT_PART='HOLE_TH-EMPTY,HOLE1247';
  end_body;
end_primitive;
primitive 'HOLE_TH-EMPTY,HOLE1248';
  pin
    '1':
      PIN_NUMBER='(1)';
      INPUT_LOAD='(-0.01,0.01)';
      OUTPUT_LOAD='(1.0,-1.0)';
      BIDIRECTIONAL='TRUE';
      PINUSE='BI';
  end_pin;
  body
      CLASS='IO';
      PART_NAME='HOLE';
      PHYS_DES_PREFIX='H';
      STANDARD='';
      LIFECYCLE='';
      JEDEC_TYPE='HOLE_C4-5D3-8B8I5-6_RO6-6_NPT_RB';
      DESCRIPTION='HOLE_C4-5D3-8B8I5-6_RO6-6_NPT_RB';
      COMPONENT_TYPE='';
      LEAD_LENGTH='';
      DFM_EXCLUSION='';
      PARENT_PART_TYPE='HOLE';
      PARENT_PPT='HOLE';
      PARENT_PPT_PART='HOLE_TH-EMPTY,HOLE1248';
  end_body;
end_primitive;
primitive 'HOLE_TH-EMPTY,HOLE372';
  pin
    '1':
      PIN_NUMBER='(1)';
      INPUT_LOAD='(-0.01,0.01)';
      OUTPUT_LOAD='(1.0,-1.0)';
      BIDIRECTIONAL='TRUE';
      PINUSE='BI';
  end_pin;
  body
      CLASS='IO';
      PART_NAME='HOLE';
      PHYS_DES_PREFIX='H';
      STANDARD='';
      LIFECYCLE='';
      JEDEC_TYPE='HOLE_C5D3-1N';
      DESCRIPTION='HOLE_C5D3-1N';
      COMPONENT_TYPE='';
      LEAD_LENGTH='';
      DFM_EXCLUSION='';
      PARENT_PART_TYPE='HOLE';
      PARENT_PPT='HOLE';
      PARENT_PPT_PART='HOLE_TH-EMPTY,HOLE372';
  end_body;
end_primitive;
primitive 'HOLE_TH-EMPTY,HOLE596';
  pin
    '1':
      PIN_NUMBER='(1)';
      INPUT_LOAD='(-0.01,0.01)';
      OUTPUT_LOAD='(1.0,-1.0)';
      BIDIRECTIONAL='TRUE';
      PINUSE='BI';
  end_pin;
  body
      CLASS='IO';
      PART_NAME='HOLE';
      PHYS_DES_PREFIX='H';
      STANDARD='';
      LIFECYCLE='';
      JEDEC_TYPE='HOLE_C10D5-6B10_NPB';
      DESCRIPTION='HOLE_C10D5-6B10_NPB';
      COMPONENT_TYPE='';
      LEAD_LENGTH='';
      DFM_EXCLUSION='';
      PARENT_PART_TYPE='HOLE';
      PARENT_PPT='HOLE';
      PARENT_PPT_PART='HOLE_TH-EMPTY,HOLE596';
  end_body;
end_primitive;
primitive 'HOLE_TH-EMPTY,SP_HOLE1199';
  pin
    '1':
      PIN_NUMBER='(1)';
      INPUT_LOAD='(-0.01,0.01)';
      OUTPUT_LOAD='(1.0,-1.0)';
      BIDIRECTIONAL='TRUE';
      PINUSE='BI';
  end_pin;
  body
      CLASS='IO';
      PART_NAME='HOLE';
      PHYS_DES_PREFIX='H';
      STANDARD='';
      LIFECYCLE='';
      JEDEC_TYPE='G_HOLE_C8D3-2B8I5_RO6_NPB';
      DESCRIPTION='G_HOLE_C8D3-2B8I5_RO6_NPB (FOR SEL)';
      COMPONENT_TYPE='';
      LEAD_LENGTH='';
      DFM_EXCLUSION='';
      PARENT_PART_TYPE='HOLE';
      PARENT_PPT='HOLE';
      PARENT_PPT_PART='HOLE_TH-EMPTY,SP_HOLE1199';
  end_body;
end_primitive;
primitive 'HOLE_TH-EMPTY,TMP-C_T2I_ALEX_1A';
  pin
    '1':
      PIN_NUMBER='(1)';
      INPUT_LOAD='(-0.01,0.01)';
      OUTPUT_LOAD='(1.0,-1.0)';
      BIDIRECTIONAL='TRUE';
      PINUSE='BI';
  end_pin;
  body
      CLASS='IO';
      PART_NAME='HOLE';
      PHYS_DES_PREFIX='H';
      STANDARD='';
      LIFECYCLE='';
      JEDEC_TYPE='HOLE_D10N';
      DESCRIPTION='HOLE_D10N';
      COMPONENT_TYPE='';
      LEAD_LENGTH='';
      DFM_EXCLUSION='';
      PARENT_PART_TYPE='HOLE';
      PARENT_PPT='HOLE';
      PARENT_PPT_PART='HOLE_TH-EMPTY,TMP-C_T2I_ALEX_1121_1';
  end_body;
end_primitive;
primitive 'HOLE_TH-EMPTY,TMP-Q_HOLE78';
  pin
    '1':
      PIN_NUMBER='(1)';
      INPUT_LOAD='(-0.01,0.01)';
      OUTPUT_LOAD='(1.0,-1.0)';
      BIDIRECTIONAL='TRUE';
      PINUSE='BI';
  end_pin;
  body
      CLASS='IO';
      PART_NAME='HOLE';
      PHYS_DES_PREFIX='H';
      STANDARD='';
      LIFECYCLE='';
      JEDEC_TYPE='HOLE_D3-1N';
      DESCRIPTION='HOLE_D3-1N';
      COMPONENT_TYPE='';
      LEAD_LENGTH='';
      DFM_EXCLUSION='';
      PARENT_PART_TYPE='HOLE';
      PARENT_PPT='HOLE';
      PARENT_PPT_PART='HOLE_TH-EMPTY,TMP-Q_HOLE78';
  end_body;
end_primitive;
primitive 'INA183A1IDBVR-INA183A1IDBVR,SMA';
  pin
    'GND0':
      PIN_NUMBER='(1)';
      PINUSE='POWER';
      NO_LOAD_CHECK='Both';
      NO_IO_CHECK='Both';
      NO_ASSERT_CHECK='TRUE';
      NO_DIR_CHECK='TRUE';
      ALLOW_CONNECT='TRUE';
    'GND1':
      PIN_NUMBER='(2)';
      PINUSE='POWER';
      NO_LOAD_CHECK='Both';
      NO_IO_CHECK='Both';
      NO_ASSERT_CHECK='TRUE';
      NO_DIR_CHECK='TRUE';
      ALLOW_CONNECT='TRUE';
    'OUT':
      PIN_NUMBER='(3)';
      OUTPUT_LOAD='(1.0,-1.0)';
      PINUSE='OUT';
    'IN-':
      PIN_NUMBER='(4)';
      INPUT_LOAD='(-0.01,0.01)';
      PINUSE='IN';
    'IN+':
      PIN_NUMBER='(5)';
      INPUT_LOAD='(-0.01,0.01)';
      PINUSE='IN';
  end_pin;
  body
      PART_NAME='INA183A1IDBVR';
      BODY_NAME='INA183A1IDBVR';
      PHYS_DES_PREFIX='U';
      CLASS='IC';
      STANDARD='';
      LIFECYCLE='';
      JEDEC_TYPE='SOT23-5_0-95_2-9X1-6XD';
      DESCRIPTION='IC AMPL(5P)INA183A1IDBVR(SOT23)';
      MANUFTR='TIC';
      MANUF_PN='INA183A1IDBVR';
      RD_CMPLS_LVL='EP(V1)';
      CMPLS_LVL='';
      FROM_PJ='S9S-KIMI';
      DIP_SMD='';
      DATA='TIC_INA183A1IDBVR.PDF';
      EE_CHECK_LIST='';
      FP_ECN='';
      PSL='';
      CREATOR='';
      STATUS='';
      MSD='NA';
      ESD_CDM='na';
      ESD_HBM='na';
      ESD_MM='na';
      PIN_LENGTH_SHORT_PIN='0 MILS';
      PIN_LENGTH_LONG_PIN='0 MILS';
      CREATEDAY='20200514';
      PARENT_PART_TYPE='INA183A1IDBVR';
      PARENT_PPT='INA183A1IDBVR';
      PARENT_PPT_PART='INA183A1IDBVR-INA183A1IDBVR,SMLF,EMPTY,AL000183000';
  end_body;
end_primitive;
primitive 'INA230AIRGTR-INA230AIRGTR,SMLFA';
  pin
    'VS':
      PIN_NUMBER='(9)';
      PINUSE='POWER';
      NO_LOAD_CHECK='Both';
      NO_IO_CHECK='Both';
      NO_ASSERT_CHECK='TRUE';
      NO_DIR_CHECK='TRUE';
      ALLOW_CONNECT='TRUE';
    'A1':
      PIN_NUMBER='(1)';
      INPUT_LOAD='(-0.01,0.01)';
      PINUSE='IN';
    'A0':
      PIN_NUMBER='(2)';
      INPUT_LOAD='(-0.01,0.01)';
      PINUSE='IN';
    'SCL':
      PIN_NUMBER='(5)';
      INPUT_LOAD='(-0.01,0.01)';
      PINUSE='IN';
    'SDA':
      PIN_NUMBER='(4)';
      BIDIRECTIONAL='TRUE';
      INPUT_LOAD='(-0.01,0.01)';
      OUTPUT_LOAD='(1.0,-1.0)';
      PINUSE='BI';
    'BUS':
      PIN_NUMBER='(11)';
      INPUT_LOAD='(-0.01,0.01)';
      PINUSE='IN';
    'IN+':
      PIN_NUMBER='(13)';
      INPUT_LOAD='(-0.01,0.01)';
      PINUSE='IN';
    'IN-':
      PIN_NUMBER='(12)';
      INPUT_LOAD='(-0.01,0.01)';
      PINUSE='IN';
    'ALERT':
      PIN_NUMBER='(3)';
      OUTPUT_LOAD='(1.0,-1.0)';
      PINUSE='OUT';
    'NC0':
      PIN_NUMBER='(6)';
      OUTPUT_LOAD='(1.0,-1.0)';
      PINUSE='OUT';
    'NC1':
      PIN_NUMBER='(7)';
      OUTPUT_LOAD='(1.0,-1.0)';
      PINUSE='OUT';
    'NC2':
      PIN_NUMBER='(8)';
      OUTPUT_LOAD='(1.0,-1.0)';
      PINUSE='OUT';
    'NC3':
      PIN_NUMBER='(14)';
      OUTPUT_LOAD='(1.0,-1.0)';
      PINUSE='OUT';
    'NC4':
      PIN_NUMBER='(15)';
      OUTPUT_LOAD='(1.0,-1.0)';
      PINUSE='OUT';
    'NC5':
      PIN_NUMBER='(16)';
      OUTPUT_LOAD='(1.0,-1.0)';
      PINUSE='OUT';
    'GND':
      PIN_NUMBER='(10)';
      PINUSE='POWER';
      NO_LOAD_CHECK='Both';
      NO_IO_CHECK='Both';
      NO_ASSERT_CHECK='TRUE';
      NO_DIR_CHECK='TRUE';
      ALLOW_CONNECT='TRUE';
    'TH':
      PIN_NUMBER='(TH)';
      PINUSE='POWER';
      NO_LOAD_CHECK='Both';
      NO_IO_CHECK='Both';
      NO_ASSERT_CHECK='TRUE';
      NO_DIR_CHECK='TRUE';
      ALLOW_CONNECT='TRUE';
  end_pin;
  body
      PART_NAME='INA230AIRGTR';
      BODY_NAME='INA230AIRGTR';
      PHYS_DES_PREFIX='U';
      CLASS='IC';
      STANDARD='';
      LIFECYCLE='';
      JEDEC_TYPE='QFN16_THXI';
      DESCRIPTION='IC OTHER (16P) INA230AIRGTR (QFN 3X3)';
      MANUFTR='TIC';
      MANUF_PN='INA230AIRGTR';
      RD_CMPLS_LVL='EP(V1)';
      CMPLS_LVL='EP(V1)';
      FROM_PJ='F07-HENRY';
      DIP_SMD='';
      DATA='TIC_INA230_REV2012.pdf';
      EE_CHECK_LIST='';
      FP_ECN='';
      PSL='';
      CREATOR='';
      STATUS='';
      MSD='';
      ESD_CDM='';
      ESD_HBM='';
      ESD_MM='';
      PIN_LENGTH_SHORT_PIN='';
      PIN_LENGTH_LONG_PIN='';
      CREATEDAY='20170914';
      PARENT_PART_TYPE='INA230AIRGTR';
      PARENT_PPT='INA230AIRGTR';
      PARENT_PPT_PART='INA230AIRGTR-INA230AIRGTR,SMLF,EMPTY,AL000230001';
  end_body;
end_primitive;
primitive 'INA230AIRGTR-INA230AIRGTR,SMLFB';
  pin
    'VS':
      PIN_NUMBER='(9)';
      PINUSE='POWER';
      NO_LOAD_CHECK='Both';
      NO_IO_CHECK='Both';
      NO_ASSERT_CHECK='TRUE';
      NO_DIR_CHECK='TRUE';
      ALLOW_CONNECT='TRUE';
    'A1':
      PIN_NUMBER='(1)';
      INPUT_LOAD='(-0.01,0.01)';
      PINUSE='IN';
    'A0':
      PIN_NUMBER='(2)';
      INPUT_LOAD='(-0.01,0.01)';
      PINUSE='IN';
    'SCL':
      PIN_NUMBER='(5)';
      INPUT_LOAD='(-0.01,0.01)';
      PINUSE='IN';
    'SDA':
      PIN_NUMBER='(4)';
      BIDIRECTIONAL='TRUE';
      INPUT_LOAD='(-0.01,0.01)';
      OUTPUT_LOAD='(1.0,-1.0)';
      PINUSE='BI';
    'BUS':
      PIN_NUMBER='(11)';
      INPUT_LOAD='(-0.01,0.01)';
      PINUSE='IN';
    'IN+':
      PIN_NUMBER='(13)';
      INPUT_LOAD='(-0.01,0.01)';
      PINUSE='IN';
    'IN-':
      PIN_NUMBER='(12)';
      INPUT_LOAD='(-0.01,0.01)';
      PINUSE='IN';
    'ALERT':
      PIN_NUMBER='(3)';
      OUTPUT_LOAD='(1.0,-1.0)';
      PINUSE='OUT';
    'NC0':
      PIN_NUMBER='(6)';
      OUTPUT_LOAD='(1.0,-1.0)';
      PINUSE='OUT';
    'NC1':
      PIN_NUMBER='(7)';
      OUTPUT_LOAD='(1.0,-1.0)';
      PINUSE='OUT';
    'NC2':
      PIN_NUMBER='(8)';
      OUTPUT_LOAD='(1.0,-1.0)';
      PINUSE='OUT';
    'NC3':
      PIN_NUMBER='(14)';
      OUTPUT_LOAD='(1.0,-1.0)';
      PINUSE='OUT';
    'NC4':
      PIN_NUMBER='(15)';
      OUTPUT_LOAD='(1.0,-1.0)';
      PINUSE='OUT';
    'NC5':
      PIN_NUMBER='(16)';
      OUTPUT_LOAD='(1.0,-1.0)';
      PINUSE='OUT';
    'GND':
      PIN_NUMBER='(10)';
      PINUSE='POWER';
      NO_LOAD_CHECK='Both';
      NO_IO_CHECK='Both';
      NO_ASSERT_CHECK='TRUE';
      NO_DIR_CHECK='TRUE';
      ALLOW_CONNECT='TRUE';
    'TH':
      PIN_NUMBER='(TH)';
      PINUSE='POWER';
      NO_LOAD_CHECK='Both';
      NO_IO_CHECK='Both';
      NO_ASSERT_CHECK='TRUE';
      NO_DIR_CHECK='TRUE';
      ALLOW_CONNECT='TRUE';
  end_pin;
  body
      PART_NAME='INA230AIRGTR';
      BODY_NAME='INA230AIRGTR';
      PHYS_DES_PREFIX='U';
      CLASS='IC';
      STANDARD='';
      LIFECYCLE='';
      JEDEC_TYPE='QFN16_THXI';
      DESCRIPTION='IC OTHER (16P) INA230AIRGTR (QFN 3X3)';
      MANUFTR='TIC';
      MANUF_PN='INA230AIRGTR';
      RD_CMPLS_LVL='EP(V1)';
      CMPLS_LVL='EP(V1)';
      FROM_PJ='F07-HENRY';
      DIP_SMD='';
      DATA='TIC_INA230_REV2012.pdf';
      EE_CHECK_LIST='';
      FP_ECN='';
      PSL='';
      CREATOR='';
      STATUS='';
      MSD='';
      ESD_CDM='';
      ESD_HBM='';
      ESD_MM='';
      PIN_LENGTH_SHORT_PIN='';
      PIN_LENGTH_LONG_PIN='';
      CREATEDAY='20170914';
      PARENT_PART_TYPE='INA230AIRGTR';
      PARENT_PPT='INA230AIRGTR';
      PARENT_PPT_PART='INA230AIRGTR-INA230AIRGTR,SMLF,IC,AL000230001';
  end_body;
end_primitive;
primitive 'IR3889MTRPBF-IR3889MTRPBF,SMLFA';
  pin
    'NC3':
      PIN_NUMBER='(34)';
      OUTPUT_TYPE='(TS,TS)';
      INPUT_LOAD='(-0.01,0.01)';
      OUTPUT_LOAD='(1.0,-1.0)';
      PINUSE='TRI';
    'TON||MODE':
      PIN_NUMBER='(36)';
      INPUT_LOAD='(-0.01,0.01)';
      PINUSE='IN';
    'VIN':
      PIN_NUMBER='(3)';
      PINUSE='POWER';
      NO_LOAD_CHECK='Both';
      NO_IO_CHECK='Both';
      NO_ASSERT_CHECK='TRUE';
      NO_DIR_CHECK='TRUE';
      ALLOW_CONNECT='TRUE';
    'FB':
      PIN_NUMBER='(30)';
      INPUT_LOAD='(-0.01,0.01)';
      PINUSE='IN';
    'BOOT':
      PIN_NUMBER='(26)';
      INPUT_LOAD='(-0.01,0.01)';
      PINUSE='IN';
    'ILIM':
      PIN_NUMBER='(1)';
      INPUT_LOAD='(-0.01,0.01)';
      PINUSE='IN';
    'PHASE':
      PIN_NUMBER='(25)';
      OUTPUT_LOAD='(1.0,-1.0)';
      PINUSE='OUT';
    'VCC||LDO':
      PIN_NUMBER='(4)';
      PINUSE='POWER';
      NO_LOAD_CHECK='Both';
      NO_IO_CHECK='Both';
      NO_ASSERT_CHECK='TRUE';
      NO_DIR_CHECK='TRUE';
      ALLOW_CONNECT='TRUE';
    'VSENM':
      PIN_NUMBER='(31)';
      INPUT_LOAD='(-0.01,0.01)';
      PINUSE='IN';
    'NC4':
      PIN_NUMBER='(35)';
      OUTPUT_TYPE='(TS,TS)';
      INPUT_LOAD='(-0.01,0.01)';
      OUTPUT_LOAD='(1.0,-1.0)';
      PINUSE='TRI';
    'PGND':
      PIN_NUMBER='(7_10-19)';
      PINUSE='POWER';
      NO_LOAD_CHECK='Both';
      NO_IO_CHECK='Both';
      NO_ASSERT_CHECK='TRUE';
      NO_DIR_CHECK='TRUE';
      ALLOW_CONNECT='TRUE';
    'NC2':
      PIN_NUMBER='(33)';
      OUTPUT_TYPE='(TS,TS)';
      INPUT_LOAD='(-0.01,0.01)';
      OUTPUT_LOAD='(1.0,-1.0)';
      PINUSE='TRI';
    'SW':
      PIN_NUMBER='(11_18)';
      PINUSE='POWER';
      NO_LOAD_CHECK='Both';
      NO_IO_CHECK='Both';
      NO_ASSERT_CHECK='TRUE';
      NO_DIR_CHECK='TRUE';
      ALLOW_CONNECT='TRUE';
    'PVIN':
      PIN_NUMBER='(20_24)';
      PINUSE='POWER';
      NO_LOAD_CHECK='Both';
      NO_IO_CHECK='Both';
      NO_ASSERT_CHECK='TRUE';
      NO_DIR_CHECK='TRUE';
      ALLOW_CONNECT='TRUE';
    'PGOOD':
      PIN_NUMBER='(2)';
      OUTPUT_LOAD='(1.0,-1.0)';
      PINUSE='OUT';
    'NC1':
      PIN_NUMBER='(28)';
      OUTPUT_TYPE='(TS,TS)';
      INPUT_LOAD='(-0.01,0.01)';
      OUTPUT_LOAD='(1.0,-1.0)';
      PINUSE='TRI';
    'AGND':
      PIN_NUMBER='(32)';
      PINUSE='POWER';
      NO_LOAD_CHECK='Both';
      NO_IO_CHECK='Both';
      NO_ASSERT_CHECK='TRUE';
      NO_DIR_CHECK='TRUE';
      ALLOW_CONNECT='TRUE';
    'EN':
      PIN_NUMBER='(27)';
      INPUT_LOAD='(-0.01,0.01)';
      PINUSE='IN';
    'VDRV':
      PIN_NUMBER='(5)';
      PINUSE='POWER';
      NO_LOAD_CHECK='Both';
      NO_IO_CHECK='Both';
      NO_ASSERT_CHECK='TRUE';
      NO_DIR_CHECK='TRUE';
      ALLOW_CONNECT='TRUE';
    'GATEL1':
      PIN_NUMBER='(6)';
      INPUT_LOAD='(-0.01,0.01)';
      PINUSE='IN';
    'SS||LATCH':
      PIN_NUMBER='(29)';
      INPUT_LOAD='(-0.01,0.01)';
      PINUSE='IN';
    'GATEL2':
      PIN_NUMBER='(37)';
      INPUT_LOAD='(-0.01,0.01)';
      PINUSE='IN';
  end_pin;
  body
      PART_NAME='IR3889MTRPBF';
      BODY_NAME='IR3889MTRPBF';
      PHYS_DES_PREFIX='U';
      CLASS='IC';
      STANDARD='';
      LIFECYCLE='';
      JEDEC_TYPE='QFN22_6X5';
      DESCRIPTION='IC OTHER(37P) IR3889MTRPBF(QFN)';
      MANUFTR='SNI';
      MANUF_PN='IR3889MTRPBF';
      RD_CMPLS_LVL='EP(V1)';
      CMPLS_LVL='';
      FROM_PJ='S6X-KIMI';
      DIP_SMD='';
      DATA='SNI_IR3889MTRPBF.pdf';
      EE_CHECK_LIST='';
      FP_ECN='IR3889MTRPBF.msg';
      PSL='';
      CREATOR='';
      STATUS='';
      MSD='NA';
      ESD_CDM='NA';
      ESD_HBM='NA';
      ESD_MM='NA';
      PIN_LENGTH_SHORT_PIN='0 MILS';
      PIN_LENGTH_LONG_PIN='0 MILS';
      CREATEDAY='20200519';
      PARENT_PART_TYPE='IR3889MTRPBF';
      PARENT_PPT='IR3889MTRPBF';
      PARENT_PPT_PART='IR3889MTRPBF-IR3889MTRPBF,SMLF,IC,AL003889000';
  end_body;
end_primitive;
primitive 'ISL69260IRAZT-ISL69260IRAZ-T,SA';
  pin
    'CS7':
      PIN_NUMBER='(23)';
      INPUT_LOAD='(-0.01,0.01)';
      PINUSE='IN';
    'VCC':
      PIN_NUMBER='(39)';
      PINUSE='POWER';
      NO_LOAD_CHECK='Both';
      NO_IO_CHECK='Both';
      NO_ASSERT_CHECK='TRUE';
      NO_DIR_CHECK='TRUE';
      ALLOW_CONNECT='TRUE';
    'EN1':
      PIN_NUMBER='(20)';
      INPUT_LOAD='(-0.01,0.01)';
      PINUSE='IN';
    'PMSCL':
      PIN_NUMBER='(10)';
      INPUT_LOAD='(-0.01,0.01)';
      PINUSE='IN';
    'SVDATA':
      PIN_NUMBER='(18)';
      BIDIRECTIONAL='TRUE';
      INPUT_LOAD='(-0.01,0.01)';
      OUTPUT_LOAD='(1.0,-1.0)';
      PINUSE='BI';
    'CS6':
      PIN_NUMBER='(24)';
      INPUT_LOAD='(-0.01,0.01)';
      PINUSE='IN';
    'NSVALERT#':
      PIN_NUMBER='(19)';
      OUTPUT_LOAD='(1.0,-1.0)';
      PINUSE='OUT';
    'NVRHOT#':
      PIN_NUMBER='(14)';
      OUTPUT_LOAD='(1.0,-1.0)';
      PINUSE='OUT';
    'CS5':
      PIN_NUMBER='(25)';
      INPUT_LOAD='(-0.01,0.01)';
      PINUSE='IN';
    'CS4':
      PIN_NUMBER='(26)';
      INPUT_LOAD='(-0.01,0.01)';
      PINUSE='IN';
    'PG1':
      PIN_NUMBER='(16)';
      OUTPUT_LOAD='(1.0,-1.0)';
      PINUSE='OUT';
    'SVCLK':
      PIN_NUMBER='(17)';
      INPUT_LOAD='(-0.01,0.01)';
      PINUSE='IN';
    'NPMALERT#':
      PIN_NUMBER='(11)';
      OUTPUT_LOAD='(1.0,-1.0)';
      PINUSE='OUT';
    'EN0':
      PIN_NUMBER='(13)';
      INPUT_LOAD='(-0.01,0.01)';
      PINUSE='IN';
    'RGND0':
      PIN_NUMBER='(22)';
      INPUT_LOAD='(-0.01,0.01)';
      PINUSE='IN';
    'PMSDA':
      PIN_NUMBER='(9)';
      BIDIRECTIONAL='TRUE';
      INPUT_LOAD='(-0.01,0.01)';
      OUTPUT_LOAD='(1.0,-1.0)';
      PINUSE='BI';
    'PWM4':
      PIN_NUMBER='(5)';
      OUTPUT_LOAD='(1.0,-1.0)';
      PINUSE='OUT';
    'PWM5':
      PIN_NUMBER='(6)';
      OUTPUT_LOAD='(1.0,-1.0)';
      PINUSE='OUT';
    'VSEN0':
      PIN_NUMBER='(21)';
      INPUT_LOAD='(-0.01,0.01)';
      PINUSE='IN';
    'PWM1':
      PIN_NUMBER='(2)';
      OUTPUT_LOAD='(1.0,-1.0)';
      PINUSE='OUT';
    'PG0':
      PIN_NUMBER='(12)';
      OUTPUT_LOAD='(1.0,-1.0)';
      PINUSE='OUT';
    'PWM6':
      PIN_NUMBER='(7)';
      OUTPUT_LOAD='(1.0,-1.0)';
      PINUSE='OUT';
    'VCCS':
      PIN_NUMBER='(40)';
      PINUSE='POWER';
      NO_LOAD_CHECK='Both';
      NO_IO_CHECK='Both';
      NO_ASSERT_CHECK='TRUE';
      NO_DIR_CHECK='TRUE';
      ALLOW_CONNECT='TRUE';
    'VMON||IINSEN||VSYS||ISYS':
      PIN_NUMBER='(37)';
      INPUT_LOAD='(-0.01,0.01)';
      PINUSE='IN';
    'VINSEN||VSYS':
      PIN_NUMBER='(38)';
      INPUT_LOAD='(-0.01,0.01)';
      PINUSE='IN';
    'TEMP1||ISYS':
      PIN_NUMBER='(36)';
      INPUT_LOAD='(-0.01,0.01)';
      PINUSE='IN';
    'NPINALERT#||NPSYSCRIT#':
      PIN_NUMBER='(15)';
      OUTPUT_LOAD='(1.0,-1.0)';
      PINUSE='OUT';
    'VSEN1':
      PIN_NUMBER='(32)';
      INPUT_LOAD='(-0.01,0.01)';
      PINUSE='IN';
    'RGND1':
      PIN_NUMBER='(31)';
      INPUT_LOAD='(-0.01,0.01)';
      PINUSE='IN';
    'CS1':
      PIN_NUMBER='(29)';
      INPUT_LOAD='(-0.01,0.01)';
      PINUSE='IN';
    'PWM7':
      PIN_NUMBER='(8)';
      OUTPUT_LOAD='(1.0,-1.0)';
      PINUSE='OUT';
    'PWM3':
      PIN_NUMBER='(4)';
      OUTPUT_LOAD='(1.0,-1.0)';
      PINUSE='OUT';
    'CS3':
      PIN_NUMBER='(27)';
      INPUT_LOAD='(-0.01,0.01)';
      PINUSE='IN';
    'PWM2':
      PIN_NUMBER='(3)';
      OUTPUT_LOAD='(1.0,-1.0)';
      PINUSE='OUT';
    'CS2':
      PIN_NUMBER='(28)';
      INPUT_LOAD='(-0.01,0.01)';
      PINUSE='IN';
    'CFP':
      PIN_NUMBER='(33)';
      OUTPUT_LOAD='(1.0,-1.0)';
      PINUSE='OUT';
    'TH_GND':
      PIN_NUMBER='(TH)';
      PINUSE='POWER';
      NO_LOAD_CHECK='Both';
      NO_IO_CHECK='Both';
      NO_ASSERT_CHECK='TRUE';
      NO_DIR_CHECK='TRUE';
      ALLOW_CONNECT='TRUE';
    'ADDR_CFG':
      PIN_NUMBER='(34)';
      INPUT_LOAD='(-0.01,0.01)';
      PINUSE='IN';
    'TEMP0':
      PIN_NUMBER='(35)';
      INPUT_LOAD='(-0.01,0.01)';
      PINUSE='IN';
    'PWM0':
      PIN_NUMBER='(1)';
      OUTPUT_LOAD='(1.0,-1.0)';
      PINUSE='OUT';
    'CS0':
      PIN_NUMBER='(30)';
      INPUT_LOAD='(-0.01,0.01)';
      PINUSE='IN';
  end_pin;
  body
      PART_NAME='ISL69260IRAZT';
      BODY_NAME='ISL69260IRAZT';
      PHYS_DES_PREFIX='U';
      CLASS='IC';
      STANDARD='';
      LIFECYCLE='';
      JEDEC_TYPE='QFN40_TH_0-4_5X5XE';
      DESCRIPTION='IC CTRL(40P)ISL69260IRAZ-T(QFN)';
      MANUFTR='RTT';
      MANUF_PN='ISL69260IRAZ-T';
      RD_CMPLS_LVL='EP(V1)';
      CMPLS_LVL='';
      FROM_PJ='S9S-KIMI';
      DIP_SMD='';
      DATA='RTT_ISL69260IRAZ-T.pdf';
      EE_CHECK_LIST='';
      FP_ECN='ISL69260IRAZ-T.msg';
      PSL='';
      CREATOR='';
      STATUS='';
      MSD='NA';
      ESD_CDM='na';
      ESD_HBM='na';
      ESD_MM='na';
      PIN_LENGTH_SHORT_PIN='0 MILS';
      PIN_LENGTH_LONG_PIN='0 MILS';
      CREATEDAY='20200310';
      PARENT_PART_TYPE='ISL69260IRAZT';
      PARENT_PPT='ISL69260IRAZT';
      PARENT_PPT_PART='ISL69260IRAZT-ISL69260IRAZ-T,SMLF,IC,AL069260000';
  end_body;
end_primitive;
primitive 'ISL99390FRZTR5935-ISL99390FRZ-A';
  pin
    'PWM':
      PIN_NUMBER='(34)';
      INPUT_LOAD='(-0.01,0.01)';
      PINUSE='IN';
    'REFIN':
      PIN_NUMBER='(39)';
      INPUT_LOAD='(-0.01,0.01)';
      PINUSE='IN';
    'VCC':
      PIN_NUMBER='(3)';
      PINUSE='POWER';
      NO_LOAD_CHECK='Both';
      NO_IO_CHECK='Both';
      NO_ASSERT_CHECK='TRUE';
      NO_DIR_CHECK='TRUE';
      ALLOW_CONNECT='TRUE';
    'AGND':
      PIN_NUMBER='(2)';
      PINUSE='POWER';
      NO_LOAD_CHECK='Both';
      NO_IO_CHECK='Both';
      NO_ASSERT_CHECK='TRUE';
      NO_DIR_CHECK='TRUE';
      ALLOW_CONNECT='TRUE';
    'BOOT':
      PIN_NUMBER='(33)';
      PINUSE='POWER';
      NO_LOAD_CHECK='Both';
      NO_IO_CHECK='Both';
      NO_ASSERT_CHECK='TRUE';
      NO_DIR_CHECK='TRUE';
      ALLOW_CONNECT='TRUE';
    'VIN1':
      PIN_NUMBER='(25_29)';
      INPUT_LOAD='(-0.01,0.01)';
      PINUSE='IN';
    'PHASE':
      PIN_NUMBER='(32)';
      PINUSE='POWER';
      NO_LOAD_CHECK='Both';
      NO_IO_CHECK='Both';
      NO_ASSERT_CHECK='TRUE';
      NO_DIR_CHECK='TRUE';
      ALLOW_CONNECT='TRUE';
    'PVCC':
      PIN_NUMBER='(4)';
      PINUSE='POWER';
      NO_LOAD_CHECK='Both';
      NO_IO_CHECK='Both';
      NO_ASSERT_CHECK='TRUE';
      NO_DIR_CHECK='TRUE';
      ALLOW_CONNECT='TRUE';
    'TOUT_FLT':
      PIN_NUMBER='(36)';
      OUTPUT_LOAD='(1.0,-1.0)';
      PINUSE='OUT';
    'IOUT':
      PIN_NUMBER='(38)';
      OUTPUT_LOAD='(1.0,-1.0)';
      PINUSE='OUT';
    'LSET':
      PIN_NUMBER='(37)';
      OUTPUT_LOAD='(1.0,-1.0)';
      PINUSE='OUT';
    'SW':
      PIN_NUMBER='(10_19)';
      OUTPUT_LOAD='(1.0,-1.0)';
      PINUSE='OUT';
    'PGND1':
      PIN_NUMBER='(5)';
      PINUSE='POWER';
      NO_LOAD_CHECK='Both';
      NO_IO_CHECK='Both';
      NO_ASSERT_CHECK='TRUE';
      NO_DIR_CHECK='TRUE';
      ALLOW_CONNECT='TRUE';
    'VIN2':
      PIN_NUMBER='(30)';
      INPUT_LOAD='(-0.01,0.01)';
      PINUSE='IN';
    'VOS':
      PIN_NUMBER='(1)';
      INPUT_LOAD='(-0.01,0.01)';
      PINUSE='IN';
    'PGND3':
      PIN_NUMBER='(40)';
      PINUSE='POWER';
      NO_LOAD_CHECK='Both';
      NO_IO_CHECK='Both';
      NO_ASSERT_CHECK='TRUE';
      NO_DIR_CHECK='TRUE';
      ALLOW_CONNECT='TRUE';
    'EN':
      PIN_NUMBER='(35)';
      INPUT_LOAD='(-0.01,0.01)';
      PINUSE='IN';
    'DNC':
      PIN_NUMBER='(31)';
      OUTPUT_TYPE='(TS,TS)';
      INPUT_LOAD='(-0.01,0.01)';
      OUTPUT_LOAD='(1.0,-1.0)';
      PINUSE='TRI';
    'GL1':
      PIN_NUMBER='(6)';
      OUTPUT_LOAD='(1.0,-1.0)';
      PINUSE='OUT';
    'GL2':
      PIN_NUMBER='(41)';
      OUTPUT_LOAD='(1.0,-1.0)';
      PINUSE='OUT';
    'PGND2':
      PIN_NUMBER='(7_9-20_24)';
      PINUSE='POWER';
      NO_LOAD_CHECK='Both';
      NO_IO_CHECK='Both';
      NO_ASSERT_CHECK='TRUE';
      NO_DIR_CHECK='TRUE';
      ALLOW_CONNECT='TRUE';
  end_pin;
  body
      PART_NAME='ISL99390FRZTR5935';
      BODY_NAME='ISL99390FRZTR5935';
      PHYS_DES_PREFIX='U';
      CLASS='IC';
      STANDARD='';
      LIFECYCLE='';
      JEDEC_TYPE='QFN21_6X5XB';
      DESCRIPTION='IC CTRL(41P) ISL99390FRZ-TR5935(QFN)';
      MANUFTR='RTT';
      MANUF_PN='ISL99390FRZ-TR5935';
      RD_CMPLS_LVL='EP(V1)';
      CMPLS_LVL='';
      FROM_PJ='S8A-KENNY';
      DIP_SMD='';
      DATA='RTT_ISL99390FRZ-TR5935.pdf';
      EE_CHECK_LIST='';
      FP_ECN='';
      PSL='';
      CREATOR='';
      STATUS='';
      MSD='NA';
      ESD_CDM='NA';
      ESD_HBM='NA';
      ESD_MM='NA';
      PIN_LENGTH_SHORT_PIN='0 MILS';
      PIN_LENGTH_LONG_PIN='0 MILS';
      CREATEDAY='20200303';
      PARENT_PART_TYPE='ISL99390FRZTR5935';
      PARENT_PPT='ISL99390FRZTR5935';
      PARENT_PPT_PART='ISL99390FRZTR5935-ISL99390FRZ-TR5935,SMLF,IC,AL099390004';
  end_body;
end_primitive;
primitive 'LCMXO3LF9400C5BG484C-LCMXO3LF-A';
  pin
    'PL2A':
      PIN_NUMBER='(D3,0,0,0,0,0,0)';
      BIDIRECTIONAL='TRUE';
      INPUT_LOAD='(-0.01,0.01)';
      OUTPUT_LOAD='(1.0,-1.0)';
      PINUSE='BI';
    'PL2B':
      PIN_NUMBER='(D4,0,0,0,0,0,0)';
      BIDIRECTIONAL='TRUE';
      INPUT_LOAD='(-0.01,0.01)';
      OUTPUT_LOAD='(1.0,-1.0)';
      PINUSE='BI';
    'PL2C':
      PIN_NUMBER='(F6,0,0,0,0,0,0)';
      BIDIRECTIONAL='TRUE';
      INPUT_LOAD='(-0.01,0.01)';
      OUTPUT_LOAD='(1.0,-1.0)';
      PINUSE='BI';
    'PL2D':
      PIN_NUMBER='(G7,0,0,0,0,0,0)';
      BIDIRECTIONAL='TRUE';
      INPUT_LOAD='(-0.01,0.01)';
      OUTPUT_LOAD='(1.0,-1.0)';
      PINUSE='BI';
    'PL3A||L_GPLLT_FB':
      PIN_NUMBER='(E4,0,0,0,0,0,0)';
      BIDIRECTIONAL='TRUE';
      INPUT_LOAD='(-0.01,0.01)';
      OUTPUT_LOAD='(1.0,-1.0)';
      PINUSE='BI';
    'PL3B||L_GPLLC_FB':
      PIN_NUMBER='(F5,0,0,0,0,0,0)';
      BIDIRECTIONAL='TRUE';
      INPUT_LOAD='(-0.01,0.01)';
      OUTPUT_LOAD='(1.0,-1.0)';
      PINUSE='BI';
    'PL3C':
      PIN_NUMBER='(G6,0,0,0,0,0,0)';
      BIDIRECTIONAL='TRUE';
      INPUT_LOAD='(-0.01,0.01)';
      OUTPUT_LOAD='(1.0,-1.0)';
      PINUSE='BI';
    'PL3D':
      PIN_NUMBER='(H7,0,0,0,0,0,0)';
      BIDIRECTIONAL='TRUE';
      INPUT_LOAD='(-0.01,0.01)';
      OUTPUT_LOAD='(1.0,-1.0)';
      PINUSE='BI';
    'PL4A||L_GPLLT_IN':
      PIN_NUMBER='(C1,0,0,0,0,0,0)';
      BIDIRECTIONAL='TRUE';
      INPUT_LOAD='(-0.01,0.01)';
      OUTPUT_LOAD='(1.0,-1.0)';
      PINUSE='BI';
    'PL4B||L_GPLLC_IN':
      PIN_NUMBER='(D2,0,0,0,0,0,0)';
      BIDIRECTIONAL='TRUE';
      INPUT_LOAD='(-0.01,0.01)';
      OUTPUT_LOAD='(1.0,-1.0)';
      PINUSE='BI';
    'PL4C':
      PIN_NUMBER='(G5,0,0,0,0,0,0)';
      BIDIRECTIONAL='TRUE';
      INPUT_LOAD='(-0.01,0.01)';
      OUTPUT_LOAD='(1.0,-1.0)';
      PINUSE='BI';
    'PL4D':
      PIN_NUMBER='(H6,0,0,0,0,0,0)';
      BIDIRECTIONAL='TRUE';
      INPUT_LOAD='(-0.01,0.01)';
      OUTPUT_LOAD='(1.0,-1.0)';
      PINUSE='BI';
    'PL5A':
      PIN_NUMBER='(D1,0,0,0,0,0,0)';
      BIDIRECTIONAL='TRUE';
      INPUT_LOAD='(-0.01,0.01)';
      OUTPUT_LOAD='(1.0,-1.0)';
      PINUSE='BI';
    'PL5B':
      PIN_NUMBER='(E2,0,0,0,0,0,0)';
      BIDIRECTIONAL='TRUE';
      INPUT_LOAD='(-0.01,0.01)';
      OUTPUT_LOAD='(1.0,-1.0)';
      PINUSE='BI';
    'PL5C':
      PIN_NUMBER='(E3,0,0,0,0,0,0)';
      BIDIRECTIONAL='TRUE';
      INPUT_LOAD='(-0.01,0.01)';
      OUTPUT_LOAD='(1.0,-1.0)';
      PINUSE='BI';
    'PL5D':
      PIN_NUMBER='(F4,0,0,0,0,0,0)';
      BIDIRECTIONAL='TRUE';
      INPUT_LOAD='(-0.01,0.01)';
      OUTPUT_LOAD='(1.0,-1.0)';
      PINUSE='BI';
    'PL13A':
      PIN_NUMBER='(L7,0,0,0,0,0,0)';
      BIDIRECTIONAL='TRUE';
      INPUT_LOAD='(-0.01,0.01)';
      OUTPUT_LOAD='(1.0,-1.0)';
      PINUSE='BI';
    'PL13B':
      PIN_NUMBER='(K5,0,0,0,0,0,0)';
      BIDIRECTIONAL='TRUE';
      INPUT_LOAD='(-0.01,0.01)';
      OUTPUT_LOAD='(1.0,-1.0)';
      PINUSE='BI';
    'PL13C':
      PIN_NUMBER='(K4,0,0,0,0,0,0)';
      BIDIRECTIONAL='TRUE';
      INPUT_LOAD='(-0.01,0.01)';
      OUTPUT_LOAD='(1.0,-1.0)';
      PINUSE='BI';
    'PL13D':
      PIN_NUMBER='(K3,0,0,0,0,0,0)';
      BIDIRECTIONAL='TRUE';
      INPUT_LOAD='(-0.01,0.01)';
      OUTPUT_LOAD='(1.0,-1.0)';
      PINUSE='BI';
    'PL14A':
      PIN_NUMBER='(K2,0,0,0,0,0,0)';
      BIDIRECTIONAL='TRUE';
      INPUT_LOAD='(-0.01,0.01)';
      OUTPUT_LOAD='(1.0,-1.0)';
      PINUSE='BI';
    'PL14B':
      PIN_NUMBER='(K1,0,0,0,0,0,0)';
      BIDIRECTIONAL='TRUE';
      INPUT_LOAD='(-0.01,0.01)';
      OUTPUT_LOAD='(1.0,-1.0)';
      PINUSE='BI';
    'PL16A||PCLKT4_0':
      PIN_NUMBER='(L1,0,0,0,0,0,0)';
      BIDIRECTIONAL='TRUE';
      INPUT_LOAD='(-0.01,0.01)';
      OUTPUT_LOAD='(1.0,-1.0)';
      PINUSE='BI';
    'PL16B||PCLKC4_0':
      PIN_NUMBER='(M2,0,0,0,0,0,0)';
      BIDIRECTIONAL='TRUE';
      INPUT_LOAD='(-0.01,0.01)';
      OUTPUT_LOAD='(1.0,-1.0)';
      PINUSE='BI';
    'PL20A':
      PIN_NUMBER='(P4,0,0,0,0,0,0)';
      BIDIRECTIONAL='TRUE';
      INPUT_LOAD='(-0.01,0.01)';
      OUTPUT_LOAD='(1.0,-1.0)';
      PINUSE='BI';
    'PL20B':
      PIN_NUMBER='(N5,0,0,0,0,0,0)';
      BIDIRECTIONAL='TRUE';
      INPUT_LOAD='(-0.01,0.01)';
      OUTPUT_LOAD='(1.0,-1.0)';
      PINUSE='BI';
    'PL20C':
      PIN_NUMBER='(N6,0,0,0,0,0,0)';
      BIDIRECTIONAL='TRUE';
      INPUT_LOAD='(-0.01,0.01)';
      OUTPUT_LOAD='(1.0,-1.0)';
      PINUSE='BI';
    'PL20D':
      PIN_NUMBER='(N7,0,0,0,0,0,0)';
      BIDIRECTIONAL='TRUE';
      INPUT_LOAD='(-0.01,0.01)';
      OUTPUT_LOAD='(1.0,-1.0)';
      PINUSE='BI';
    'PL21A':
      PIN_NUMBER='(R2,0,0,0,0,0,0)';
      BIDIRECTIONAL='TRUE';
      INPUT_LOAD='(-0.01,0.01)';
      OUTPUT_LOAD='(1.0,-1.0)';
      PINUSE='BI';
    'PL21B':
      PIN_NUMBER='(T1,0,0,0,0,0,0)';
      BIDIRECTIONAL='TRUE';
      INPUT_LOAD='(-0.01,0.01)';
      OUTPUT_LOAD='(1.0,-1.0)';
      PINUSE='BI';
    'PL21C':
      PIN_NUMBER='(P5,0,0,0,0,0,0)';
      BIDIRECTIONAL='TRUE';
      INPUT_LOAD='(-0.01,0.01)';
      OUTPUT_LOAD='(1.0,-1.0)';
      PINUSE='BI';
    'PL21D':
      PIN_NUMBER='(P6,0,0,0,0,0,0)';
      BIDIRECTIONAL='TRUE';
      INPUT_LOAD='(-0.01,0.01)';
      OUTPUT_LOAD='(1.0,-1.0)';
      PINUSE='BI';
    'PL26C':
      PIN_NUMBER='(T5,0,0,0,0,0,0)';
      BIDIRECTIONAL='TRUE';
      INPUT_LOAD='(-0.01,0.01)';
      OUTPUT_LOAD='(1.0,-1.0)';
      PINUSE='BI';
    'PL26D':
      PIN_NUMBER='(T6,0,0,0,0,0,0)';
      BIDIRECTIONAL='TRUE';
      INPUT_LOAD='(-0.01,0.01)';
      OUTPUT_LOAD='(1.0,-1.0)';
      PINUSE='BI';
    'PL14C':
      PIN_NUMBER='(L6,0,0,0,0,0,0)';
      BIDIRECTIONAL='TRUE';
      INPUT_LOAD='(-0.01,0.01)';
      OUTPUT_LOAD='(1.0,-1.0)';
      PINUSE='BI';
    'PL14D':
      PIN_NUMBER='(L5,0,0,0,0,0,0)';
      BIDIRECTIONAL='TRUE';
      INPUT_LOAD='(-0.01,0.01)';
      OUTPUT_LOAD='(1.0,-1.0)';
      PINUSE='BI';
    'PL16C':
      PIN_NUMBER='(L3,0,0,0,0,0,0)';
      BIDIRECTIONAL='TRUE';
      INPUT_LOAD='(-0.01,0.01)';
      OUTPUT_LOAD='(1.0,-1.0)';
      PINUSE='BI';
    'PL16D':
      PIN_NUMBER='(L4,0,0,0,0,0,0)';
      BIDIRECTIONAL='TRUE';
      INPUT_LOAD='(-0.01,0.01)';
      OUTPUT_LOAD='(1.0,-1.0)';
      PINUSE='BI';
    'PL6C':
      PIN_NUMBER='(G3,0,0,0,0,0,0)';
      BIDIRECTIONAL='TRUE';
      INPUT_LOAD='(-0.01,0.01)';
      OUTPUT_LOAD='(1.0,-1.0)';
      PINUSE='BI';
    'PL6D':
      PIN_NUMBER='(G4,0,0,0,0,0,0)';
      BIDIRECTIONAL='TRUE';
      INPUT_LOAD='(-0.01,0.01)';
      OUTPUT_LOAD='(1.0,-1.0)';
      PINUSE='BI';
    'PL6A':
      PIN_NUMBER='(E1,0,0,0,0,0,0)';
      BIDIRECTIONAL='TRUE';
      INPUT_LOAD='(-0.01,0.01)';
      OUTPUT_LOAD='(1.0,-1.0)';
      PINUSE='BI';
    'PL6B':
      PIN_NUMBER='(F1,0,0,0,0,0,0)';
      BIDIRECTIONAL='TRUE';
      INPUT_LOAD='(-0.01,0.01)';
      OUTPUT_LOAD='(1.0,-1.0)';
      PINUSE='BI';
    'PL25A':
      PIN_NUMBER='(T2,0,0,0,0,0,0)';
      BIDIRECTIONAL='TRUE';
      INPUT_LOAD='(-0.01,0.01)';
      OUTPUT_LOAD='(1.0,-1.0)';
      PINUSE='BI';
    'PL25B':
      PIN_NUMBER='(U1,0,0,0,0,0,0)';
      BIDIRECTIONAL='TRUE';
      INPUT_LOAD='(-0.01,0.01)';
      OUTPUT_LOAD='(1.0,-1.0)';
      PINUSE='BI';
    'PL24A':
      PIN_NUMBER='(R3,0,0,0,0,0,0)';
      BIDIRECTIONAL='TRUE';
      INPUT_LOAD='(-0.01,0.01)';
      OUTPUT_LOAD='(1.0,-1.0)';
      PINUSE='BI';
    'PL24B':
      PIN_NUMBER='(R4,0,0,0,0,0,0)';
      BIDIRECTIONAL='TRUE';
      INPUT_LOAD='(-0.01,0.01)';
      OUTPUT_LOAD='(1.0,-1.0)';
      PINUSE='BI';
    'PL24C':
      PIN_NUMBER='(R5,0,0,0,0,0,0)';
      BIDIRECTIONAL='TRUE';
      INPUT_LOAD='(-0.01,0.01)';
      OUTPUT_LOAD='(1.0,-1.0)';
      PINUSE='BI';
    'PL24D':
      PIN_NUMBER='(P7,0,0,0,0,0,0)';
      BIDIRECTIONAL='TRUE';
      INPUT_LOAD='(-0.01,0.01)';
      OUTPUT_LOAD='(1.0,-1.0)';
      PINUSE='BI';
    'PL25C':
      PIN_NUMBER='(R6,0,0,0,0,0,0)';
      BIDIRECTIONAL='TRUE';
      INPUT_LOAD='(-0.01,0.01)';
      OUTPUT_LOAD='(1.0,-1.0)';
      PINUSE='BI';
    'PL25D':
      PIN_NUMBER='(R7,0,0,0,0,0,0)';
      BIDIRECTIONAL='TRUE';
      INPUT_LOAD='(-0.01,0.01)';
      OUTPUT_LOAD='(1.0,-1.0)';
      PINUSE='BI';
    'PL26A':
      PIN_NUMBER='(T3,0,0,0,0,0,0)';
      BIDIRECTIONAL='TRUE';
      INPUT_LOAD='(-0.01,0.01)';
      OUTPUT_LOAD='(1.0,-1.0)';
      PINUSE='BI';
    'PL26B':
      PIN_NUMBER='(T4,0,0,0,0,0,0)';
      BIDIRECTIONAL='TRUE';
      INPUT_LOAD='(-0.01,0.01)';
      OUTPUT_LOAD='(1.0,-1.0)';
      PINUSE='BI';
    'PL17A':
      PIN_NUMBER='(M1,0,0,0,0,0,0)';
      BIDIRECTIONAL='TRUE';
      INPUT_LOAD='(-0.01,0.01)';
      OUTPUT_LOAD='(1.0,-1.0)';
      PINUSE='BI';
    'PL17B':
      PIN_NUMBER='(N1,0,0,0,0,0,0)';
      BIDIRECTIONAL='TRUE';
      INPUT_LOAD='(-0.01,0.01)';
      OUTPUT_LOAD='(1.0,-1.0)';
      PINUSE='BI';
    'PL17C':
      PIN_NUMBER='(M6,0,0,0,0,0,0)';
      BIDIRECTIONAL='TRUE';
      INPUT_LOAD='(-0.01,0.01)';
      OUTPUT_LOAD='(1.0,-1.0)';
      PINUSE='BI';
    'PL17D':
      PIN_NUMBER='(M5,0,0,0,0,0,0)';
      BIDIRECTIONAL='TRUE';
      INPUT_LOAD='(-0.01,0.01)';
      OUTPUT_LOAD='(1.0,-1.0)';
      PINUSE='BI';
    'PL18A':
      PIN_NUMBER='(N2,0,0,0,0,0,0)';
      BIDIRECTIONAL='TRUE';
      INPUT_LOAD='(-0.01,0.01)';
      OUTPUT_LOAD='(1.0,-1.0)';
      PINUSE='BI';
    'PL18B':
      PIN_NUMBER='(P1,0,0,0,0,0,0)';
      BIDIRECTIONAL='TRUE';
      INPUT_LOAD='(-0.01,0.01)';
      OUTPUT_LOAD='(1.0,-1.0)';
      PINUSE='BI';
    'PL18C':
      PIN_NUMBER='(N3,0,0,0,0,0,0)';
      BIDIRECTIONAL='TRUE';
      INPUT_LOAD='(-0.01,0.01)';
      OUTPUT_LOAD='(1.0,-1.0)';
      PINUSE='BI';
    'PL18D':
      PIN_NUMBER='(N4,0,0,0,0,0,0)';
      BIDIRECTIONAL='TRUE';
      INPUT_LOAD='(-0.01,0.01)';
      OUTPUT_LOAD='(1.0,-1.0)';
      PINUSE='BI';
    'PL19A':
      PIN_NUMBER='(P2,0,0,0,0,0,0)';
      BIDIRECTIONAL='TRUE';
      INPUT_LOAD='(-0.01,0.01)';
      OUTPUT_LOAD='(1.0,-1.0)';
      PINUSE='BI';
    'PL19B':
      PIN_NUMBER='(R1,0,0,0,0,0,0)';
      BIDIRECTIONAL='TRUE';
      INPUT_LOAD='(-0.01,0.01)';
      OUTPUT_LOAD='(1.0,-1.0)';
      PINUSE='BI';
    'PL19C':
      PIN_NUMBER='(P3,0,0,0,0,0,0)';
      BIDIRECTIONAL='TRUE';
      INPUT_LOAD='(-0.01,0.01)';
      OUTPUT_LOAD='(1.0,-1.0)';
      PINUSE='BI';
    'PL19D':
      PIN_NUMBER='(M7,0,0,0,0,0,0)';
      BIDIRECTIONAL='TRUE';
      INPUT_LOAD='(-0.01,0.01)';
      OUTPUT_LOAD='(1.0,-1.0)';
      PINUSE='BI';
    'PL27A||PCLKT3_0':
      PIN_NUMBER='(U2,0,0,0,0,0,0)';
      BIDIRECTIONAL='TRUE';
      INPUT_LOAD='(-0.01,0.01)';
      OUTPUT_LOAD='(1.0,-1.0)';
      PINUSE='BI';
    'PL27B||PCLKC3_0':
      PIN_NUMBER='(V1,0,0,0,0,0,0)';
      BIDIRECTIONAL='TRUE';
      INPUT_LOAD='(-0.01,0.01)';
      OUTPUT_LOAD='(1.0,-1.0)';
      PINUSE='BI';
    'PL27C':
      PIN_NUMBER='(U3,0,0,0,0,0,0)';
      BIDIRECTIONAL='TRUE';
      INPUT_LOAD='(-0.01,0.01)';
      OUTPUT_LOAD='(1.0,-1.0)';
      PINUSE='BI';
    'PL27D':
      PIN_NUMBER='(U4,0,0,0,0,0,0)';
      BIDIRECTIONAL='TRUE';
      INPUT_LOAD='(-0.01,0.01)';
      OUTPUT_LOAD='(1.0,-1.0)';
      PINUSE='BI';
    'PL28A':
      PIN_NUMBER='(W1,0,0,0,0,0,0)';
      BIDIRECTIONAL='TRUE';
      INPUT_LOAD='(-0.01,0.01)';
      OUTPUT_LOAD='(1.0,-1.0)';
      PINUSE='BI';
    'PL28B':
      PIN_NUMBER='(W2,0,0,0,0,0,0)';
      BIDIRECTIONAL='TRUE';
      INPUT_LOAD='(-0.01,0.01)';
      OUTPUT_LOAD='(1.0,-1.0)';
      PINUSE='BI';
    'PL28C':
      PIN_NUMBER='(V4,0,0,0,0,0,0)';
      BIDIRECTIONAL='TRUE';
      INPUT_LOAD='(-0.01,0.01)';
      OUTPUT_LOAD='(1.0,-1.0)';
      PINUSE='BI';
    'PL28D':
      PIN_NUMBER='(U5,0,0,0,0,0,0)';
      BIDIRECTIONAL='TRUE';
      INPUT_LOAD='(-0.01,0.01)';
      OUTPUT_LOAD='(1.0,-1.0)';
      PINUSE='BI';
    'PL29A':
      PIN_NUMBER='(Y1,0,0,0,0,0,0)';
      BIDIRECTIONAL='TRUE';
      INPUT_LOAD='(-0.01,0.01)';
      OUTPUT_LOAD='(1.0,-1.0)';
      PINUSE='BI';
    'PL29B':
      PIN_NUMBER='(AA1,0,0,0,0,0,0)';
      BIDIRECTIONAL='TRUE';
      INPUT_LOAD='(-0.01,0.01)';
      OUTPUT_LOAD='(1.0,-1.0)';
      PINUSE='BI';
    'PL29C':
      PIN_NUMBER='(W3,0,0,0,0,0,0)';
      BIDIRECTIONAL='TRUE';
      INPUT_LOAD='(-0.01,0.01)';
      OUTPUT_LOAD='(1.0,-1.0)';
      PINUSE='BI';
    'PL29D':
      PIN_NUMBER='(Y2,0,0,0,0,0,0)';
      BIDIRECTIONAL='TRUE';
      INPUT_LOAD='(-0.01,0.01)';
      OUTPUT_LOAD='(1.0,-1.0)';
      PINUSE='BI';
    'PL30A':
      PIN_NUMBER='(Y3,0,0,0,0,0,0)';
      BIDIRECTIONAL='TRUE';
      INPUT_LOAD='(-0.01,0.01)';
      OUTPUT_LOAD='(1.0,-1.0)';
      PINUSE='BI';
    'PL30B':
      PIN_NUMBER='(W4,0,0,0,0,0,0)';
      BIDIRECTIONAL='TRUE';
      INPUT_LOAD='(-0.01,0.01)';
      OUTPUT_LOAD='(1.0,-1.0)';
      PINUSE='BI';
    'PL30C':
      PIN_NUMBER='(V5,0,0,0,0,0,0)';
      BIDIRECTIONAL='TRUE';
      INPUT_LOAD='(-0.01,0.01)';
      OUTPUT_LOAD='(1.0,-1.0)';
      PINUSE='BI';
    'PL30D':
      PIN_NUMBER='(T7,0,0,0,0,0,0)';
      BIDIRECTIONAL='TRUE';
      INPUT_LOAD='(-0.01,0.01)';
      OUTPUT_LOAD='(1.0,-1.0)';
      PINUSE='BI';
    'PL7A||PCLKT5_0':
      PIN_NUMBER='(G2,0,0,0,0,0,0)';
      BIDIRECTIONAL='TRUE';
      INPUT_LOAD='(-0.01,0.01)';
      OUTPUT_LOAD='(1.0,-1.0)';
      PINUSE='BI';
    'PL7B||PCLKC5_0':
      PIN_NUMBER='(G1,0,0,0,0,0,0)';
      BIDIRECTIONAL='TRUE';
      INPUT_LOAD='(-0.01,0.01)';
      OUTPUT_LOAD='(1.0,-1.0)';
      PINUSE='BI';
    'PL7C':
      PIN_NUMBER='(H4,0,0,0,0,0,0)';
      BIDIRECTIONAL='TRUE';
      INPUT_LOAD='(-0.01,0.01)';
      OUTPUT_LOAD='(1.0,-1.0)';
      PINUSE='BI';
    'PL7D':
      PIN_NUMBER='(H3,0,0,0,0,0,0)';
      BIDIRECTIONAL='TRUE';
      INPUT_LOAD='(-0.01,0.01)';
      OUTPUT_LOAD='(1.0,-1.0)';
      PINUSE='BI';
    'PL10A':
      PIN_NUMBER='(H2,0,0,0,0,0,0)';
      BIDIRECTIONAL='TRUE';
      INPUT_LOAD='(-0.01,0.01)';
      OUTPUT_LOAD='(1.0,-1.0)';
      PINUSE='BI';
    'PL10B':
      PIN_NUMBER='(H1,0,0,0,0,0,0)';
      BIDIRECTIONAL='TRUE';
      INPUT_LOAD='(-0.01,0.01)';
      OUTPUT_LOAD='(1.0,-1.0)';
      PINUSE='BI';
    'PL10C':
      PIN_NUMBER='(J7,0,0,0,0,0,0)';
      BIDIRECTIONAL='TRUE';
      INPUT_LOAD='(-0.01,0.01)';
      OUTPUT_LOAD='(1.0,-1.0)';
      PINUSE='BI';
    'PL10D':
      PIN_NUMBER='(J6,0,0,0,0,0,0)';
      BIDIRECTIONAL='TRUE';
      INPUT_LOAD='(-0.01,0.01)';
      OUTPUT_LOAD='(1.0,-1.0)';
      PINUSE='BI';
    'PL11A':
      PIN_NUMBER='(H5,0,0,0,0,0,0)';
      BIDIRECTIONAL='TRUE';
      INPUT_LOAD='(-0.01,0.01)';
      OUTPUT_LOAD='(1.0,-1.0)';
      PINUSE='BI';
    'PL11B':
      PIN_NUMBER='(J5,0,0,0,0,0,0)';
      BIDIRECTIONAL='TRUE';
      INPUT_LOAD='(-0.01,0.01)';
      OUTPUT_LOAD='(1.0,-1.0)';
      PINUSE='BI';
    'PL11C':
      PIN_NUMBER='(J4,0,0,0,0,0,0)';
      BIDIRECTIONAL='TRUE';
      INPUT_LOAD='(-0.01,0.01)';
      OUTPUT_LOAD='(1.0,-1.0)';
      PINUSE='BI';
    'PL11D':
      PIN_NUMBER='(J3,0,0,0,0,0,0)';
      BIDIRECTIONAL='TRUE';
      INPUT_LOAD='(-0.01,0.01)';
      OUTPUT_LOAD='(1.0,-1.0)';
      PINUSE='BI';
    'PL12A':
      PIN_NUMBER='(J2,0,0,0,0,0,0)';
      BIDIRECTIONAL='TRUE';
      INPUT_LOAD='(-0.01,0.01)';
      OUTPUT_LOAD='(1.0,-1.0)';
      PINUSE='BI';
    'PL12B':
      PIN_NUMBER='(J1,0,0,0,0,0,0)';
      BIDIRECTIONAL='TRUE';
      INPUT_LOAD='(-0.01,0.01)';
      OUTPUT_LOAD='(1.0,-1.0)';
      PINUSE='BI';
    'PL12C':
      PIN_NUMBER='(K7,0,0,0,0,0,0)';
      BIDIRECTIONAL='TRUE';
      INPUT_LOAD='(-0.01,0.01)';
      OUTPUT_LOAD='(1.0,-1.0)';
      PINUSE='BI';
    'PL12D':
      PIN_NUMBER='(K6,0,0,0,0,0,0)';
      BIDIRECTIONAL='TRUE';
      INPUT_LOAD='(-0.01,0.01)';
      OUTPUT_LOAD='(1.0,-1.0)';
      PINUSE='BI';
    'PB5A':
      PIN_NUMBER='(0,AA2,0,0,0,0,0)';
      BIDIRECTIONAL='TRUE';
      INPUT_LOAD='(-0.01,0.01)';
      OUTPUT_LOAD='(1.0,-1.0)';
      PINUSE='BI';
    'PB5B':
      PIN_NUMBER='(0,AB2,0,0,0,0,0)';
      BIDIRECTIONAL='TRUE';
      INPUT_LOAD='(-0.01,0.01)';
      OUTPUT_LOAD='(1.0,-1.0)';
      PINUSE='BI';
    'PB5C':
      PIN_NUMBER='(0,V6,0,0,0,0,0)';
      BIDIRECTIONAL='TRUE';
      INPUT_LOAD='(-0.01,0.01)';
      OUTPUT_LOAD='(1.0,-1.0)';
      PINUSE='BI';
    'PB5D':
      PIN_NUMBER='(0,U6,0,0,0,0,0)';
      BIDIRECTIONAL='TRUE';
      INPUT_LOAD='(-0.01,0.01)';
      OUTPUT_LOAD='(1.0,-1.0)';
      PINUSE='BI';
    'PB7A||CSSPIN':
      PIN_NUMBER='(0,AA3,0,0,0,0,0)';
      BIDIRECTIONAL='TRUE';
      INPUT_LOAD='(-0.01,0.01)';
      OUTPUT_LOAD='(1.0,-1.0)';
      PINUSE='BI';
    'PB7B':
      PIN_NUMBER='(0,AB3,0,0,0,0,0)';
      BIDIRECTIONAL='TRUE';
      INPUT_LOAD='(-0.01,0.01)';
      OUTPUT_LOAD='(1.0,-1.0)';
      PINUSE='BI';
    'PB7C':
      PIN_NUMBER='(0,Y4,0,0,0,0,0)';
      BIDIRECTIONAL='TRUE';
      INPUT_LOAD='(-0.01,0.01)';
      OUTPUT_LOAD='(1.0,-1.0)';
      PINUSE='BI';
    'PB7D':
      PIN_NUMBER='(0,W5,0,0,0,0,0)';
      BIDIRECTIONAL='TRUE';
      INPUT_LOAD='(-0.01,0.01)';
      OUTPUT_LOAD='(1.0,-1.0)';
      PINUSE='BI';
    'PB8C':
      PIN_NUMBER='(0,U7,0,0,0,0,0)';
      BIDIRECTIONAL='TRUE';
      INPUT_LOAD='(-0.01,0.01)';
      OUTPUT_LOAD='(1.0,-1.0)';
      PINUSE='BI';
    'PB8D':
      PIN_NUMBER='(0,T8,0,0,0,0,0)';
      BIDIRECTIONAL='TRUE';
      INPUT_LOAD='(-0.01,0.01)';
      OUTPUT_LOAD='(1.0,-1.0)';
      PINUSE='BI';
    'PB8A':
      PIN_NUMBER='(0,AA4,0,0,0,0,0)';
      BIDIRECTIONAL='TRUE';
      INPUT_LOAD='(-0.01,0.01)';
      OUTPUT_LOAD='(1.0,-1.0)';
      PINUSE='BI';
    'PB8B':
      PIN_NUMBER='(0,AB4,0,0,0,0,0)';
      BIDIRECTIONAL='TRUE';
      INPUT_LOAD='(-0.01,0.01)';
      OUTPUT_LOAD='(1.0,-1.0)';
      PINUSE='BI';
    'PB10A':
      PIN_NUMBER='(0,AA5,0,0,0,0,0)';
      BIDIRECTIONAL='TRUE';
      INPUT_LOAD='(-0.01,0.01)';
      OUTPUT_LOAD='(1.0,-1.0)';
      PINUSE='BI';
    'PB10B':
      PIN_NUMBER='(0,AB5,0,0,0,0,0)';
      BIDIRECTIONAL='TRUE';
      INPUT_LOAD='(-0.01,0.01)';
      OUTPUT_LOAD='(1.0,-1.0)';
      PINUSE='BI';
    'PB10C':
      PIN_NUMBER='(0,Y5,0,0,0,0,0)';
      BIDIRECTIONAL='TRUE';
      INPUT_LOAD='(-0.01,0.01)';
      OUTPUT_LOAD='(1.0,-1.0)';
      PINUSE='BI';
    'PB10D':
      PIN_NUMBER='(0,Y6,0,0,0,0,0)';
      BIDIRECTIONAL='TRUE';
      INPUT_LOAD='(-0.01,0.01)';
      OUTPUT_LOAD='(1.0,-1.0)';
      PINUSE='BI';
    'PB13C':
      PIN_NUMBER='(0,V8,0,0,0,0,0)';
      BIDIRECTIONAL='TRUE';
      INPUT_LOAD='(-0.01,0.01)';
      OUTPUT_LOAD='(1.0,-1.0)';
      PINUSE='BI';
    'PB13D':
      PIN_NUMBER='(0,U8,0,0,0,0,0)';
      BIDIRECTIONAL='TRUE';
      INPUT_LOAD='(-0.01,0.01)';
      OUTPUT_LOAD='(1.0,-1.0)';
      PINUSE='BI';
    'PB16A||MCLK||CCLK':
      PIN_NUMBER='(0,T9,0,0,0,0,0)';
      BIDIRECTIONAL='TRUE';
      INPUT_LOAD='(-0.01,0.01)';
      OUTPUT_LOAD='(1.0,-1.0)';
      PINUSE='BI';
    'PB16B||SO||SPISO':
      PIN_NUMBER='(0,U9,0,0,0,0,0)';
      BIDIRECTIONAL='TRUE';
      INPUT_LOAD='(-0.01,0.01)';
      OUTPUT_LOAD='(1.0,-1.0)';
      PINUSE='BI';
    'PB18A':
      PIN_NUMBER='(0,AA8,0,0,0,0,0)';
      BIDIRECTIONAL='TRUE';
      INPUT_LOAD='(-0.01,0.01)';
      OUTPUT_LOAD='(1.0,-1.0)';
      PINUSE='BI';
    'PB18B':
      PIN_NUMBER='(0,AB8,0,0,0,0,0)';
      BIDIRECTIONAL='TRUE';
      INPUT_LOAD='(-0.01,0.01)';
      OUTPUT_LOAD='(1.0,-1.0)';
      PINUSE='BI';
    'PB21A':
      PIN_NUMBER='(0,V10,0,0,0,0,0)';
      BIDIRECTIONAL='TRUE';
      INPUT_LOAD='(-0.01,0.01)';
      OUTPUT_LOAD='(1.0,-1.0)';
      PINUSE='BI';
    'PB21B':
      PIN_NUMBER='(0,W10,0,0,0,0,0)';
      BIDIRECTIONAL='TRUE';
      INPUT_LOAD='(-0.01,0.01)';
      OUTPUT_LOAD='(1.0,-1.0)';
      PINUSE='BI';
    'PB22A||PCLKT2_0':
      PIN_NUMBER='(0,AA10,0,0,0,0,0)';
      BIDIRECTIONAL='TRUE';
      INPUT_LOAD='(-0.01,0.01)';
      OUTPUT_LOAD='(1.0,-1.0)';
      PINUSE='BI';
    'PB22B||PCLKC2_0':
      PIN_NUMBER='(0,AB10,0,0,0,0,0)';
      BIDIRECTIONAL='TRUE';
      INPUT_LOAD='(-0.01,0.01)';
      OUTPUT_LOAD='(1.0,-1.0)';
      PINUSE='BI';
    'PB24A':
      PIN_NUMBER='(0,AA11,0,0,0,0,0)';
      BIDIRECTIONAL='TRUE';
      INPUT_LOAD='(-0.01,0.01)';
      OUTPUT_LOAD='(1.0,-1.0)';
      PINUSE='BI';
    'PB24B':
      PIN_NUMBER='(0,AB11,0,0,0,0,0)';
      BIDIRECTIONAL='TRUE';
      INPUT_LOAD='(-0.01,0.01)';
      OUTPUT_LOAD='(1.0,-1.0)';
      PINUSE='BI';
    'PB24C':
      PIN_NUMBER='(0,V11,0,0,0,0,0)';
      BIDIRECTIONAL='TRUE';
      INPUT_LOAD='(-0.01,0.01)';
      OUTPUT_LOAD='(1.0,-1.0)';
      PINUSE='BI';
    'PB24D':
      PIN_NUMBER='(0,Y11,0,0,0,0,0)';
      BIDIRECTIONAL='TRUE';
      INPUT_LOAD='(-0.01,0.01)';
      OUTPUT_LOAD='(1.0,-1.0)';
      PINUSE='BI';
    'PB29A||PCLKT2_1':
      PIN_NUMBER='(0,AB12,0,0,0,0,0)';
      BIDIRECTIONAL='TRUE';
      INPUT_LOAD='(-0.01,0.01)';
      OUTPUT_LOAD='(1.0,-1.0)';
      PINUSE='BI';
    'PB29B||PCLKC2_1':
      PIN_NUMBER='(0,AA12,0,0,0,0,0)';
      BIDIRECTIONAL='TRUE';
      INPUT_LOAD='(-0.01,0.01)';
      OUTPUT_LOAD='(1.0,-1.0)';
      PINUSE='BI';
    'PB30A':
      PIN_NUMBER='(0,AB13,0,0,0,0,0)';
      BIDIRECTIONAL='TRUE';
      INPUT_LOAD='(-0.01,0.01)';
      OUTPUT_LOAD='(1.0,-1.0)';
      PINUSE='BI';
    'PB30B':
      PIN_NUMBER='(0,AA13,0,0,0,0,0)';
      BIDIRECTIONAL='TRUE';
      INPUT_LOAD='(-0.01,0.01)';
      OUTPUT_LOAD='(1.0,-1.0)';
      PINUSE='BI';
    'PB33A':
      PIN_NUMBER='(0,AB14,0,0,0,0,0)';
      BIDIRECTIONAL='TRUE';
      INPUT_LOAD='(-0.01,0.01)';
      OUTPUT_LOAD='(1.0,-1.0)';
      PINUSE='BI';
    'PB33B':
      PIN_NUMBER='(0,AA14,0,0,0,0,0)';
      BIDIRECTIONAL='TRUE';
      INPUT_LOAD='(-0.01,0.01)';
      OUTPUT_LOAD='(1.0,-1.0)';
      PINUSE='BI';
    'PB43A':
      PIN_NUMBER='(0,AB19,0,0,0,0,0)';
      BIDIRECTIONAL='TRUE';
      INPUT_LOAD='(-0.01,0.01)';
      OUTPUT_LOAD='(1.0,-1.0)';
      PINUSE='BI';
    'PB43B':
      PIN_NUMBER='(0,AA19,0,0,0,0,0)';
      BIDIRECTIONAL='TRUE';
      INPUT_LOAD='(-0.01,0.01)';
      OUTPUT_LOAD='(1.0,-1.0)';
      PINUSE='BI';
    'PB44A':
      PIN_NUMBER='(0,AB20,0,0,0,0,0)';
      BIDIRECTIONAL='TRUE';
      INPUT_LOAD='(-0.01,0.01)';
      OUTPUT_LOAD='(1.0,-1.0)';
      PINUSE='BI';
    'PB44B':
      PIN_NUMBER='(0,AA20,0,0,0,0,0)';
      BIDIRECTIONAL='TRUE';
      INPUT_LOAD='(-0.01,0.01)';
      OUTPUT_LOAD='(1.0,-1.0)';
      PINUSE='BI';
    'PB46A||SN':
      PIN_NUMBER='(0,AB21,0,0,0,0,0)';
      BIDIRECTIONAL='TRUE';
      INPUT_LOAD='(-0.01,0.01)';
      OUTPUT_LOAD='(1.0,-1.0)';
      PINUSE='BI';
    'PB46B||SI||SISPI':
      PIN_NUMBER='(0,AA21,0,0,0,0,0)';
      BIDIRECTIONAL='TRUE';
      INPUT_LOAD='(-0.01,0.01)';
      OUTPUT_LOAD='(1.0,-1.0)';
      PINUSE='BI';
    'PB35A':
      PIN_NUMBER='(0,AB15,0,0,0,0,0)';
      BIDIRECTIONAL='TRUE';
      INPUT_LOAD='(-0.01,0.01)';
      OUTPUT_LOAD='(1.0,-1.0)';
      PINUSE='BI';
    'PB35B':
      PIN_NUMBER='(0,AA15,0,0,0,0,0)';
      BIDIRECTIONAL='TRUE';
      INPUT_LOAD='(-0.01,0.01)';
      OUTPUT_LOAD='(1.0,-1.0)';
      PINUSE='BI';
    'PB11A':
      PIN_NUMBER='(0,AA6,0,0,0,0,0)';
      BIDIRECTIONAL='TRUE';
      INPUT_LOAD='(-0.01,0.01)';
      OUTPUT_LOAD='(1.0,-1.0)';
      PINUSE='BI';
    'PB11B':
      PIN_NUMBER='(0,AB6,0,0,0,0,0)';
      BIDIRECTIONAL='TRUE';
      INPUT_LOAD='(-0.01,0.01)';
      OUTPUT_LOAD='(1.0,-1.0)';
      PINUSE='BI';
    'PB11C':
      PIN_NUMBER='(0,W6,0,0,0,0,0)';
      BIDIRECTIONAL='TRUE';
      INPUT_LOAD='(-0.01,0.01)';
      OUTPUT_LOAD='(1.0,-1.0)';
      PINUSE='BI';
    'PB11D':
      PIN_NUMBER='(0,V7,0,0,0,0,0)';
      BIDIRECTIONAL='TRUE';
      INPUT_LOAD='(-0.01,0.01)';
      OUTPUT_LOAD='(1.0,-1.0)';
      PINUSE='BI';
    'PB13A':
      PIN_NUMBER='(0,AA7,0,0,0,0,0)';
      BIDIRECTIONAL='TRUE';
      INPUT_LOAD='(-0.01,0.01)';
      OUTPUT_LOAD='(1.0,-1.0)';
      PINUSE='BI';
    'PB13B':
      PIN_NUMBER='(0,AB7,0,0,0,0,0)';
      BIDIRECTIONAL='TRUE';
      INPUT_LOAD='(-0.01,0.01)';
      OUTPUT_LOAD='(1.0,-1.0)';
      PINUSE='BI';
    'PB16C':
      PIN_NUMBER='(0,V9,0,0,0,0,0)';
      BIDIRECTIONAL='TRUE';
      INPUT_LOAD='(-0.01,0.01)';
      OUTPUT_LOAD='(1.0,-1.0)';
      PINUSE='BI';
    'PB16D':
      PIN_NUMBER='(0,W8,0,0,0,0,0)';
      BIDIRECTIONAL='TRUE';
      INPUT_LOAD='(-0.01,0.01)';
      OUTPUT_LOAD='(1.0,-1.0)';
      PINUSE='BI';
    'PB18C':
      PIN_NUMBER='(0,Y8,0,0,0,0,0)';
      BIDIRECTIONAL='TRUE';
      INPUT_LOAD='(-0.01,0.01)';
      OUTPUT_LOAD='(1.0,-1.0)';
      PINUSE='BI';
    'PB18D':
      PIN_NUMBER='(0,W9,0,0,0,0,0)';
      BIDIRECTIONAL='TRUE';
      INPUT_LOAD='(-0.01,0.01)';
      OUTPUT_LOAD='(1.0,-1.0)';
      PINUSE='BI';
    'PB19A':
      PIN_NUMBER='(0,AA9,0,0,0,0,0)';
      BIDIRECTIONAL='TRUE';
      INPUT_LOAD='(-0.01,0.01)';
      OUTPUT_LOAD='(1.0,-1.0)';
      PINUSE='BI';
    'PB19B':
      PIN_NUMBER='(0,AB9,0,0,0,0,0)';
      BIDIRECTIONAL='TRUE';
      INPUT_LOAD='(-0.01,0.01)';
      OUTPUT_LOAD='(1.0,-1.0)';
      PINUSE='BI';
    'PB19C':
      PIN_NUMBER='(0,T10,0,0,0,0,0)';
      BIDIRECTIONAL='TRUE';
      INPUT_LOAD='(-0.01,0.01)';
      OUTPUT_LOAD='(1.0,-1.0)';
      PINUSE='BI';
    'PB19D':
      PIN_NUMBER='(0,U10,0,0,0,0,0)';
      BIDIRECTIONAL='TRUE';
      INPUT_LOAD='(-0.01,0.01)';
      OUTPUT_LOAD='(1.0,-1.0)';
      PINUSE='BI';
    'PB22C':
      PIN_NUMBER='(0,T11,0,0,0,0,0)';
      BIDIRECTIONAL='TRUE';
      INPUT_LOAD='(-0.01,0.01)';
      OUTPUT_LOAD='(1.0,-1.0)';
      PINUSE='BI';
    'PB22D':
      PIN_NUMBER='(0,U11,0,0,0,0,0)';
      BIDIRECTIONAL='TRUE';
      INPUT_LOAD='(-0.01,0.01)';
      OUTPUT_LOAD='(1.0,-1.0)';
      PINUSE='BI';
    'PB27A':
      PIN_NUMBER='(0,Y12,0,0,0,0,0)';
      BIDIRECTIONAL='TRUE';
      INPUT_LOAD='(-0.01,0.01)';
      OUTPUT_LOAD='(1.0,-1.0)';
      PINUSE='BI';
    'PB27B':
      PIN_NUMBER='(0,T12,0,0,0,0,0)';
      BIDIRECTIONAL='TRUE';
      INPUT_LOAD='(-0.01,0.01)';
      OUTPUT_LOAD='(1.0,-1.0)';
      PINUSE='BI';
    'PB27C':
      PIN_NUMBER='(0,U12,0,0,0,0,0)';
      BIDIRECTIONAL='TRUE';
      INPUT_LOAD='(-0.01,0.01)';
      OUTPUT_LOAD='(1.0,-1.0)';
      PINUSE='BI';
    'PB27D':
      PIN_NUMBER='(0,V12,0,0,0,0,0)';
      BIDIRECTIONAL='TRUE';
      INPUT_LOAD='(-0.01,0.01)';
      OUTPUT_LOAD='(1.0,-1.0)';
      PINUSE='BI';
    'PB29C':
      PIN_NUMBER='(0,V13,0,0,0,0,0)';
      BIDIRECTIONAL='TRUE';
      INPUT_LOAD='(-0.01,0.01)';
      OUTPUT_LOAD='(1.0,-1.0)';
      PINUSE='BI';
    'PB29D':
      PIN_NUMBER='(0,U13,0,0,0,0,0)';
      BIDIRECTIONAL='TRUE';
      INPUT_LOAD='(-0.01,0.01)';
      OUTPUT_LOAD='(1.0,-1.0)';
      PINUSE='BI';
    'PB30C':
      PIN_NUMBER='(0,Y13,0,0,0,0,0)';
      BIDIRECTIONAL='TRUE';
      INPUT_LOAD='(-0.01,0.01)';
      OUTPUT_LOAD='(1.0,-1.0)';
      PINUSE='BI';
    'PB30D':
      PIN_NUMBER='(0,W13,0,0,0,0,0)';
      BIDIRECTIONAL='TRUE';
      INPUT_LOAD='(-0.01,0.01)';
      OUTPUT_LOAD='(1.0,-1.0)';
      PINUSE='BI';
    'PB33C':
      PIN_NUMBER='(0,Y14,0,0,0,0,0)';
      BIDIRECTIONAL='TRUE';
      INPUT_LOAD='(-0.01,0.01)';
      OUTPUT_LOAD='(1.0,-1.0)';
      PINUSE='BI';
    'PB33D':
      PIN_NUMBER='(0,W14,0,0,0,0,0)';
      BIDIRECTIONAL='TRUE';
      INPUT_LOAD='(-0.01,0.01)';
      OUTPUT_LOAD='(1.0,-1.0)';
      PINUSE='BI';
    'PB32A':
      PIN_NUMBER='(0,T13,0,0,0,0,0)';
      BIDIRECTIONAL='TRUE';
      INPUT_LOAD='(-0.01,0.01)';
      OUTPUT_LOAD='(1.0,-1.0)';
      PINUSE='BI';
    'PB32B':
      PIN_NUMBER='(0,T14,0,0,0,0,0)';
      BIDIRECTIONAL='TRUE';
      INPUT_LOAD='(-0.01,0.01)';
      OUTPUT_LOAD='(1.0,-1.0)';
      PINUSE='BI';
    'PB32C':
      PIN_NUMBER='(0,U14,0,0,0,0,0)';
      BIDIRECTIONAL='TRUE';
      INPUT_LOAD='(-0.01,0.01)';
      OUTPUT_LOAD='(1.0,-1.0)';
      PINUSE='BI';
    'PB32D':
      PIN_NUMBER='(0,V14,0,0,0,0,0)';
      BIDIRECTIONAL='TRUE';
      INPUT_LOAD='(-0.01,0.01)';
      OUTPUT_LOAD='(1.0,-1.0)';
      PINUSE='BI';
    'PB35C':
      PIN_NUMBER='(0,Y15,0,0,0,0,0)';
      BIDIRECTIONAL='TRUE';
      INPUT_LOAD='(-0.01,0.01)';
      OUTPUT_LOAD='(1.0,-1.0)';
      PINUSE='BI';
    'PB35D':
      PIN_NUMBER='(0,W15,0,0,0,0,0)';
      BIDIRECTIONAL='TRUE';
      INPUT_LOAD='(-0.01,0.01)';
      OUTPUT_LOAD='(1.0,-1.0)';
      PINUSE='BI';
    'PB38A':
      PIN_NUMBER='(0,AB16,0,0,0,0,0)';
      BIDIRECTIONAL='TRUE';
      INPUT_LOAD='(-0.01,0.01)';
      OUTPUT_LOAD='(1.0,-1.0)';
      PINUSE='BI';
    'PB38B':
      PIN_NUMBER='(0,AA16,0,0,0,0,0)';
      BIDIRECTIONAL='TRUE';
      INPUT_LOAD='(-0.01,0.01)';
      OUTPUT_LOAD='(1.0,-1.0)';
      PINUSE='BI';
    'PB38C':
      PIN_NUMBER='(0,V15,0,0,0,0,0)';
      BIDIRECTIONAL='TRUE';
      INPUT_LOAD='(-0.01,0.01)';
      OUTPUT_LOAD='(1.0,-1.0)';
      PINUSE='BI';
    'PB38D':
      PIN_NUMBER='(0,U15,0,0,0,0,0)';
      BIDIRECTIONAL='TRUE';
      INPUT_LOAD='(-0.01,0.01)';
      OUTPUT_LOAD='(1.0,-1.0)';
      PINUSE='BI';
    'PB40A':
      PIN_NUMBER='(0,AB17,0,0,0,0,0)';
      BIDIRECTIONAL='TRUE';
      INPUT_LOAD='(-0.01,0.01)';
      OUTPUT_LOAD='(1.0,-1.0)';
      PINUSE='BI';
    'PB40B':
      PIN_NUMBER='(0,AA17,0,0,0,0,0)';
      BIDIRECTIONAL='TRUE';
      INPUT_LOAD='(-0.01,0.01)';
      OUTPUT_LOAD='(1.0,-1.0)';
      PINUSE='BI';
    'PB40C':
      PIN_NUMBER='(0,Y17,0,0,0,0,0)';
      BIDIRECTIONAL='TRUE';
      INPUT_LOAD='(-0.01,0.01)';
      OUTPUT_LOAD='(1.0,-1.0)';
      PINUSE='BI';
    'PB40D':
      PIN_NUMBER='(0,V16,0,0,0,0,0)';
      BIDIRECTIONAL='TRUE';
      INPUT_LOAD='(-0.01,0.01)';
      OUTPUT_LOAD='(1.0,-1.0)';
      PINUSE='BI';
    'PB41A':
      PIN_NUMBER='(0,AB18,0,0,0,0,0)';
      BIDIRECTIONAL='TRUE';
      INPUT_LOAD='(-0.01,0.01)';
      OUTPUT_LOAD='(1.0,-1.0)';
      PINUSE='BI';
    'PB41B':
      PIN_NUMBER='(0,AA18,0,0,0,0,0)';
      BIDIRECTIONAL='TRUE';
      INPUT_LOAD='(-0.01,0.01)';
      OUTPUT_LOAD='(1.0,-1.0)';
      PINUSE='BI';
    'PB41C':
      PIN_NUMBER='(0,Y18,0,0,0,0,0)';
      BIDIRECTIONAL='TRUE';
      INPUT_LOAD='(-0.01,0.01)';
      OUTPUT_LOAD='(1.0,-1.0)';
      PINUSE='BI';
    'PB41D':
      PIN_NUMBER='(0,W17,0,0,0,0,0)';
      BIDIRECTIONAL='TRUE';
      INPUT_LOAD='(-0.01,0.01)';
      OUTPUT_LOAD='(1.0,-1.0)';
      PINUSE='BI';
    'PB43C':
      PIN_NUMBER='(0,T15,0,0,0,0,0)';
      BIDIRECTIONAL='TRUE';
      INPUT_LOAD='(-0.01,0.01)';
      OUTPUT_LOAD='(1.0,-1.0)';
      PINUSE='BI';
    'PB43D':
      PIN_NUMBER='(0,U16,0,0,0,0,0)';
      BIDIRECTIONAL='TRUE';
      INPUT_LOAD='(-0.01,0.01)';
      OUTPUT_LOAD='(1.0,-1.0)';
      PINUSE='BI';
    'PB44C':
      PIN_NUMBER='(0,Y19,0,0,0,0,0)';
      BIDIRECTIONAL='TRUE';
      INPUT_LOAD='(-0.01,0.01)';
      OUTPUT_LOAD='(1.0,-1.0)';
      PINUSE='BI';
    'PB44D':
      PIN_NUMBER='(0,W18,0,0,0,0,0)';
      BIDIRECTIONAL='TRUE';
      INPUT_LOAD='(-0.01,0.01)';
      OUTPUT_LOAD='(1.0,-1.0)';
      PINUSE='BI';
    'PB46C':
      PIN_NUMBER='(0,V17,0,0,0,0,0)';
      BIDIRECTIONAL='TRUE';
      INPUT_LOAD='(-0.01,0.01)';
      OUTPUT_LOAD='(1.0,-1.0)';
      PINUSE='BI';
    'PB46D':
      PIN_NUMBER='(0,T16,0,0,0,0,0)';
      BIDIRECTIONAL='TRUE';
      INPUT_LOAD='(-0.01,0.01)';
      OUTPUT_LOAD='(1.0,-1.0)';
      PINUSE='BI';
    'PB21C':
      PIN_NUMBER='(0,Y9,0,0,0,0,0)';
      BIDIRECTIONAL='TRUE';
      INPUT_LOAD='(-0.01,0.01)';
      OUTPUT_LOAD='(1.0,-1.0)';
      PINUSE='BI';
    'PB21D':
      PIN_NUMBER='(0,Y10,0,0,0,0,0)';
      BIDIRECTIONAL='TRUE';
      INPUT_LOAD='(-0.01,0.01)';
      OUTPUT_LOAD='(1.0,-1.0)';
      PINUSE='BI';
    'PT43B||R_GPLLC':
      PIN_NUMBER='(0,0,B21,0,0,0,0)';
      BIDIRECTIONAL='TRUE';
      INPUT_LOAD='(-0.01,0.01)';
      OUTPUT_LOAD='(1.0,-1.0)';
      PINUSE='BI';
    'PT43A||R_GPLLT':
      PIN_NUMBER='(0,0,A20,0,0,0,0)';
      BIDIRECTIONAL='TRUE';
      INPUT_LOAD='(-0.01,0.01)';
      OUTPUT_LOAD='(1.0,-1.0)';
      PINUSE='BI';
    'PT41B':
      PIN_NUMBER='(0,0,B19,0,0,0,0)';
      BIDIRECTIONAL='TRUE';
      INPUT_LOAD='(-0.01,0.01)';
      OUTPUT_LOAD='(1.0,-1.0)';
      PINUSE='BI';
    'PT41A':
      PIN_NUMBER='(0,0,A18,0,0,0,0)';
      BIDIRECTIONAL='TRUE';
      INPUT_LOAD='(-0.01,0.01)';
      OUTPUT_LOAD='(1.0,-1.0)';
      PINUSE='BI';
    'PT31B':
      PIN_NUMBER='(0,0,F14,0,0,0,0)';
      BIDIRECTIONAL='TRUE';
      INPUT_LOAD='(-0.01,0.01)';
      OUTPUT_LOAD='(1.0,-1.0)';
      PINUSE='BI';
    'PT31A':
      PIN_NUMBER='(0,0,G14,0,0,0,0)';
      BIDIRECTIONAL='TRUE';
      INPUT_LOAD='(-0.01,0.01)';
      OUTPUT_LOAD='(1.0,-1.0)';
      PINUSE='BI';
    'PT28B':
      PIN_NUMBER='(0,0,F12,0,0,0,0)';
      BIDIRECTIONAL='TRUE';
      INPUT_LOAD='(-0.01,0.01)';
      OUTPUT_LOAD='(1.0,-1.0)';
      PINUSE='BI';
    'PT28A':
      PIN_NUMBER='(0,0,G12,0,0,0,0)';
      BIDIRECTIONAL='TRUE';
      INPUT_LOAD='(-0.01,0.01)';
      OUTPUT_LOAD='(1.0,-1.0)';
      PINUSE='BI';
    'PT27D||SDA||PCLKC0_0':
      PIN_NUMBER='(0,0,A12,0,0,0,0)';
      BIDIRECTIONAL='TRUE';
      INPUT_LOAD='(-0.01,0.01)';
      OUTPUT_LOAD='(1.0,-1.0)';
      PINUSE='BI';
    'PT27C||SCL||PCLKT0_0':
      PIN_NUMBER='(0,0,B12,0,0,0,0)';
      BIDIRECTIONAL='TRUE';
      INPUT_LOAD='(-0.01,0.01)';
      OUTPUT_LOAD='(1.0,-1.0)';
      PINUSE='BI';
    'PT44B||R_GPLLC':
      PIN_NUMBER='(0,0,B22,0,0,0,0)';
      BIDIRECTIONAL='TRUE';
      INPUT_LOAD='(-0.01,0.01)';
      OUTPUT_LOAD='(1.0,-1.0)';
      PINUSE='BI';
    'PT44A||R_GPLLT':
      PIN_NUMBER='(0,0,A21,0,0,0,0)';
      BIDIRECTIONAL='TRUE';
      INPUT_LOAD='(-0.01,0.01)';
      OUTPUT_LOAD='(1.0,-1.0)';
      PINUSE='BI';
    'PT23B||PCLKC0_1':
      PIN_NUMBER='(0,0,A10,0,0,0,0)';
      BIDIRECTIONAL='TRUE';
      INPUT_LOAD='(-0.01,0.01)';
      OUTPUT_LOAD='(1.0,-1.0)';
      PINUSE='BI';
    'PT23A||PCLKT0_1':
      PIN_NUMBER='(0,0,B10,0,0,0,0)';
      BIDIRECTIONAL='TRUE';
      INPUT_LOAD='(-0.01,0.01)';
      OUTPUT_LOAD='(1.0,-1.0)';
      PINUSE='BI';
    'PT15B':
      PIN_NUMBER='(0,0,D8,0,0,0,0)';
      BIDIRECTIONAL='TRUE';
      INPUT_LOAD='(-0.01,0.01)';
      OUTPUT_LOAD='(1.0,-1.0)';
      PINUSE='BI';
    'PT9D':
      PIN_NUMBER='(0,0,F7,0,0,0,0)';
      BIDIRECTIONAL='TRUE';
      INPUT_LOAD='(-0.01,0.01)';
      OUTPUT_LOAD='(1.0,-1.0)';
      PINUSE='BI';
    'PT9B||L_GPLLC':
      PIN_NUMBER='(0,0,A2,0,0,0,0)';
      BIDIRECTIONAL='TRUE';
      INPUT_LOAD='(-0.01,0.01)';
      OUTPUT_LOAD='(1.0,-1.0)';
      PINUSE='BI';
    'PT9C':
      PIN_NUMBER='(0,0,E6,0,0,0,0)';
      BIDIRECTIONAL='TRUE';
      INPUT_LOAD='(-0.01,0.01)';
      OUTPUT_LOAD='(1.0,-1.0)';
      PINUSE='BI';
    'PT9A||L_GPLLT':
      PIN_NUMBER='(0,0,B1,0,0,0,0)';
      BIDIRECTIONAL='TRUE';
      INPUT_LOAD='(-0.01,0.01)';
      OUTPUT_LOAD='(1.0,-1.0)';
      PINUSE='BI';
    'PT15A':
      PIN_NUMBER='(0,0,C8,0,0,0,0)';
      BIDIRECTIONAL='TRUE';
      INPUT_LOAD='(-0.01,0.01)';
      OUTPUT_LOAD='(1.0,-1.0)';
      PINUSE='BI';
    'PT11A':
      PIN_NUMBER='(0,0,B3,0,0,0,0)';
      BIDIRECTIONAL='TRUE';
      INPUT_LOAD='(-0.01,0.01)';
      OUTPUT_LOAD='(1.0,-1.0)';
      PINUSE='BI';
    'PT11B':
      PIN_NUMBER='(0,0,A4,0,0,0,0)';
      BIDIRECTIONAL='TRUE';
      INPUT_LOAD='(-0.01,0.01)';
      OUTPUT_LOAD='(1.0,-1.0)';
      PINUSE='BI';
    'PT22A':
      PIN_NUMBER='(0,0,F10,0,0,0,0)';
      BIDIRECTIONAL='TRUE';
      INPUT_LOAD='(-0.01,0.01)';
      OUTPUT_LOAD='(1.0,-1.0)';
      PINUSE='BI';
    'PT22B':
      PIN_NUMBER='(0,0,E10,0,0,0,0)';
      BIDIRECTIONAL='TRUE';
      INPUT_LOAD='(-0.01,0.01)';
      OUTPUT_LOAD='(1.0,-1.0)';
      PINUSE='BI';
    'PT11C':
      PIN_NUMBER='(0,0,F8,0,0,0,0)';
      BIDIRECTIONAL='TRUE';
      INPUT_LOAD='(-0.01,0.01)';
      OUTPUT_LOAD='(1.0,-1.0)';
      PINUSE='BI';
    'PT11D':
      PIN_NUMBER='(0,0,G8,0,0,0,0)';
      BIDIRECTIONAL='TRUE';
      INPUT_LOAD='(-0.01,0.01)';
      OUTPUT_LOAD='(1.0,-1.0)';
      PINUSE='BI';
    'PT10A':
      PIN_NUMBER='(0,0,B2,0,0,0,0)';
      BIDIRECTIONAL='TRUE';
      INPUT_LOAD='(-0.01,0.01)';
      OUTPUT_LOAD='(1.0,-1.0)';
      PINUSE='BI';
    'PT10B':
      PIN_NUMBER='(0,0,A3,0,0,0,0)';
      BIDIRECTIONAL='TRUE';
      INPUT_LOAD='(-0.01,0.01)';
      OUTPUT_LOAD='(1.0,-1.0)';
      PINUSE='BI';
    'PT10C':
      PIN_NUMBER='(0,0,C3,0,0,0,0)';
      BIDIRECTIONAL='TRUE';
      INPUT_LOAD='(-0.01,0.01)';
      OUTPUT_LOAD='(1.0,-1.0)';
      PINUSE='BI';
    'PT10D':
      PIN_NUMBER='(0,0,C4,0,0,0,0)';
      BIDIRECTIONAL='TRUE';
      INPUT_LOAD='(-0.01,0.01)';
      OUTPUT_LOAD='(1.0,-1.0)';
      PINUSE='BI';
    'PT12A':
      PIN_NUMBER='(0,0,B4,0,0,0,0)';
      BIDIRECTIONAL='TRUE';
      INPUT_LOAD='(-0.01,0.01)';
      OUTPUT_LOAD='(1.0,-1.0)';
      PINUSE='BI';
    'PT12B':
      PIN_NUMBER='(0,0,A5,0,0,0,0)';
      BIDIRECTIONAL='TRUE';
      INPUT_LOAD='(-0.01,0.01)';
      OUTPUT_LOAD='(1.0,-1.0)';
      PINUSE='BI';
    'PT12C':
      PIN_NUMBER='(0,0,D5,0,0,0,0)';
      BIDIRECTIONAL='TRUE';
      INPUT_LOAD='(-0.01,0.01)';
      OUTPUT_LOAD='(1.0,-1.0)';
      PINUSE='BI';
    'PT12D':
      PIN_NUMBER='(0,0,C5,0,0,0,0)';
      BIDIRECTIONAL='TRUE';
      INPUT_LOAD='(-0.01,0.01)';
      OUTPUT_LOAD='(1.0,-1.0)';
      PINUSE='BI';
    'PT13A':
      PIN_NUMBER='(0,0,B5,0,0,0,0)';
      BIDIRECTIONAL='TRUE';
      INPUT_LOAD='(-0.01,0.01)';
      OUTPUT_LOAD='(1.0,-1.0)';
      PINUSE='BI';
    'PT13B':
      PIN_NUMBER='(0,0,A6,0,0,0,0)';
      BIDIRECTIONAL='TRUE';
      INPUT_LOAD='(-0.01,0.01)';
      OUTPUT_LOAD='(1.0,-1.0)';
      PINUSE='BI';
    'PT13C':
      PIN_NUMBER='(0,0,D6,0,0,0,0)';
      BIDIRECTIONAL='TRUE';
      INPUT_LOAD='(-0.01,0.01)';
      OUTPUT_LOAD='(1.0,-1.0)';
      PINUSE='BI';
    'PT13D':
      PIN_NUMBER='(0,0,E7,0,0,0,0)';
      BIDIRECTIONAL='TRUE';
      INPUT_LOAD='(-0.01,0.01)';
      OUTPUT_LOAD='(1.0,-1.0)';
      PINUSE='BI';
    'PT14A':
      PIN_NUMBER='(0,0,B6,0,0,0,0)';
      BIDIRECTIONAL='TRUE';
      INPUT_LOAD='(-0.01,0.01)';
      OUTPUT_LOAD='(1.0,-1.0)';
      PINUSE='BI';
    'PT14B':
      PIN_NUMBER='(0,0,A7,0,0,0,0)';
      BIDIRECTIONAL='TRUE';
      INPUT_LOAD='(-0.01,0.01)';
      OUTPUT_LOAD='(1.0,-1.0)';
      PINUSE='BI';
    'PT14C':
      PIN_NUMBER='(0,0,C6,0,0,0,0)';
      BIDIRECTIONAL='TRUE';
      INPUT_LOAD='(-0.01,0.01)';
      OUTPUT_LOAD='(1.0,-1.0)';
      PINUSE='BI';
    'PT14D':
      PIN_NUMBER='(0,0,D7,0,0,0,0)';
      BIDIRECTIONAL='TRUE';
      INPUT_LOAD='(-0.01,0.01)';
      OUTPUT_LOAD='(1.0,-1.0)';
      PINUSE='BI';
    'PT20A':
      PIN_NUMBER='(0,0,B8,0,0,0,0)';
      BIDIRECTIONAL='TRUE';
      INPUT_LOAD='(-0.01,0.01)';
      OUTPUT_LOAD='(1.0,-1.0)';
      PINUSE='BI';
    'PT20B':
      PIN_NUMBER='(0,0,A8,0,0,0,0)';
      BIDIRECTIONAL='TRUE';
      INPUT_LOAD='(-0.01,0.01)';
      OUTPUT_LOAD='(1.0,-1.0)';
      PINUSE='BI';
    'PT20C':
      PIN_NUMBER='(0,0,C9,0,0,0,0)';
      BIDIRECTIONAL='TRUE';
      INPUT_LOAD='(-0.01,0.01)';
      OUTPUT_LOAD='(1.0,-1.0)';
      PINUSE='BI';
    'PT20D':
      PIN_NUMBER='(0,0,D9,0,0,0,0)';
      BIDIRECTIONAL='TRUE';
      INPUT_LOAD='(-0.01,0.01)';
      OUTPUT_LOAD='(1.0,-1.0)';
      PINUSE='BI';
    'PT21A':
      PIN_NUMBER='(0,0,B9,0,0,0,0)';
      BIDIRECTIONAL='TRUE';
      INPUT_LOAD='(-0.01,0.01)';
      OUTPUT_LOAD='(1.0,-1.0)';
      PINUSE='BI';
    'PT21B':
      PIN_NUMBER='(0,0,A9,0,0,0,0)';
      BIDIRECTIONAL='TRUE';
      INPUT_LOAD='(-0.01,0.01)';
      OUTPUT_LOAD='(1.0,-1.0)';
      PINUSE='BI';
    'PT21C':
      PIN_NUMBER='(0,0,F9,0,0,0,0)';
      BIDIRECTIONAL='TRUE';
      INPUT_LOAD='(-0.01,0.01)';
      OUTPUT_LOAD='(1.0,-1.0)';
      PINUSE='BI';
    'PT21D':
      PIN_NUMBER='(0,0,G9,0,0,0,0)';
      BIDIRECTIONAL='TRUE';
      INPUT_LOAD='(-0.01,0.01)';
      OUTPUT_LOAD='(1.0,-1.0)';
      PINUSE='BI';
    'PT23C':
      PIN_NUMBER='(0,0,G11,0,0,0,0)';
      BIDIRECTIONAL='TRUE';
      INPUT_LOAD='(-0.01,0.01)';
      OUTPUT_LOAD='(1.0,-1.0)';
      PINUSE='BI';
    'PT23D':
      PIN_NUMBER='(0,0,F11,0,0,0,0)';
      BIDIRECTIONAL='TRUE';
      INPUT_LOAD='(-0.01,0.01)';
      OUTPUT_LOAD='(1.0,-1.0)';
      PINUSE='BI';
    'PT24A':
      PIN_NUMBER='(0,0,B11,0,0,0,0)';
      BIDIRECTIONAL='TRUE';
      INPUT_LOAD='(-0.01,0.01)';
      OUTPUT_LOAD='(1.0,-1.0)';
      PINUSE='BI';
    'PT24B':
      PIN_NUMBER='(0,0,A11,0,0,0,0)';
      BIDIRECTIONAL='TRUE';
      INPUT_LOAD='(-0.01,0.01)';
      OUTPUT_LOAD='(1.0,-1.0)';
      PINUSE='BI';
    'PT24C':
      PIN_NUMBER='(0,0,E11,0,0,0,0)';
      BIDIRECTIONAL='TRUE';
      INPUT_LOAD='(-0.01,0.01)';
      OUTPUT_LOAD='(1.0,-1.0)';
      PINUSE='BI';
    'PT24D':
      PIN_NUMBER='(0,0,D11,0,0,0,0)';
      BIDIRECTIONAL='TRUE';
      INPUT_LOAD='(-0.01,0.01)';
      OUTPUT_LOAD='(1.0,-1.0)';
      PINUSE='BI';
    'PT27A':
      PIN_NUMBER='(0,0,D12,0,0,0,0)';
      BIDIRECTIONAL='TRUE';
      INPUT_LOAD='(-0.01,0.01)';
      OUTPUT_LOAD='(1.0,-1.0)';
      PINUSE='BI';
    'PT27B':
      PIN_NUMBER='(0,0,E12,0,0,0,0)';
      BIDIRECTIONAL='TRUE';
      INPUT_LOAD='(-0.01,0.01)';
      OUTPUT_LOAD='(1.0,-1.0)';
      PINUSE='BI';
    'PT28C':
      PIN_NUMBER='(0,0,E13,0,0,0,0)';
      BIDIRECTIONAL='TRUE';
      INPUT_LOAD='(-0.01,0.01)';
      OUTPUT_LOAD='(1.0,-1.0)';
      PINUSE='BI';
    'PT28D':
      PIN_NUMBER='(0,0,F13,0,0,0,0)';
      BIDIRECTIONAL='TRUE';
      INPUT_LOAD='(-0.01,0.01)';
      OUTPUT_LOAD='(1.0,-1.0)';
      PINUSE='BI';
    'PT29A':
      PIN_NUMBER='(0,0,A13,0,0,0,0)';
      BIDIRECTIONAL='TRUE';
      INPUT_LOAD='(-0.01,0.01)';
      OUTPUT_LOAD='(1.0,-1.0)';
      PINUSE='BI';
    'PT29B':
      PIN_NUMBER='(0,0,B13,0,0,0,0)';
      BIDIRECTIONAL='TRUE';
      INPUT_LOAD='(-0.01,0.01)';
      OUTPUT_LOAD='(1.0,-1.0)';
      PINUSE='BI';
    'PT29C':
      PIN_NUMBER='(0,0,C13,0,0,0,0)';
      BIDIRECTIONAL='TRUE';
      INPUT_LOAD='(-0.01,0.01)';
      OUTPUT_LOAD='(1.0,-1.0)';
      PINUSE='BI';
    'PT29D':
      PIN_NUMBER='(0,0,D13,0,0,0,0)';
      BIDIRECTIONAL='TRUE';
      INPUT_LOAD='(-0.01,0.01)';
      OUTPUT_LOAD='(1.0,-1.0)';
      PINUSE='BI';
    'PT30A':
      PIN_NUMBER='(0,0,A14,0,0,0,0)';
      BIDIRECTIONAL='TRUE';
      INPUT_LOAD='(-0.01,0.01)';
      OUTPUT_LOAD='(1.0,-1.0)';
      PINUSE='BI';
    'PT30B':
      PIN_NUMBER='(0,0,B14,0,0,0,0)';
      BIDIRECTIONAL='TRUE';
      INPUT_LOAD='(-0.01,0.01)';
      OUTPUT_LOAD='(1.0,-1.0)';
      PINUSE='BI';
    'PT30C':
      PIN_NUMBER='(0,0,C14,0,0,0,0)';
      BIDIRECTIONAL='TRUE';
      INPUT_LOAD='(-0.01,0.01)';
      OUTPUT_LOAD='(1.0,-1.0)';
      PINUSE='BI';
    'PT30D':
      PIN_NUMBER='(0,0,D14,0,0,0,0)';
      BIDIRECTIONAL='TRUE';
      INPUT_LOAD='(-0.01,0.01)';
      OUTPUT_LOAD='(1.0,-1.0)';
      PINUSE='BI';
    'PT38A':
      PIN_NUMBER='(0,0,A15,0,0,0,0)';
      BIDIRECTIONAL='TRUE';
      INPUT_LOAD='(-0.01,0.01)';
      OUTPUT_LOAD='(1.0,-1.0)';
      PINUSE='BI';
    'PT38B':
      PIN_NUMBER='(0,0,B15,0,0,0,0)';
      BIDIRECTIONAL='TRUE';
      INPUT_LOAD='(-0.01,0.01)';
      OUTPUT_LOAD='(1.0,-1.0)';
      PINUSE='BI';
    'PT38C':
      PIN_NUMBER='(0,0,C15,0,0,0,0)';
      BIDIRECTIONAL='TRUE';
      INPUT_LOAD='(-0.01,0.01)';
      OUTPUT_LOAD='(1.0,-1.0)';
      PINUSE='BI';
    'PT38D':
      PIN_NUMBER='(0,0,D15,0,0,0,0)';
      BIDIRECTIONAL='TRUE';
      INPUT_LOAD='(-0.01,0.01)';
      OUTPUT_LOAD='(1.0,-1.0)';
      PINUSE='BI';
    'PT39A':
      PIN_NUMBER='(0,0,A16,0,0,0,0)';
      BIDIRECTIONAL='TRUE';
      INPUT_LOAD='(-0.01,0.01)';
      OUTPUT_LOAD='(1.0,-1.0)';
      PINUSE='BI';
    'PT39B':
      PIN_NUMBER='(0,0,B17,0,0,0,0)';
      BIDIRECTIONAL='TRUE';
      INPUT_LOAD='(-0.01,0.01)';
      OUTPUT_LOAD='(1.0,-1.0)';
      PINUSE='BI';
    'PT39C':
      PIN_NUMBER='(0,0,C17,0,0,0,0)';
      BIDIRECTIONAL='TRUE';
      INPUT_LOAD='(-0.01,0.01)';
      OUTPUT_LOAD='(1.0,-1.0)';
      PINUSE='BI';
    'PT39D':
      PIN_NUMBER='(0,0,D16,0,0,0,0)';
      BIDIRECTIONAL='TRUE';
      INPUT_LOAD='(-0.01,0.01)';
      OUTPUT_LOAD='(1.0,-1.0)';
      PINUSE='BI';
    'PT40A':
      PIN_NUMBER='(0,0,A17,0,0,0,0)';
      BIDIRECTIONAL='TRUE';
      INPUT_LOAD='(-0.01,0.01)';
      OUTPUT_LOAD='(1.0,-1.0)';
      PINUSE='BI';
    'PT40B':
      PIN_NUMBER='(0,0,B18,0,0,0,0)';
      BIDIRECTIONAL='TRUE';
      INPUT_LOAD='(-0.01,0.01)';
      OUTPUT_LOAD='(1.0,-1.0)';
      PINUSE='BI';
    'PT40C':
      PIN_NUMBER='(0,0,E16,0,0,0,0)';
      BIDIRECTIONAL='TRUE';
      INPUT_LOAD='(-0.01,0.01)';
      OUTPUT_LOAD='(1.0,-1.0)';
      PINUSE='BI';
    'PT40D':
      PIN_NUMBER='(0,0,D17,0,0,0,0)';
      BIDIRECTIONAL='TRUE';
      INPUT_LOAD='(-0.01,0.01)';
      OUTPUT_LOAD='(1.0,-1.0)';
      PINUSE='BI';
    'PT41C':
      PIN_NUMBER='(0,0,C18,0,0,0,0)';
      BIDIRECTIONAL='TRUE';
      INPUT_LOAD='(-0.01,0.01)';
      OUTPUT_LOAD='(1.0,-1.0)';
      PINUSE='BI';
    'PT41D':
      PIN_NUMBER='(0,0,D18,0,0,0,0)';
      BIDIRECTIONAL='TRUE';
      INPUT_LOAD='(-0.01,0.01)';
      OUTPUT_LOAD='(1.0,-1.0)';
      PINUSE='BI';
    'PT42A':
      PIN_NUMBER='(0,0,A19,0,0,0,0)';
      BIDIRECTIONAL='TRUE';
      INPUT_LOAD='(-0.01,0.01)';
      OUTPUT_LOAD='(1.0,-1.0)';
      PINUSE='BI';
    'PT42B':
      PIN_NUMBER='(0,0,B20,0,0,0,0)';
      BIDIRECTIONAL='TRUE';
      INPUT_LOAD='(-0.01,0.01)';
      OUTPUT_LOAD='(1.0,-1.0)';
      PINUSE='BI';
    'PT42C':
      PIN_NUMBER='(0,0,F15,0,0,0,0)';
      BIDIRECTIONAL='TRUE';
      INPUT_LOAD='(-0.01,0.01)';
      OUTPUT_LOAD='(1.0,-1.0)';
      PINUSE='BI';
    'PT42D':
      PIN_NUMBER='(0,0,G15,0,0,0,0)';
      BIDIRECTIONAL='TRUE';
      INPUT_LOAD='(-0.01,0.01)';
      OUTPUT_LOAD='(1.0,-1.0)';
      PINUSE='BI';
    'PT43C':
      PIN_NUMBER='(0,0,C19,0,0,0,0)';
      BIDIRECTIONAL='TRUE';
      INPUT_LOAD='(-0.01,0.01)';
      OUTPUT_LOAD='(1.0,-1.0)';
      PINUSE='BI';
    'PT43D':
      PIN_NUMBER='(0,0,C20,0,0,0,0)';
      BIDIRECTIONAL='TRUE';
      INPUT_LOAD='(-0.01,0.01)';
      OUTPUT_LOAD='(1.0,-1.0)';
      PINUSE='BI';
    'PT15C||TDO':
      PIN_NUMBER='(0,0,0,E8,0,0,0)';
      BIDIRECTIONAL='TRUE';
      INPUT_LOAD='(-0.01,0.01)';
      OUTPUT_LOAD='(1.0,-1.0)';
      PINUSE='BI';
    'PT15D||TDI':
      PIN_NUMBER='(0,0,0,E9,0,0,0)';
      BIDIRECTIONAL='TRUE';
      INPUT_LOAD='(-0.01,0.01)';
      OUTPUT_LOAD='(1.0,-1.0)';
      PINUSE='BI';
    'PT22C||TCK':
      PIN_NUMBER='(0,0,0,D10,0,0,0)';
      BIDIRECTIONAL='TRUE';
      INPUT_LOAD='(-0.01,0.01)';
      OUTPUT_LOAD='(1.0,-1.0)';
      PINUSE='BI';
    'PT22D||TMS':
      PIN_NUMBER='(0,0,0,C10,0,0,0)';
      BIDIRECTIONAL='TRUE';
      INPUT_LOAD='(-0.01,0.01)';
      OUTPUT_LOAD='(1.0,-1.0)';
      PINUSE='BI';
    'PT31D||PROGRAMN':
      PIN_NUMBER='(0,0,0,E15,0,0,0)';
      BIDIRECTIONAL='TRUE';
      INPUT_LOAD='(-0.01,0.01)';
      OUTPUT_LOAD='(1.0,-1.0)';
      PINUSE='BI';
    'PT44C||INITN':
      PIN_NUMBER='(0,0,0,F16,0,0,0)';
      BIDIRECTIONAL='TRUE';
      INPUT_LOAD='(-0.01,0.01)';
      OUTPUT_LOAD='(1.0,-1.0)';
      PINUSE='BI';
    'PT44D||DONE':
      PIN_NUMBER='(0,0,0,E17,0,0,0)';
      BIDIRECTIONAL='TRUE';
      INPUT_LOAD='(-0.01,0.01)';
      OUTPUT_LOAD='(1.0,-1.0)';
      PINUSE='BI';
    'PT31C||JTAGENB':
      PIN_NUMBER='(0,0,0,E14,0,0,0)';
      BIDIRECTIONAL='TRUE';
      INPUT_LOAD='(-0.01,0.01)';
      OUTPUT_LOAD='(1.0,-1.0)';
      PINUSE='BI';
    'VCC1':
      PIN_NUMBER='(0,0,0,0,K10,0,0)';
      PINUSE='POWER';
      NO_LOAD_CHECK='Both';
      NO_IO_CHECK='Both';
      NO_ASSERT_CHECK='TRUE';
      NO_DIR_CHECK='TRUE';
      ALLOW_CONNECT='TRUE';
    'VCC2':
      PIN_NUMBER='(0,0,0,0,K11,0,0)';
      PINUSE='POWER';
      NO_LOAD_CHECK='Both';
      NO_IO_CHECK='Both';
      NO_ASSERT_CHECK='TRUE';
      NO_DIR_CHECK='TRUE';
      ALLOW_CONNECT='TRUE';
    'VCC3':
      PIN_NUMBER='(0,0,0,0,K12,0,0)';
      PINUSE='POWER';
      NO_LOAD_CHECK='Both';
      NO_IO_CHECK='Both';
      NO_ASSERT_CHECK='TRUE';
      NO_DIR_CHECK='TRUE';
      ALLOW_CONNECT='TRUE';
    'VCC4':
      PIN_NUMBER='(0,0,0,0,K13,0,0)';
      PINUSE='POWER';
      NO_LOAD_CHECK='Both';
      NO_IO_CHECK='Both';
      NO_ASSERT_CHECK='TRUE';
      NO_DIR_CHECK='TRUE';
      ALLOW_CONNECT='TRUE';
    'VCC5':
      PIN_NUMBER='(0,0,0,0,L11,0,0)';
      PINUSE='POWER';
      NO_LOAD_CHECK='Both';
      NO_IO_CHECK='Both';
      NO_ASSERT_CHECK='TRUE';
      NO_DIR_CHECK='TRUE';
      ALLOW_CONNECT='TRUE';
    'VCC6':
      PIN_NUMBER='(0,0,0,0,L12,0,0)';
      PINUSE='POWER';
      NO_LOAD_CHECK='Both';
      NO_IO_CHECK='Both';
      NO_ASSERT_CHECK='TRUE';
      NO_DIR_CHECK='TRUE';
      ALLOW_CONNECT='TRUE';
    'VCC7':
      PIN_NUMBER='(0,0,0,0,M11,0,0)';
      PINUSE='POWER';
      NO_LOAD_CHECK='Both';
      NO_IO_CHECK='Both';
      NO_ASSERT_CHECK='TRUE';
      NO_DIR_CHECK='TRUE';
      ALLOW_CONNECT='TRUE';
    'VCC8':
      PIN_NUMBER='(0,0,0,0,M12,0,0)';
      PINUSE='POWER';
      NO_LOAD_CHECK='Both';
      NO_IO_CHECK='Both';
      NO_ASSERT_CHECK='TRUE';
      NO_DIR_CHECK='TRUE';
      ALLOW_CONNECT='TRUE';
    'VCC9':
      PIN_NUMBER='(0,0,0,0,N10,0,0)';
      PINUSE='POWER';
      NO_LOAD_CHECK='Both';
      NO_IO_CHECK='Both';
      NO_ASSERT_CHECK='TRUE';
      NO_DIR_CHECK='TRUE';
      ALLOW_CONNECT='TRUE';
    'VCC10':
      PIN_NUMBER='(0,0,0,0,N11,0,0)';
      PINUSE='POWER';
      NO_LOAD_CHECK='Both';
      NO_IO_CHECK='Both';
      NO_ASSERT_CHECK='TRUE';
      NO_DIR_CHECK='TRUE';
      ALLOW_CONNECT='TRUE';
    'VCC11':
      PIN_NUMBER='(0,0,0,0,N12,0,0)';
      PINUSE='POWER';
      NO_LOAD_CHECK='Both';
      NO_IO_CHECK='Both';
      NO_ASSERT_CHECK='TRUE';
      NO_DIR_CHECK='TRUE';
      ALLOW_CONNECT='TRUE';
    'VCC12':
      PIN_NUMBER='(0,0,0,0,N13,0,0)';
      PINUSE='POWER';
      NO_LOAD_CHECK='Both';
      NO_IO_CHECK='Both';
      NO_ASSERT_CHECK='TRUE';
      NO_DIR_CHECK='TRUE';
      ALLOW_CONNECT='TRUE';
    'VCCIO5_1':
      PIN_NUMBER='(0,0,0,0,F3,0,0)';
      PINUSE='POWER';
      NO_LOAD_CHECK='Both';
      NO_IO_CHECK='Both';
      NO_ASSERT_CHECK='TRUE';
      NO_DIR_CHECK='TRUE';
      ALLOW_CONNECT='TRUE';
    'VCCIO5_2':
      PIN_NUMBER='(0,0,0,0,J8,0,0)';
      PINUSE='POWER';
      NO_LOAD_CHECK='Both';
      NO_IO_CHECK='Both';
      NO_ASSERT_CHECK='TRUE';
      NO_DIR_CHECK='TRUE';
      ALLOW_CONNECT='TRUE';
    'VCCIO5_3':
      PIN_NUMBER='(0,0,0,0,K8,0,0)';
      PINUSE='POWER';
      NO_LOAD_CHECK='Both';
      NO_IO_CHECK='Both';
      NO_ASSERT_CHECK='TRUE';
      NO_DIR_CHECK='TRUE';
      ALLOW_CONNECT='TRUE';
    'VCCIO4_1':
      PIN_NUMBER='(0,0,0,0,L8,0,0)';
      PINUSE='POWER';
      NO_LOAD_CHECK='Both';
      NO_IO_CHECK='Both';
      NO_ASSERT_CHECK='TRUE';
      NO_DIR_CHECK='TRUE';
      ALLOW_CONNECT='TRUE';
    'VCCIO4_2':
      PIN_NUMBER='(0,0,0,0,M8,0,0)';
      PINUSE='POWER';
      NO_LOAD_CHECK='Both';
      NO_IO_CHECK='Both';
      NO_ASSERT_CHECK='TRUE';
      NO_DIR_CHECK='TRUE';
      ALLOW_CONNECT='TRUE';
    'VCCIO4_3':
      PIN_NUMBER='(0,0,0,0,M3,0,0)';
      PINUSE='POWER';
      NO_LOAD_CHECK='Both';
      NO_IO_CHECK='Both';
      NO_ASSERT_CHECK='TRUE';
      NO_DIR_CHECK='TRUE';
      ALLOW_CONNECT='TRUE';
    'VCCIO3_1':
      PIN_NUMBER='(0,0,0,0,N8,0,0)';
      PINUSE='POWER';
      NO_LOAD_CHECK='Both';
      NO_IO_CHECK='Both';
      NO_ASSERT_CHECK='TRUE';
      NO_DIR_CHECK='TRUE';
      ALLOW_CONNECT='TRUE';
    'VCCIO3_2':
      PIN_NUMBER='(0,0,0,0,P8,0,0)';
      PINUSE='POWER';
      NO_LOAD_CHECK='Both';
      NO_IO_CHECK='Both';
      NO_ASSERT_CHECK='TRUE';
      NO_DIR_CHECK='TRUE';
      ALLOW_CONNECT='TRUE';
    'VCCIO3_3':
      PIN_NUMBER='(0,0,0,0,V3,0,0)';
      PINUSE='POWER';
      NO_LOAD_CHECK='Both';
      NO_IO_CHECK='Both';
      NO_ASSERT_CHECK='TRUE';
      NO_DIR_CHECK='TRUE';
      ALLOW_CONNECT='TRUE';
    'VCCIO2_1':
      PIN_NUMBER='(0,0,0,0,R9,0,0)';
      PINUSE='POWER';
      NO_LOAD_CHECK='Both';
      NO_IO_CHECK='Both';
      NO_ASSERT_CHECK='TRUE';
      NO_DIR_CHECK='TRUE';
      ALLOW_CONNECT='TRUE';
    'VCCIO2_2':
      PIN_NUMBER='(0,0,0,0,R10,0,0)';
      PINUSE='POWER';
      NO_LOAD_CHECK='Both';
      NO_IO_CHECK='Both';
      NO_ASSERT_CHECK='TRUE';
      NO_DIR_CHECK='TRUE';
      ALLOW_CONNECT='TRUE';
    'VCCIO2_3':
      PIN_NUMBER='(0,0,0,0,R11,0,0)';
      PINUSE='POWER';
      NO_LOAD_CHECK='Both';
      NO_IO_CHECK='Both';
      NO_ASSERT_CHECK='TRUE';
      NO_DIR_CHECK='TRUE';
      ALLOW_CONNECT='TRUE';
    'VCCIO2_4':
      PIN_NUMBER='(0,0,0,0,R12,0,0)';
      PINUSE='POWER';
      NO_LOAD_CHECK='Both';
      NO_IO_CHECK='Both';
      NO_ASSERT_CHECK='TRUE';
      NO_DIR_CHECK='TRUE';
      ALLOW_CONNECT='TRUE';
    'VCCIO2_5':
      PIN_NUMBER='(0,0,0,0,R13,0,0)';
      PINUSE='POWER';
      NO_LOAD_CHECK='Both';
      NO_IO_CHECK='Both';
      NO_ASSERT_CHECK='TRUE';
      NO_DIR_CHECK='TRUE';
      ALLOW_CONNECT='TRUE';
    'VCCIO2_6':
      PIN_NUMBER='(0,0,0,0,R14,0,0)';
      PINUSE='POWER';
      NO_LOAD_CHECK='Both';
      NO_IO_CHECK='Both';
      NO_ASSERT_CHECK='TRUE';
      NO_DIR_CHECK='TRUE';
      ALLOW_CONNECT='TRUE';
    'VCCIO2_7':
      PIN_NUMBER='(0,0,0,0,W7,0,0)';
      PINUSE='POWER';
      NO_LOAD_CHECK='Both';
      NO_IO_CHECK='Both';
      NO_ASSERT_CHECK='TRUE';
      NO_DIR_CHECK='TRUE';
      ALLOW_CONNECT='TRUE';
    'VCCIO2_8':
      PIN_NUMBER='(0,0,0,0,W11,0,0)';
      PINUSE='POWER';
      NO_LOAD_CHECK='Both';
      NO_IO_CHECK='Both';
      NO_ASSERT_CHECK='TRUE';
      NO_DIR_CHECK='TRUE';
      ALLOW_CONNECT='TRUE';
    'VCCIO2_9':
      PIN_NUMBER='(0,0,0,0,W16,0,0)';
      PINUSE='POWER';
      NO_LOAD_CHECK='Both';
      NO_IO_CHECK='Both';
      NO_ASSERT_CHECK='TRUE';
      NO_DIR_CHECK='TRUE';
      ALLOW_CONNECT='TRUE';
    'VCCIO1_1':
      PIN_NUMBER='(0,0,0,0,F20,0,0)';
      PINUSE='POWER';
      NO_LOAD_CHECK='Both';
      NO_IO_CHECK='Both';
      NO_ASSERT_CHECK='TRUE';
      NO_DIR_CHECK='TRUE';
      ALLOW_CONNECT='TRUE';
    'VCCIO1_2':
      PIN_NUMBER='(0,0,0,0,J15,0,0)';
      PINUSE='POWER';
      NO_LOAD_CHECK='Both';
      NO_IO_CHECK='Both';
      NO_ASSERT_CHECK='TRUE';
      NO_DIR_CHECK='TRUE';
      ALLOW_CONNECT='TRUE';
    'VCCIO1_3':
      PIN_NUMBER='(0,0,0,0,K15,0,0)';
      PINUSE='POWER';
      NO_LOAD_CHECK='Both';
      NO_IO_CHECK='Both';
      NO_ASSERT_CHECK='TRUE';
      NO_DIR_CHECK='TRUE';
      ALLOW_CONNECT='TRUE';
    'VCCIO1_4':
      PIN_NUMBER='(0,0,0,0,L15,0,0)';
      PINUSE='POWER';
      NO_LOAD_CHECK='Both';
      NO_IO_CHECK='Both';
      NO_ASSERT_CHECK='TRUE';
      NO_DIR_CHECK='TRUE';
      ALLOW_CONNECT='TRUE';
    'VCCIO1_5':
      PIN_NUMBER='(0,0,0,0,M15,0,0)';
      PINUSE='POWER';
      NO_LOAD_CHECK='Both';
      NO_IO_CHECK='Both';
      NO_ASSERT_CHECK='TRUE';
      NO_DIR_CHECK='TRUE';
      ALLOW_CONNECT='TRUE';
    'VCCIO1_6':
      PIN_NUMBER='(0,0,0,0,M18,0,0)';
      PINUSE='POWER';
      NO_LOAD_CHECK='Both';
      NO_IO_CHECK='Both';
      NO_ASSERT_CHECK='TRUE';
      NO_DIR_CHECK='TRUE';
      ALLOW_CONNECT='TRUE';
    'VCCIO1_7':
      PIN_NUMBER='(0,0,0,0,N15,0,0)';
      PINUSE='POWER';
      NO_LOAD_CHECK='Both';
      NO_IO_CHECK='Both';
      NO_ASSERT_CHECK='TRUE';
      NO_DIR_CHECK='TRUE';
      ALLOW_CONNECT='TRUE';
    'VCCIO1_8':
      PIN_NUMBER='(0,0,0,0,P15,0,0)';
      PINUSE='POWER';
      NO_LOAD_CHECK='Both';
      NO_IO_CHECK='Both';
      NO_ASSERT_CHECK='TRUE';
      NO_DIR_CHECK='TRUE';
      ALLOW_CONNECT='TRUE';
    'VCCIO1_9':
      PIN_NUMBER='(0,0,0,0,V20,0,0)';
      PINUSE='POWER';
      NO_LOAD_CHECK='Both';
      NO_IO_CHECK='Both';
      NO_ASSERT_CHECK='TRUE';
      NO_DIR_CHECK='TRUE';
      ALLOW_CONNECT='TRUE';
    'VCCIO0_1':
      PIN_NUMBER='(0,0,0,0,C7,0,0)';
      PINUSE='POWER';
      NO_LOAD_CHECK='Both';
      NO_IO_CHECK='Both';
      NO_ASSERT_CHECK='TRUE';
      NO_DIR_CHECK='TRUE';
      ALLOW_CONNECT='TRUE';
    'VCCIO0_2':
      PIN_NUMBER='(0,0,0,0,C12,0,0)';
      PINUSE='POWER';
      NO_LOAD_CHECK='Both';
      NO_IO_CHECK='Both';
      NO_ASSERT_CHECK='TRUE';
      NO_DIR_CHECK='TRUE';
      ALLOW_CONNECT='TRUE';
    'VCCIO0_3':
      PIN_NUMBER='(0,0,0,0,C16,0,0)';
      PINUSE='POWER';
      NO_LOAD_CHECK='Both';
      NO_IO_CHECK='Both';
      NO_ASSERT_CHECK='TRUE';
      NO_DIR_CHECK='TRUE';
      ALLOW_CONNECT='TRUE';
    'VCCIO0_4':
      PIN_NUMBER='(0,0,0,0,G10,0,0)';
      PINUSE='POWER';
      NO_LOAD_CHECK='Both';
      NO_IO_CHECK='Both';
      NO_ASSERT_CHECK='TRUE';
      NO_DIR_CHECK='TRUE';
      ALLOW_CONNECT='TRUE';
    'VCCIO0_7':
      PIN_NUMBER='(0,0,0,0,H11,0,0)';
      PINUSE='POWER';
      NO_LOAD_CHECK='Both';
      NO_IO_CHECK='Both';
      NO_ASSERT_CHECK='TRUE';
      NO_DIR_CHECK='TRUE';
      ALLOW_CONNECT='TRUE';
    'VCCIO0_8':
      PIN_NUMBER='(0,0,0,0,H12,0,0)';
      PINUSE='POWER';
      NO_LOAD_CHECK='Both';
      NO_IO_CHECK='Both';
      NO_ASSERT_CHECK='TRUE';
      NO_DIR_CHECK='TRUE';
      ALLOW_CONNECT='TRUE';
    'VCCIO0_9':
      PIN_NUMBER='(0,0,0,0,H14,0,0)';
      PINUSE='POWER';
      NO_LOAD_CHECK='Both';
      NO_IO_CHECK='Both';
      NO_ASSERT_CHECK='TRUE';
      NO_DIR_CHECK='TRUE';
      ALLOW_CONNECT='TRUE';
    'VCCIO0_6':
      PIN_NUMBER='(0,0,0,0,H9,0,0)';
      PINUSE='POWER';
      NO_LOAD_CHECK='Both';
      NO_IO_CHECK='Both';
      NO_ASSERT_CHECK='TRUE';
      NO_DIR_CHECK='TRUE';
      ALLOW_CONNECT='TRUE';
    'VCCIO0_5':
      PIN_NUMBER='(0,0,0,0,G13,0,0)';
      PINUSE='POWER';
      NO_LOAD_CHECK='Both';
      NO_IO_CHECK='Both';
      NO_ASSERT_CHECK='TRUE';
      NO_DIR_CHECK='TRUE';
      ALLOW_CONNECT='TRUE';
    'GND1':
      PIN_NUMBER='(0,0,0,0,0,A1,0)';
      PINUSE='POWER';
      NO_LOAD_CHECK='Both';
      NO_IO_CHECK='Both';
      NO_ASSERT_CHECK='TRUE';
      NO_DIR_CHECK='TRUE';
      ALLOW_CONNECT='TRUE';
    'GND2':
      PIN_NUMBER='(0,0,0,0,0,A22,0)';
      PINUSE='POWER';
      NO_LOAD_CHECK='Both';
      NO_IO_CHECK='Both';
      NO_ASSERT_CHECK='TRUE';
      NO_DIR_CHECK='TRUE';
      ALLOW_CONNECT='TRUE';
    'GND3':
      PIN_NUMBER='(0,0,0,0,0,B7,0)';
      PINUSE='POWER';
      NO_LOAD_CHECK='Both';
      NO_IO_CHECK='Both';
      NO_ASSERT_CHECK='TRUE';
      NO_DIR_CHECK='TRUE';
      ALLOW_CONNECT='TRUE';
    'GND4':
      PIN_NUMBER='(0,0,0,0,0,B16,0)';
      PINUSE='POWER';
      NO_LOAD_CHECK='Both';
      NO_IO_CHECK='Both';
      NO_ASSERT_CHECK='TRUE';
      NO_DIR_CHECK='TRUE';
      ALLOW_CONNECT='TRUE';
    'GND5':
      PIN_NUMBER='(0,0,0,0,0,C2,0)';
      PINUSE='POWER';
      NO_LOAD_CHECK='Both';
      NO_IO_CHECK='Both';
      NO_ASSERT_CHECK='TRUE';
      NO_DIR_CHECK='TRUE';
      ALLOW_CONNECT='TRUE';
    'GND6':
      PIN_NUMBER='(0,0,0,0,0,C11,0)';
      PINUSE='POWER';
      NO_LOAD_CHECK='Both';
      NO_IO_CHECK='Both';
      NO_ASSERT_CHECK='TRUE';
      NO_DIR_CHECK='TRUE';
      ALLOW_CONNECT='TRUE';
    'GND7':
      PIN_NUMBER='(0,0,0,0,0,E5,0)';
      PINUSE='POWER';
      NO_LOAD_CHECK='Both';
      NO_IO_CHECK='Both';
      NO_ASSERT_CHECK='TRUE';
      NO_DIR_CHECK='TRUE';
      ALLOW_CONNECT='TRUE';
    'GND8':
      PIN_NUMBER='(0,0,0,0,0,E18,0)';
      PINUSE='POWER';
      NO_LOAD_CHECK='Both';
      NO_IO_CHECK='Both';
      NO_ASSERT_CHECK='TRUE';
      NO_DIR_CHECK='TRUE';
      ALLOW_CONNECT='TRUE';
    'GND9':
      PIN_NUMBER='(0,0,0,0,0,F2,0)';
      PINUSE='POWER';
      NO_LOAD_CHECK='Both';
      NO_IO_CHECK='Both';
      NO_ASSERT_CHECK='TRUE';
      NO_DIR_CHECK='TRUE';
      ALLOW_CONNECT='TRUE';
    'GND10':
      PIN_NUMBER='(0,0,0,0,0,F21,0)';
      PINUSE='POWER';
      NO_LOAD_CHECK='Both';
      NO_IO_CHECK='Both';
      NO_ASSERT_CHECK='TRUE';
      NO_DIR_CHECK='TRUE';
      ALLOW_CONNECT='TRUE';
    'GND11':
      PIN_NUMBER='(0,0,0,0,0,H8,0)';
      PINUSE='POWER';
      NO_LOAD_CHECK='Both';
      NO_IO_CHECK='Both';
      NO_ASSERT_CHECK='TRUE';
      NO_DIR_CHECK='TRUE';
      ALLOW_CONNECT='TRUE';
    'GND12':
      PIN_NUMBER='(0,0,0,0,0,H10,0)';
      PINUSE='POWER';
      NO_LOAD_CHECK='Both';
      NO_IO_CHECK='Both';
      NO_ASSERT_CHECK='TRUE';
      NO_DIR_CHECK='TRUE';
      ALLOW_CONNECT='TRUE';
    'GND13':
      PIN_NUMBER='(0,0,0,0,0,H13,0)';
      PINUSE='POWER';
      NO_LOAD_CHECK='Both';
      NO_IO_CHECK='Both';
      NO_ASSERT_CHECK='TRUE';
      NO_DIR_CHECK='TRUE';
      ALLOW_CONNECT='TRUE';
    'GND14':
      PIN_NUMBER='(0,0,0,0,0,H15,0)';
      PINUSE='POWER';
      NO_LOAD_CHECK='Both';
      NO_IO_CHECK='Both';
      NO_ASSERT_CHECK='TRUE';
      NO_DIR_CHECK='TRUE';
      ALLOW_CONNECT='TRUE';
    'GND15':
      PIN_NUMBER='(0,0,0,0,0,J9,0)';
      PINUSE='POWER';
      NO_LOAD_CHECK='Both';
      NO_IO_CHECK='Both';
      NO_ASSERT_CHECK='TRUE';
      NO_DIR_CHECK='TRUE';
      ALLOW_CONNECT='TRUE';
    'GND16':
      PIN_NUMBER='(0,0,0,0,0,J10,0)';
      PINUSE='POWER';
      NO_LOAD_CHECK='Both';
      NO_IO_CHECK='Both';
      NO_ASSERT_CHECK='TRUE';
      NO_DIR_CHECK='TRUE';
      ALLOW_CONNECT='TRUE';
    'GND17':
      PIN_NUMBER='(0,0,0,0,0,J11,0)';
      PINUSE='POWER';
      NO_LOAD_CHECK='Both';
      NO_IO_CHECK='Both';
      NO_ASSERT_CHECK='TRUE';
      NO_DIR_CHECK='TRUE';
      ALLOW_CONNECT='TRUE';
    'GND18':
      PIN_NUMBER='(0,0,0,0,0,J12,0)';
      PINUSE='POWER';
      NO_LOAD_CHECK='Both';
      NO_IO_CHECK='Both';
      NO_ASSERT_CHECK='TRUE';
      NO_DIR_CHECK='TRUE';
      ALLOW_CONNECT='TRUE';
    'GND19':
      PIN_NUMBER='(0,0,0,0,0,J13,0)';
      PINUSE='POWER';
      NO_LOAD_CHECK='Both';
      NO_IO_CHECK='Both';
      NO_ASSERT_CHECK='TRUE';
      NO_DIR_CHECK='TRUE';
      ALLOW_CONNECT='TRUE';
    'GND20':
      PIN_NUMBER='(0,0,0,0,0,J14,0)';
      PINUSE='POWER';
      NO_LOAD_CHECK='Both';
      NO_IO_CHECK='Both';
      NO_ASSERT_CHECK='TRUE';
      NO_DIR_CHECK='TRUE';
      ALLOW_CONNECT='TRUE';
    'GND21':
      PIN_NUMBER='(0,0,0,0,0,K9,0)';
      PINUSE='POWER';
      NO_LOAD_CHECK='Both';
      NO_IO_CHECK='Both';
      NO_ASSERT_CHECK='TRUE';
      NO_DIR_CHECK='TRUE';
      ALLOW_CONNECT='TRUE';
    'GND22':
      PIN_NUMBER='(0,0,0,0,0,K14,0)';
      PINUSE='POWER';
      NO_LOAD_CHECK='Both';
      NO_IO_CHECK='Both';
      NO_ASSERT_CHECK='TRUE';
      NO_DIR_CHECK='TRUE';
      ALLOW_CONNECT='TRUE';
    'GND23':
      PIN_NUMBER='(0,0,0,0,0,K21,0)';
      PINUSE='POWER';
      NO_LOAD_CHECK='Both';
      NO_IO_CHECK='Both';
      NO_ASSERT_CHECK='TRUE';
      NO_DIR_CHECK='TRUE';
      ALLOW_CONNECT='TRUE';
    'GND24':
      PIN_NUMBER='(0,0,0,0,0,L2,0)';
      PINUSE='POWER';
      NO_LOAD_CHECK='Both';
      NO_IO_CHECK='Both';
      NO_ASSERT_CHECK='TRUE';
      NO_DIR_CHECK='TRUE';
      ALLOW_CONNECT='TRUE';
    'GND25':
      PIN_NUMBER='(0,0,0,0,0,L9,0)';
      PINUSE='POWER';
      NO_LOAD_CHECK='Both';
      NO_IO_CHECK='Both';
      NO_ASSERT_CHECK='TRUE';
      NO_DIR_CHECK='TRUE';
      ALLOW_CONNECT='TRUE';
    'GND26':
      PIN_NUMBER='(0,0,0,0,0,L10,0)';
      PINUSE='POWER';
      NO_LOAD_CHECK='Both';
      NO_IO_CHECK='Both';
      NO_ASSERT_CHECK='TRUE';
      NO_DIR_CHECK='TRUE';
      ALLOW_CONNECT='TRUE';
    'GND27':
      PIN_NUMBER='(0,0,0,0,0,L13,0)';
      PINUSE='POWER';
      NO_LOAD_CHECK='Both';
      NO_IO_CHECK='Both';
      NO_ASSERT_CHECK='TRUE';
      NO_DIR_CHECK='TRUE';
      ALLOW_CONNECT='TRUE';
    'GND28':
      PIN_NUMBER='(0,0,0,0,0,L14,0)';
      PINUSE='POWER';
      NO_LOAD_CHECK='Both';
      NO_IO_CHECK='Both';
      NO_ASSERT_CHECK='TRUE';
      NO_DIR_CHECK='TRUE';
      ALLOW_CONNECT='TRUE';
    'GND29':
      PIN_NUMBER='(0,0,0,0,0,L18,0)';
      PINUSE='POWER';
      NO_LOAD_CHECK='Both';
      NO_IO_CHECK='Both';
      NO_ASSERT_CHECK='TRUE';
      NO_DIR_CHECK='TRUE';
      ALLOW_CONNECT='TRUE';
    'GND30':
      PIN_NUMBER='(0,0,0,0,0,M4,0)';
      PINUSE='POWER';
      NO_LOAD_CHECK='Both';
      NO_IO_CHECK='Both';
      NO_ASSERT_CHECK='TRUE';
      NO_DIR_CHECK='TRUE';
      ALLOW_CONNECT='TRUE';
    'GND31':
      PIN_NUMBER='(0,0,0,0,0,M9,0)';
      PINUSE='POWER';
      NO_LOAD_CHECK='Both';
      NO_IO_CHECK='Both';
      NO_ASSERT_CHECK='TRUE';
      NO_DIR_CHECK='TRUE';
      ALLOW_CONNECT='TRUE';
    'GND32':
      PIN_NUMBER='(0,0,0,0,0,M10,0)';
      PINUSE='POWER';
      NO_LOAD_CHECK='Both';
      NO_IO_CHECK='Both';
      NO_ASSERT_CHECK='TRUE';
      NO_DIR_CHECK='TRUE';
      ALLOW_CONNECT='TRUE';
    'GND33':
      PIN_NUMBER='(0,0,0,0,0,M13,0)';
      PINUSE='POWER';
      NO_LOAD_CHECK='Both';
      NO_IO_CHECK='Both';
      NO_ASSERT_CHECK='TRUE';
      NO_DIR_CHECK='TRUE';
      ALLOW_CONNECT='TRUE';
    'GND34':
      PIN_NUMBER='(0,0,0,0,0,M14,0)';
      PINUSE='POWER';
      NO_LOAD_CHECK='Both';
      NO_IO_CHECK='Both';
      NO_ASSERT_CHECK='TRUE';
      NO_DIR_CHECK='TRUE';
      ALLOW_CONNECT='TRUE';
    'GND35':
      PIN_NUMBER='(0,0,0,0,0,N9,0)';
      PINUSE='POWER';
      NO_LOAD_CHECK='Both';
      NO_IO_CHECK='Both';
      NO_ASSERT_CHECK='TRUE';
      NO_DIR_CHECK='TRUE';
      ALLOW_CONNECT='TRUE';
    'GND36':
      PIN_NUMBER='(0,0,0,0,0,N14,0)';
      PINUSE='POWER';
      NO_LOAD_CHECK='Both';
      NO_IO_CHECK='Both';
      NO_ASSERT_CHECK='TRUE';
      NO_DIR_CHECK='TRUE';
      ALLOW_CONNECT='TRUE';
    'GND37':
      PIN_NUMBER='(0,0,0,0,0,N21,0)';
      PINUSE='POWER';
      NO_LOAD_CHECK='Both';
      NO_IO_CHECK='Both';
      NO_ASSERT_CHECK='TRUE';
      NO_DIR_CHECK='TRUE';
      ALLOW_CONNECT='TRUE';
    'GND38':
      PIN_NUMBER='(0,0,0,0,0,P9,0)';
      PINUSE='POWER';
      NO_LOAD_CHECK='Both';
      NO_IO_CHECK='Both';
      NO_ASSERT_CHECK='TRUE';
      NO_DIR_CHECK='TRUE';
      ALLOW_CONNECT='TRUE';
    'GND39':
      PIN_NUMBER='(0,0,0,0,0,P10,0)';
      PINUSE='POWER';
      NO_LOAD_CHECK='Both';
      NO_IO_CHECK='Both';
      NO_ASSERT_CHECK='TRUE';
      NO_DIR_CHECK='TRUE';
      ALLOW_CONNECT='TRUE';
    'GND40':
      PIN_NUMBER='(0,0,0,0,0,P11,0)';
      PINUSE='POWER';
      NO_LOAD_CHECK='Both';
      NO_IO_CHECK='Both';
      NO_ASSERT_CHECK='TRUE';
      NO_DIR_CHECK='TRUE';
      ALLOW_CONNECT='TRUE';
    'GND41':
      PIN_NUMBER='(0,0,0,0,0,P12,0)';
      PINUSE='POWER';
      NO_LOAD_CHECK='Both';
      NO_IO_CHECK='Both';
      NO_ASSERT_CHECK='TRUE';
      NO_DIR_CHECK='TRUE';
      ALLOW_CONNECT='TRUE';
    'GND42':
      PIN_NUMBER='(0,0,0,0,0,P13,0)';
      PINUSE='POWER';
      NO_LOAD_CHECK='Both';
      NO_IO_CHECK='Both';
      NO_ASSERT_CHECK='TRUE';
      NO_DIR_CHECK='TRUE';
      ALLOW_CONNECT='TRUE';
    'GND43':
      PIN_NUMBER='(0,0,0,0,0,P14,0)';
      PINUSE='POWER';
      NO_LOAD_CHECK='Both';
      NO_IO_CHECK='Both';
      NO_ASSERT_CHECK='TRUE';
      NO_DIR_CHECK='TRUE';
      ALLOW_CONNECT='TRUE';
    'GND44':
      PIN_NUMBER='(0,0,0,0,0,R8,0)';
      PINUSE='POWER';
      NO_LOAD_CHECK='Both';
      NO_IO_CHECK='Both';
      NO_ASSERT_CHECK='TRUE';
      NO_DIR_CHECK='TRUE';
      ALLOW_CONNECT='TRUE';
    'GND45':
      PIN_NUMBER='(0,0,0,0,0,R15,0)';
      PINUSE='POWER';
      NO_LOAD_CHECK='Both';
      NO_IO_CHECK='Both';
      NO_ASSERT_CHECK='TRUE';
      NO_DIR_CHECK='TRUE';
      ALLOW_CONNECT='TRUE';
    'GND46':
      PIN_NUMBER='(0,0,0,0,0,V2,0)';
      PINUSE='POWER';
      NO_LOAD_CHECK='Both';
      NO_IO_CHECK='Both';
      NO_ASSERT_CHECK='TRUE';
      NO_DIR_CHECK='TRUE';
      ALLOW_CONNECT='TRUE';
    'GND47':
      PIN_NUMBER='(0,0,0,0,0,V21,0)';
      PINUSE='POWER';
      NO_LOAD_CHECK='Both';
      NO_IO_CHECK='Both';
      NO_ASSERT_CHECK='TRUE';
      NO_DIR_CHECK='TRUE';
      ALLOW_CONNECT='TRUE';
    'GND48':
      PIN_NUMBER='(0,0,0,0,0,W12,0)';
      PINUSE='POWER';
      NO_LOAD_CHECK='Both';
      NO_IO_CHECK='Both';
      NO_ASSERT_CHECK='TRUE';
      NO_DIR_CHECK='TRUE';
      ALLOW_CONNECT='TRUE';
    'GND50':
      PIN_NUMBER='(0,0,0,0,0,Y16,0)';
      PINUSE='POWER';
      NO_LOAD_CHECK='Both';
      NO_IO_CHECK='Both';
      NO_ASSERT_CHECK='TRUE';
      NO_DIR_CHECK='TRUE';
      ALLOW_CONNECT='TRUE';
    'GND49':
      PIN_NUMBER='(0,0,0,0,0,Y7,0)';
      PINUSE='POWER';
      NO_LOAD_CHECK='Both';
      NO_IO_CHECK='Both';
      NO_ASSERT_CHECK='TRUE';
      NO_DIR_CHECK='TRUE';
      ALLOW_CONNECT='TRUE';
    'GND51':
      PIN_NUMBER='(0,0,0,0,0,AB1,0)';
      PINUSE='POWER';
      NO_LOAD_CHECK='Both';
      NO_IO_CHECK='Both';
      NO_ASSERT_CHECK='TRUE';
      NO_DIR_CHECK='TRUE';
      ALLOW_CONNECT='TRUE';
    'GND52':
      PIN_NUMBER='(0,0,0,0,0,AB22,0)';
      PINUSE='POWER';
      NO_LOAD_CHECK='Both';
      NO_IO_CHECK='Both';
      NO_ASSERT_CHECK='TRUE';
      NO_DIR_CHECK='TRUE';
      ALLOW_CONNECT='TRUE';
    'PR30B':
      PIN_NUMBER='(0,0,0,0,0,0,W20)';
      BIDIRECTIONAL='TRUE';
      INPUT_LOAD='(-0.01,0.01)';
      OUTPUT_LOAD='(1.0,-1.0)';
      PINUSE='BI';
    'PR30A':
      PIN_NUMBER='(0,0,0,0,0,0,V18)';
      BIDIRECTIONAL='TRUE';
      INPUT_LOAD='(-0.01,0.01)';
      OUTPUT_LOAD='(1.0,-1.0)';
      PINUSE='BI';
    'PR29D':
      PIN_NUMBER='(0,0,0,0,0,0,V19)';
      BIDIRECTIONAL='TRUE';
      INPUT_LOAD='(-0.01,0.01)';
      OUTPUT_LOAD='(1.0,-1.0)';
      PINUSE='BI';
    'PR29B':
      PIN_NUMBER='(0,0,0,0,0,0,Y21)';
      BIDIRECTIONAL='TRUE';
      INPUT_LOAD='(-0.01,0.01)';
      OUTPUT_LOAD='(1.0,-1.0)';
      PINUSE='BI';
    'PR29C':
      PIN_NUMBER='(0,0,0,0,0,0,U17)';
      BIDIRECTIONAL='TRUE';
      INPUT_LOAD='(-0.01,0.01)';
      OUTPUT_LOAD='(1.0,-1.0)';
      PINUSE='BI';
    'PR29A':
      PIN_NUMBER='(0,0,0,0,0,0,AA22)';
      BIDIRECTIONAL='TRUE';
      INPUT_LOAD='(-0.01,0.01)';
      OUTPUT_LOAD='(1.0,-1.0)';
      PINUSE='BI';
    'PR25B':
      PIN_NUMBER='(0,0,0,0,0,0,W22)';
      BIDIRECTIONAL='TRUE';
      INPUT_LOAD='(-0.01,0.01)';
      OUTPUT_LOAD='(1.0,-1.0)';
      PINUSE='BI';
    'PR25A':
      PIN_NUMBER='(0,0,0,0,0,0,V22)';
      BIDIRECTIONAL='TRUE';
      INPUT_LOAD='(-0.01,0.01)';
      OUTPUT_LOAD='(1.0,-1.0)';
      PINUSE='BI';
    'PR20B':
      PIN_NUMBER='(0,0,0,0,0,0,R21)';
      BIDIRECTIONAL='TRUE';
      INPUT_LOAD='(-0.01,0.01)';
      OUTPUT_LOAD='(1.0,-1.0)';
      PINUSE='BI';
    'PR20A':
      PIN_NUMBER='(0,0,0,0,0,0,R22)';
      BIDIRECTIONAL='TRUE';
      INPUT_LOAD='(-0.01,0.01)';
      OUTPUT_LOAD='(1.0,-1.0)';
      PINUSE='BI';
    'PR19B':
      PIN_NUMBER='(0,0,0,0,0,0,P21)';
      BIDIRECTIONAL='TRUE';
      INPUT_LOAD='(-0.01,0.01)';
      OUTPUT_LOAD='(1.0,-1.0)';
      PINUSE='BI';
    'PR19A':
      PIN_NUMBER='(0,0,0,0,0,0,N22)';
      BIDIRECTIONAL='TRUE';
      INPUT_LOAD='(-0.01,0.01)';
      OUTPUT_LOAD='(1.0,-1.0)';
      PINUSE='BI';
    'PR17B||PCLKC1_0':
      PIN_NUMBER='(0,0,0,0,0,0,M21)';
      BIDIRECTIONAL='TRUE';
      INPUT_LOAD='(-0.01,0.01)';
      OUTPUT_LOAD='(1.0,-1.0)';
      PINUSE='BI';
    'PR17A||PCLKT1_0':
      PIN_NUMBER='(0,0,0,0,0,0,M22)';
      BIDIRECTIONAL='TRUE';
      INPUT_LOAD='(-0.01,0.01)';
      OUTPUT_LOAD='(1.0,-1.0)';
      PINUSE='BI';
    'PR16B':
      PIN_NUMBER='(0,0,0,0,0,0,L21)';
      BIDIRECTIONAL='TRUE';
      INPUT_LOAD='(-0.01,0.01)';
      OUTPUT_LOAD='(1.0,-1.0)';
      PINUSE='BI';
    'PR16A':
      PIN_NUMBER='(0,0,0,0,0,0,K22)';
      BIDIRECTIONAL='TRUE';
      INPUT_LOAD='(-0.01,0.01)';
      OUTPUT_LOAD='(1.0,-1.0)';
      PINUSE='BI';
    'PR14B':
      PIN_NUMBER='(0,0,0,0,0,0,L16)';
      BIDIRECTIONAL='TRUE';
      INPUT_LOAD='(-0.01,0.01)';
      OUTPUT_LOAD='(1.0,-1.0)';
      PINUSE='BI';
    'PR14A':
      PIN_NUMBER='(0,0,0,0,0,0,L17)';
      BIDIRECTIONAL='TRUE';
      INPUT_LOAD='(-0.01,0.01)';
      OUTPUT_LOAD='(1.0,-1.0)';
      PINUSE='BI';
    'PR7B':
      PIN_NUMBER='(0,0,0,0,0,0,H21)';
      BIDIRECTIONAL='TRUE';
      INPUT_LOAD='(-0.01,0.01)';
      OUTPUT_LOAD='(1.0,-1.0)';
      PINUSE='BI';
    'PR7A':
      PIN_NUMBER='(0,0,0,0,0,0,H22)';
      BIDIRECTIONAL='TRUE';
      INPUT_LOAD='(-0.01,0.01)';
      OUTPUT_LOAD='(1.0,-1.0)';
      PINUSE='BI';
    'PR3B||R_GPLLC_IN':
      PIN_NUMBER='(0,0,0,0,0,0,D21)';
      BIDIRECTIONAL='TRUE';
      INPUT_LOAD='(-0.01,0.01)';
      OUTPUT_LOAD='(1.0,-1.0)';
      PINUSE='BI';
    'PR3A||R_GPLLT_IN':
      PIN_NUMBER='(0,0,0,0,0,0,D22)';
      BIDIRECTIONAL='TRUE';
      INPUT_LOAD='(-0.01,0.01)';
      OUTPUT_LOAD='(1.0,-1.0)';
      PINUSE='BI';
    'PR2B||R_GPLLC_FB':
      PIN_NUMBER='(0,0,0,0,0,0,C22)';
      BIDIRECTIONAL='TRUE';
      INPUT_LOAD='(-0.01,0.01)';
      OUTPUT_LOAD='(1.0,-1.0)';
      PINUSE='BI';
    'PR2A||R_GPLLT_FB':
      PIN_NUMBER='(0,0,0,0,0,0,C21)';
      BIDIRECTIONAL='TRUE';
      INPUT_LOAD='(-0.01,0.01)';
      OUTPUT_LOAD='(1.0,-1.0)';
      PINUSE='BI';
    'PR2C':
      PIN_NUMBER='(0,0,0,0,0,0,F17)';
      BIDIRECTIONAL='TRUE';
      INPUT_LOAD='(-0.01,0.01)';
      OUTPUT_LOAD='(1.0,-1.0)';
      PINUSE='BI';
    'PR2D':
      PIN_NUMBER='(0,0,0,0,0,0,G16)';
      BIDIRECTIONAL='TRUE';
      INPUT_LOAD='(-0.01,0.01)';
      OUTPUT_LOAD='(1.0,-1.0)';
      PINUSE='BI';
    'PR3C':
      PIN_NUMBER='(0,0,0,0,0,0,D19)';
      BIDIRECTIONAL='TRUE';
      INPUT_LOAD='(-0.01,0.01)';
      OUTPUT_LOAD='(1.0,-1.0)';
      PINUSE='BI';
    'PR3D':
      PIN_NUMBER='(0,0,0,0,0,0,D20)';
      BIDIRECTIONAL='TRUE';
      INPUT_LOAD='(-0.01,0.01)';
      OUTPUT_LOAD='(1.0,-1.0)';
      PINUSE='BI';
    'PR4C':
      PIN_NUMBER='(0,0,0,0,0,0,E19)';
      BIDIRECTIONAL='TRUE';
      INPUT_LOAD='(-0.01,0.01)';
      OUTPUT_LOAD='(1.0,-1.0)';
      PINUSE='BI';
    'PR4D':
      PIN_NUMBER='(0,0,0,0,0,0,E20)';
      BIDIRECTIONAL='TRUE';
      INPUT_LOAD='(-0.01,0.01)';
      OUTPUT_LOAD='(1.0,-1.0)';
      PINUSE='BI';
    'PR4A':
      PIN_NUMBER='(0,0,0,0,0,0,E22)';
      BIDIRECTIONAL='TRUE';
      INPUT_LOAD='(-0.01,0.01)';
      OUTPUT_LOAD='(1.0,-1.0)';
      PINUSE='BI';
    'PR4B':
      PIN_NUMBER='(0,0,0,0,0,0,E21)';
      BIDIRECTIONAL='TRUE';
      INPUT_LOAD='(-0.01,0.01)';
      OUTPUT_LOAD='(1.0,-1.0)';
      PINUSE='BI';
    'PR5A':
      PIN_NUMBER='(0,0,0,0,0,0,F22)';
      BIDIRECTIONAL='TRUE';
      INPUT_LOAD='(-0.01,0.01)';
      OUTPUT_LOAD='(1.0,-1.0)';
      PINUSE='BI';
    'PR5B':
      PIN_NUMBER='(0,0,0,0,0,0,G22)';
      BIDIRECTIONAL='TRUE';
      INPUT_LOAD='(-0.01,0.01)';
      OUTPUT_LOAD='(1.0,-1.0)';
      PINUSE='BI';
    'PR5C':
      PIN_NUMBER='(0,0,0,0,0,0,F18)';
      BIDIRECTIONAL='TRUE';
      INPUT_LOAD='(-0.01,0.01)';
      OUTPUT_LOAD='(1.0,-1.0)';
      PINUSE='BI';
    'PR5D':
      PIN_NUMBER='(0,0,0,0,0,0,F19)';
      BIDIRECTIONAL='TRUE';
      INPUT_LOAD='(-0.01,0.01)';
      OUTPUT_LOAD='(1.0,-1.0)';
      PINUSE='BI';
    'PR6A':
      PIN_NUMBER='(0,0,0,0,0,0,G21)';
      BIDIRECTIONAL='TRUE';
      INPUT_LOAD='(-0.01,0.01)';
      OUTPUT_LOAD='(1.0,-1.0)';
      PINUSE='BI';
    'PR6B':
      PIN_NUMBER='(0,0,0,0,0,0,G20)';
      BIDIRECTIONAL='TRUE';
      INPUT_LOAD='(-0.01,0.01)';
      OUTPUT_LOAD='(1.0,-1.0)';
      PINUSE='BI';
    'PR6C':
      PIN_NUMBER='(0,0,0,0,0,0,G19)';
      BIDIRECTIONAL='TRUE';
      INPUT_LOAD='(-0.01,0.01)';
      OUTPUT_LOAD='(1.0,-1.0)';
      PINUSE='BI';
    'PR6D':
      PIN_NUMBER='(0,0,0,0,0,0,G18)';
      BIDIRECTIONAL='TRUE';
      INPUT_LOAD='(-0.01,0.01)';
      OUTPUT_LOAD='(1.0,-1.0)';
      PINUSE='BI';
    'PR7C':
      PIN_NUMBER='(0,0,0,0,0,0,G17)';
      BIDIRECTIONAL='TRUE';
      INPUT_LOAD='(-0.01,0.01)';
      OUTPUT_LOAD='(1.0,-1.0)';
      PINUSE='BI';
    'PR7D':
      PIN_NUMBER='(0,0,0,0,0,0,H20)';
      BIDIRECTIONAL='TRUE';
      INPUT_LOAD='(-0.01,0.01)';
      OUTPUT_LOAD='(1.0,-1.0)';
      PINUSE='BI';
    'PR10A':
      PIN_NUMBER='(0,0,0,0,0,0,H19)';
      BIDIRECTIONAL='TRUE';
      INPUT_LOAD='(-0.01,0.01)';
      OUTPUT_LOAD='(1.0,-1.0)';
      PINUSE='BI';
    'PR10B':
      PIN_NUMBER='(0,0,0,0,0,0,H18)';
      BIDIRECTIONAL='TRUE';
      INPUT_LOAD='(-0.01,0.01)';
      OUTPUT_LOAD='(1.0,-1.0)';
      PINUSE='BI';
    'PR10C':
      PIN_NUMBER='(0,0,0,0,0,0,H17)';
      BIDIRECTIONAL='TRUE';
      INPUT_LOAD='(-0.01,0.01)';
      OUTPUT_LOAD='(1.0,-1.0)';
      PINUSE='BI';
    'PR10D':
      PIN_NUMBER='(0,0,0,0,0,0,H16)';
      BIDIRECTIONAL='TRUE';
      INPUT_LOAD='(-0.01,0.01)';
      OUTPUT_LOAD='(1.0,-1.0)';
      PINUSE='BI';
    'PR11A':
      PIN_NUMBER='(0,0,0,0,0,0,J16)';
      BIDIRECTIONAL='TRUE';
      INPUT_LOAD='(-0.01,0.01)';
      OUTPUT_LOAD='(1.0,-1.0)';
      PINUSE='BI';
    'PR11B':
      PIN_NUMBER='(0,0,0,0,0,0,J17)';
      BIDIRECTIONAL='TRUE';
      INPUT_LOAD='(-0.01,0.01)';
      OUTPUT_LOAD='(1.0,-1.0)';
      PINUSE='BI';
    'PR11C':
      PIN_NUMBER='(0,0,0,0,0,0,J18)';
      BIDIRECTIONAL='TRUE';
      INPUT_LOAD='(-0.01,0.01)';
      OUTPUT_LOAD='(1.0,-1.0)';
      PINUSE='BI';
    'PR11D':
      PIN_NUMBER='(0,0,0,0,0,0,J19)';
      BIDIRECTIONAL='TRUE';
      INPUT_LOAD='(-0.01,0.01)';
      OUTPUT_LOAD='(1.0,-1.0)';
      PINUSE='BI';
    'PR12A':
      PIN_NUMBER='(0,0,0,0,0,0,J21)';
      BIDIRECTIONAL='TRUE';
      INPUT_LOAD='(-0.01,0.01)';
      OUTPUT_LOAD='(1.0,-1.0)';
      PINUSE='BI';
    'PR12B':
      PIN_NUMBER='(0,0,0,0,0,0,J22)';
      BIDIRECTIONAL='TRUE';
      INPUT_LOAD='(-0.01,0.01)';
      OUTPUT_LOAD='(1.0,-1.0)';
      PINUSE='BI';
    'PR12C':
      PIN_NUMBER='(0,0,0,0,0,0,J20)';
      BIDIRECTIONAL='TRUE';
      INPUT_LOAD='(-0.01,0.01)';
      OUTPUT_LOAD='(1.0,-1.0)';
      PINUSE='BI';
    'PR12D':
      PIN_NUMBER='(0,0,0,0,0,0,K20)';
      BIDIRECTIONAL='TRUE';
      INPUT_LOAD='(-0.01,0.01)';
      OUTPUT_LOAD='(1.0,-1.0)';
      PINUSE='BI';
    'PR13A':
      PIN_NUMBER='(0,0,0,0,0,0,K19)';
      BIDIRECTIONAL='TRUE';
      INPUT_LOAD='(-0.01,0.01)';
      OUTPUT_LOAD='(1.0,-1.0)';
      PINUSE='BI';
    'PR13B':
      PIN_NUMBER='(0,0,0,0,0,0,K18)';
      BIDIRECTIONAL='TRUE';
      INPUT_LOAD='(-0.01,0.01)';
      OUTPUT_LOAD='(1.0,-1.0)';
      PINUSE='BI';
    'PR13C':
      PIN_NUMBER='(0,0,0,0,0,0,K17)';
      BIDIRECTIONAL='TRUE';
      INPUT_LOAD='(-0.01,0.01)';
      OUTPUT_LOAD='(1.0,-1.0)';
      PINUSE='BI';
    'PR13D':
      PIN_NUMBER='(0,0,0,0,0,0,K16)';
      BIDIRECTIONAL='TRUE';
      INPUT_LOAD='(-0.01,0.01)';
      OUTPUT_LOAD='(1.0,-1.0)';
      PINUSE='BI';
    'PR14C':
      PIN_NUMBER='(0,0,0,0,0,0,L19)';
      BIDIRECTIONAL='TRUE';
      INPUT_LOAD='(-0.01,0.01)';
      OUTPUT_LOAD='(1.0,-1.0)';
      PINUSE='BI';
    'PR14D':
      PIN_NUMBER='(0,0,0,0,0,0,L20)';
      BIDIRECTIONAL='TRUE';
      INPUT_LOAD='(-0.01,0.01)';
      OUTPUT_LOAD='(1.0,-1.0)';
      PINUSE='BI';
    'PR16C':
      PIN_NUMBER='(0,0,0,0,0,0,L22)';
      BIDIRECTIONAL='TRUE';
      INPUT_LOAD='(-0.01,0.01)';
      OUTPUT_LOAD='(1.0,-1.0)';
      PINUSE='BI';
    'PR16D':
      PIN_NUMBER='(0,0,0,0,0,0,M17)';
      BIDIRECTIONAL='TRUE';
      INPUT_LOAD='(-0.01,0.01)';
      OUTPUT_LOAD='(1.0,-1.0)';
      PINUSE='BI';
    'PR17C':
      PIN_NUMBER='(0,0,0,0,0,0,M20)';
      BIDIRECTIONAL='TRUE';
      INPUT_LOAD='(-0.01,0.01)';
      OUTPUT_LOAD='(1.0,-1.0)';
      PINUSE='BI';
    'PR17D':
      PIN_NUMBER='(0,0,0,0,0,0,M19)';
      BIDIRECTIONAL='TRUE';
      INPUT_LOAD='(-0.01,0.01)';
      OUTPUT_LOAD='(1.0,-1.0)';
      PINUSE='BI';
    'PR18A':
      PIN_NUMBER='(0,0,0,0,0,0,M16)';
      BIDIRECTIONAL='TRUE';
      INPUT_LOAD='(-0.01,0.01)';
      OUTPUT_LOAD='(1.0,-1.0)';
      PINUSE='BI';
    'PR18B':
      PIN_NUMBER='(0,0,0,0,0,0,N16)';
      BIDIRECTIONAL='TRUE';
      INPUT_LOAD='(-0.01,0.01)';
      OUTPUT_LOAD='(1.0,-1.0)';
      PINUSE='BI';
    'PR18C':
      PIN_NUMBER='(0,0,0,0,0,0,N17)';
      BIDIRECTIONAL='TRUE';
      INPUT_LOAD='(-0.01,0.01)';
      OUTPUT_LOAD='(1.0,-1.0)';
      PINUSE='BI';
    'PR18D':
      PIN_NUMBER='(0,0,0,0,0,0,N18)';
      BIDIRECTIONAL='TRUE';
      INPUT_LOAD='(-0.01,0.01)';
      OUTPUT_LOAD='(1.0,-1.0)';
      PINUSE='BI';
    'PR19C':
      PIN_NUMBER='(0,0,0,0,0,0,N20)';
      BIDIRECTIONAL='TRUE';
      INPUT_LOAD='(-0.01,0.01)';
      OUTPUT_LOAD='(1.0,-1.0)';
      PINUSE='BI';
    'PR19D':
      PIN_NUMBER='(0,0,0,0,0,0,N19)';
      BIDIRECTIONAL='TRUE';
      INPUT_LOAD='(-0.01,0.01)';
      OUTPUT_LOAD='(1.0,-1.0)';
      PINUSE='BI';
    'PR20C':
      PIN_NUMBER='(0,0,0,0,0,0,P22)';
      BIDIRECTIONAL='TRUE';
      INPUT_LOAD='(-0.01,0.01)';
      OUTPUT_LOAD='(1.0,-1.0)';
      PINUSE='BI';
    'PR20D':
      PIN_NUMBER='(0,0,0,0,0,0,P20)';
      BIDIRECTIONAL='TRUE';
      INPUT_LOAD='(-0.01,0.01)';
      OUTPUT_LOAD='(1.0,-1.0)';
      PINUSE='BI';
    'PR21A':
      PIN_NUMBER='(0,0,0,0,0,0,T22)';
      BIDIRECTIONAL='TRUE';
      INPUT_LOAD='(-0.01,0.01)';
      OUTPUT_LOAD='(1.0,-1.0)';
      PINUSE='BI';
    'PR21B':
      PIN_NUMBER='(0,0,0,0,0,0,T21)';
      BIDIRECTIONAL='TRUE';
      INPUT_LOAD='(-0.01,0.01)';
      OUTPUT_LOAD='(1.0,-1.0)';
      PINUSE='BI';
    'PR21C':
      PIN_NUMBER='(0,0,0,0,0,0,P19)';
      BIDIRECTIONAL='TRUE';
      INPUT_LOAD='(-0.01,0.01)';
      OUTPUT_LOAD='(1.0,-1.0)';
      PINUSE='BI';
    'PR21D':
      PIN_NUMBER='(0,0,0,0,0,0,P18)';
      BIDIRECTIONAL='TRUE';
      INPUT_LOAD='(-0.01,0.01)';
      OUTPUT_LOAD='(1.0,-1.0)';
      PINUSE='BI';
    'PR24A':
      PIN_NUMBER='(0,0,0,0,0,0,P17)';
      BIDIRECTIONAL='TRUE';
      INPUT_LOAD='(-0.01,0.01)';
      OUTPUT_LOAD='(1.0,-1.0)';
      PINUSE='BI';
    'PR24B':
      PIN_NUMBER='(0,0,0,0,0,0,P16)';
      BIDIRECTIONAL='TRUE';
      INPUT_LOAD='(-0.01,0.01)';
      OUTPUT_LOAD='(1.0,-1.0)';
      PINUSE='BI';
    'PR24C':
      PIN_NUMBER='(0,0,0,0,0,0,U22)';
      BIDIRECTIONAL='TRUE';
      INPUT_LOAD='(-0.01,0.01)';
      OUTPUT_LOAD='(1.0,-1.0)';
      PINUSE='BI';
    'PR24D':
      PIN_NUMBER='(0,0,0,0,0,0,U21)';
      BIDIRECTIONAL='TRUE';
      INPUT_LOAD='(-0.01,0.01)';
      OUTPUT_LOAD='(1.0,-1.0)';
      PINUSE='BI';
    'PR25C':
      PIN_NUMBER='(0,0,0,0,0,0,R20)';
      BIDIRECTIONAL='TRUE';
      INPUT_LOAD='(-0.01,0.01)';
      OUTPUT_LOAD='(1.0,-1.0)';
      PINUSE='BI';
    'PR25D':
      PIN_NUMBER='(0,0,0,0,0,0,R19)';
      BIDIRECTIONAL='TRUE';
      INPUT_LOAD='(-0.01,0.01)';
      OUTPUT_LOAD='(1.0,-1.0)';
      PINUSE='BI';
    'PR26A':
      PIN_NUMBER='(0,0,0,0,0,0,R18)';
      BIDIRECTIONAL='TRUE';
      INPUT_LOAD='(-0.01,0.01)';
      OUTPUT_LOAD='(1.0,-1.0)';
      PINUSE='BI';
    'PR26B':
      PIN_NUMBER='(0,0,0,0,0,0,R17)';
      BIDIRECTIONAL='TRUE';
      INPUT_LOAD='(-0.01,0.01)';
      OUTPUT_LOAD='(1.0,-1.0)';
      PINUSE='BI';
    'PR26C':
      PIN_NUMBER='(0,0,0,0,0,0,R16)';
      BIDIRECTIONAL='TRUE';
      INPUT_LOAD='(-0.01,0.01)';
      OUTPUT_LOAD='(1.0,-1.0)';
      PINUSE='BI';
    'PR26D':
      PIN_NUMBER='(0,0,0,0,0,0,T20)';
      BIDIRECTIONAL='TRUE';
      INPUT_LOAD='(-0.01,0.01)';
      OUTPUT_LOAD='(1.0,-1.0)';
      PINUSE='BI';
    'PR27A':
      PIN_NUMBER='(0,0,0,0,0,0,T19)';
      BIDIRECTIONAL='TRUE';
      INPUT_LOAD='(-0.01,0.01)';
      OUTPUT_LOAD='(1.0,-1.0)';
      PINUSE='BI';
    'PR27B':
      PIN_NUMBER='(0,0,0,0,0,0,T18)';
      BIDIRECTIONAL='TRUE';
      INPUT_LOAD='(-0.01,0.01)';
      OUTPUT_LOAD='(1.0,-1.0)';
      PINUSE='BI';
    'PR27C':
      PIN_NUMBER='(0,0,0,0,0,0,T17)';
      BIDIRECTIONAL='TRUE';
      INPUT_LOAD='(-0.01,0.01)';
      OUTPUT_LOAD='(1.0,-1.0)';
      PINUSE='BI';
    'PR27D':
      PIN_NUMBER='(0,0,0,0,0,0,U20)';
      BIDIRECTIONAL='TRUE';
      INPUT_LOAD='(-0.01,0.01)';
      OUTPUT_LOAD='(1.0,-1.0)';
      PINUSE='BI';
    'PR28A':
      PIN_NUMBER='(0,0,0,0,0,0,Y22)';
      BIDIRECTIONAL='TRUE';
      INPUT_LOAD='(-0.01,0.01)';
      OUTPUT_LOAD='(1.0,-1.0)';
      PINUSE='BI';
    'PR28B':
      PIN_NUMBER='(0,0,0,0,0,0,W21)';
      BIDIRECTIONAL='TRUE';
      INPUT_LOAD='(-0.01,0.01)';
      OUTPUT_LOAD='(1.0,-1.0)';
      PINUSE='BI';
    'PR28C':
      PIN_NUMBER='(0,0,0,0,0,0,U19)';
      BIDIRECTIONAL='TRUE';
      INPUT_LOAD='(-0.01,0.01)';
      OUTPUT_LOAD='(1.0,-1.0)';
      PINUSE='BI';
    'PR28D':
      PIN_NUMBER='(0,0,0,0,0,0,U18)';
      BIDIRECTIONAL='TRUE';
      INPUT_LOAD='(-0.01,0.01)';
      OUTPUT_LOAD='(1.0,-1.0)';
      PINUSE='BI';
    'PR30C':
      PIN_NUMBER='(0,0,0,0,0,0,W19)';
      BIDIRECTIONAL='TRUE';
      INPUT_LOAD='(-0.01,0.01)';
      OUTPUT_LOAD='(1.0,-1.0)';
      PINUSE='BI';
    'PR30D':
      PIN_NUMBER='(0,0,0,0,0,0,Y20)';
      BIDIRECTIONAL='TRUE';
      INPUT_LOAD='(-0.01,0.01)';
      OUTPUT_LOAD='(1.0,-1.0)';
      PINUSE='BI';
  end_pin;
  body
      PART_NAME='LCMXO3LF9400C5BG484C';
      BODY_NAME='LCMXO3LF9400C5BG484C';
      PHYS_DES_PREFIX='U';
      CLASS='IC';
      STANDARD='';
      LIFECYCLE='';
      JEDEC_TYPE='BGA484_0-8_19X19_H67';
      DESCRIPTION='IC(484P)LCMXO3LF-9400C-5BG484C(CABGA)';
      MANUFTR='LSC';
      MANUF_PN='LCMXO3LF-9400C-5BG484C';
      RD_CMPLS_LVL='EP(V1)';
      CMPLS_LVL='';
      FROM_PJ='F0T-FENTUS';
      DIP_SMD='';
      DATA='LSC_LCMXO3LF-9400C-5BG484C.pdf';
      EE_CHECK_LIST='';
      FP_ECN='';
      PSL='';
      CREATOR='';
      STATUS='';
      MSD='';
      ESD_CDM='';
      ESD_HBM='';
      ESD_MM='';
      PIN_LENGTH_SHORT_PIN='0 MILS';
      PIN_LENGTH_LONG_PIN='0 MILS';
      CREATEDAY='20210929';
      PARENT_PART_TYPE='LCMXO3LF9400C5BG484C';
      PARENT_PPT='LCMXO3LF9400C5BG484C';
      PARENT_PPT_PART='LCMXO3LF9400C5BG484C-LCMXO3LF-9400C-5BG484C,SMLF,IC,AJ094000T08';
  end_body;
end_primitive;
primitive 'LM4040AIM3X25NOPB-LM4040AIM3X-A';
  pin
    '1+':
      PIN_NUMBER='(1)';
      BIDIRECTIONAL='TRUE';
      INPUT_LOAD='(-0.01,0.01)';
      OUTPUT_LOAD='(1.0,-1.0)';
      PINUSE='BI';
    '2-':
      PIN_NUMBER='(2)';
      OUTPUT_LOAD='(1.0,-1.0)';
      PINUSE='OUT';
    '3':
      PIN_NUMBER='(3)';
      BIDIRECTIONAL='TRUE';
      INPUT_LOAD='(-0.01,0.01)';
      OUTPUT_LOAD='(1.0,-1.0)';
      PINUSE='BI';
  end_pin;
  body
      PART_NAME='LM4040AIM3X25NOPB';
      BODY_NAME='LM4040AIM3X25NOPB';
      PHYS_DES_PREFIX='U';
      CLASS='IC';
      STANDARD='';
      LIFECYCLE='';
      JEDEC_TYPE='SOT23_123_2-92X1-3';
      DESCRIPTION='IC OTHER(3P)LM4040AIM3X-2.5/NOPB(SOT23)';
      MANUFTR='TIC';
      MANUF_PN='LM4040AIM3X-2.5/NOPB';
      RD_CMPLS_LVL='EP(V1)';
      CMPLS_LVL='';
      FROM_PJ='T6MB-JOSEPH';
      DIP_SMD='';
      DATA='TIC_LM4040-N_LM4040-N-Q1.pdf';
      EE_CHECK_LIST='';
      FP_ECN='';
      PSL='';
      CREATOR='';
      STATUS='';
      CREATEDAY='20150917';
      PARENT_PART_TYPE='LM4040AIM3X25NOPB';
      PARENT_PPT='LM4040AIM3X25NOPB';
      PARENT_PPT_PART='LM4040AIM3X25NOPB-LM4040AIM3X-2.5/NOPB,SMLF,EMPTY,AL404025013';
  end_body;
end_primitive;
primitive 'LM75BD-LM75BD,SMLF,IC,AL0075BDA';
  pin
    'SDA':
      PIN_NUMBER='(1)';
      BIDIRECTIONAL='TRUE';
      INPUT_LOAD='(-0.01,0.01)';
      OUTPUT_LOAD='(1.0,-1.0)';
      PINUSE='BI';
    'SCL':
      PIN_NUMBER='(2)';
      INPUT_LOAD='(-0.01,0.01)';
      PINUSE='IN';
    'OS':
      PIN_NUMBER='(3)';
      OUTPUT_LOAD='(1.0,-1.0)';
      PINUSE='OUT';
    'GND':
      PIN_NUMBER='(4)';
      PINUSE='POWER';
      NO_LOAD_CHECK='Both';
      NO_IO_CHECK='Both';
      NO_ASSERT_CHECK='TRUE';
      NO_DIR_CHECK='TRUE';
      ALLOW_CONNECT='TRUE';
    'A2':
      PIN_NUMBER='(5)';
      INPUT_LOAD='(-0.01,0.01)';
      PINUSE='IN';
    'A1':
      PIN_NUMBER='(6)';
      INPUT_LOAD='(-0.01,0.01)';
      PINUSE='IN';
    'A0':
      PIN_NUMBER='(7)';
      INPUT_LOAD='(-0.01,0.01)';
      PINUSE='IN';
    'VCC':
      PIN_NUMBER='(8)';
      PINUSE='POWER';
      NO_LOAD_CHECK='Both';
      NO_IO_CHECK='Both';
      NO_ASSERT_CHECK='TRUE';
      NO_DIR_CHECK='TRUE';
      ALLOW_CONNECT='TRUE';
  end_pin;
  body
      PART_NAME='LM75BD';
      BODY_NAME='LM75BD';
      PHYS_DES_PREFIX='U';
      CLASS='IC';
      STANDARD='';
      LIFECYCLE='';
      JEDEC_TYPE='SO8_1-27_4-9X3-9';
      DESCRIPTION='IC OTHER (8P) LM75BD(SO8)';
      MANUFTR='NXP';
      MANUF_PN='LM75BD';
      RD_CMPLS_LVL='EP(V1)';
      CMPLS_LVL='EP(V1)';
      FROM_PJ='F0T-BOB-JON';
      DIP_SMD='';
      DATA='NXP_LM75BD.pdf';
      EE_CHECK_LIST='';
      FP_ECN='';
      PSL='';
      CREATOR='';
      STATUS='';
      MSD='';
      ESD_CDM='';
      ESD_HBM='';
      ESD_MM='';
      PIN_LENGTH_SHORT_PIN='0 MILS';
      PIN_LENGTH_LONG_PIN='0 MILS';
      CREATEDAY='20211112';
      PARENT_PART_TYPE='LM75BD';
      PARENT_PPT='LM75BD';
      PARENT_PPT_PART='LM75BD-LM75BD,SMLF,IC,AL0075BD000';
  end_body;
end_primitive;
primitive 'LT6700CS61TRPBF-LT6700CS6-1#TRA';
  pin
    'VS':
      PIN_NUMBER='(5)';
      PINUSE='POWER';
      NO_LOAD_CHECK='Both';
      NO_IO_CHECK='Both';
      NO_ASSERT_CHECK='TRUE';
      NO_DIR_CHECK='TRUE';
      ALLOW_CONNECT='TRUE';
    'INB-':
      PIN_NUMBER='(4)';
      INPUT_LOAD='(-0.01,0.01)';
      PINUSE='IN';
    'GND':
      PIN_NUMBER='(2)';
      PINUSE='POWER';
      NO_LOAD_CHECK='Both';
      NO_IO_CHECK='Both';
      NO_ASSERT_CHECK='TRUE';
      NO_DIR_CHECK='TRUE';
      ALLOW_CONNECT='TRUE';
    'OUTA':
      PIN_NUMBER='(1)';
      OUTPUT_LOAD='(1.0,-1.0)';
      PINUSE='OUT';
    'INA+':
      PIN_NUMBER='(3)';
      INPUT_LOAD='(-0.01,0.01)';
      PINUSE='IN';
    'OUTB':
      PIN_NUMBER='(6)';
      OUTPUT_LOAD='(1.0,-1.0)';
      PINUSE='OUT';
  end_pin;
  body
      PART_NAME='LT6700CS61TRPBF';
      BODY_NAME='LT6700CS61TRPBF';
      PHYS_DES_PREFIX='U';
      CLASS='IC';
      STANDARD='';
      LIFECYCLE='';
      JEDEC_TYPE='TSOT23-6_0-95_2-9X1-625';
      DESCRIPTION='IC OTHER(6P)LT6700CS6-1#TRPBF(TSOT-23)';
      MANUFTR='LIN';
      MANUF_PN='LT6700CS6-1#TRPBF';
      RD_CMPLS_LVL='EP';
      CMPLS_LVL='';
      FROM_PJ='F0CE-GARY';
      DIP_SMD='';
      DATA='LIN_LT6700CS6-1TRPBF.pdf';
      EE_CHECK_LIST='';
      FP_ECN='';
      PSL='';
      CREATOR='';
      STATUS='';
      MSD='';
      ESD_CDM='';
      ESD_HBM='';
      ESD_MM='';
      PIN_LENGTH_SHORT_PIN='0 MILS';
      PIN_LENGTH_LONG_PIN='0 MILS';
      CREATEDAY='20210603';
      PARENT_PART_TYPE='LT6700CS61TRPBF';
      PARENT_PPT='LT6700CS61TRPBF';
      PARENT_PPT_PART='LT6700CS61TRPBF-LT6700CS6-1#TRPBF,SMLF,IC,AL006700001';
  end_body;
end_primitive;
primitive 'LTC4307CMS8-LTC4307CMS8,SMLF,EA';
  pin
    'ENABLE':
      PIN_NUMBER='(1)';
      INPUT_LOAD='(-0.01,0.01)';
      PINUSE='IN';
    'SCL_IN':
      PIN_NUMBER='(3)';
      INPUT_LOAD='(-0.01,0.01)';
      OUTPUT_LOAD='(1.0,-1.0)';
      BIDIRECTIONAL='TRUE';
      PINUSE='BI';
    'SDA_IN':
      PIN_NUMBER='(6)';
      INPUT_LOAD='(-0.01,0.01)';
      OUTPUT_LOAD='(1.0,-1.0)';
      BIDIRECTIONAL='TRUE';
      PINUSE='BI';
    'SCL_OUT':
      PIN_NUMBER='(2)';
      INPUT_LOAD='(-0.01,0.01)';
      OUTPUT_LOAD='(1.0,-1.0)';
      BIDIRECTIONAL='TRUE';
      PINUSE='BI';
    'SDA_OUT':
      PIN_NUMBER='(7)';
      INPUT_LOAD='(-0.01,0.01)';
      OUTPUT_LOAD='(1.0,-1.0)';
      BIDIRECTIONAL='TRUE';
      PINUSE='BI';
    'READY':
      PIN_NUMBER='(5)';
      OUTPUT_LOAD='(1.0,-1.0)';
      PINUSE='OUT';
    'GND':
      PIN_NUMBER='(4)';
      PINUSE='POWER';
    'VCC':
      PIN_NUMBER='(8)';
      PINUSE='POWER';
  end_pin;
  body
      CLASS='IC';
      PART_NAME='LTC4307CMS8';
      PHYS_DES_PREFIX='U';
      JEDEC_TYPE='MSOP8';
      DESCRIPTION='IC OTHER(8P) LTC4307CMS8#TRPBF(MSOP)';
      MANUFTR='LIN';
      MANUF_PN='LTC4307CMS8#TRPBF';
      RD_CMPLS_LVL='';
      CMPLS_LVL='EP_Tmp';
      FROM_PJ='LU1-EASON';
      DIP_SMD='';
      DATA='LIN_LTC4307.pdf';
      EE_CHECK_LIST='';
      FP_ECN='';
      PSL='';
      LIFECYCLE='';
      CREATOR='';
      STANDARD='';
      CREATEDAY='20111202';
      STATUS='';
      PARENT_PART_TYPE='LTC4307CMS8';
      PARENT_PPT='LTC4307CMS8';
      PARENT_PPT_PART='LTC4307CMS8-LTC4307CMS8,SMLF,EMPTY,AL004307000';
  end_body;
end_primitive;
primitive 'LTC4307CMS8-LTC4307CMS8,SMLF,IA';
  pin
    'ENABLE':
      PIN_NUMBER='(1)';
      INPUT_LOAD='(-0.01,0.01)';
      PINUSE='IN';
    'SCL_IN':
      PIN_NUMBER='(3)';
      INPUT_LOAD='(-0.01,0.01)';
      OUTPUT_LOAD='(1.0,-1.0)';
      BIDIRECTIONAL='TRUE';
      PINUSE='BI';
    'SDA_IN':
      PIN_NUMBER='(6)';
      INPUT_LOAD='(-0.01,0.01)';
      OUTPUT_LOAD='(1.0,-1.0)';
      BIDIRECTIONAL='TRUE';
      PINUSE='BI';
    'SCL_OUT':
      PIN_NUMBER='(2)';
      INPUT_LOAD='(-0.01,0.01)';
      OUTPUT_LOAD='(1.0,-1.0)';
      BIDIRECTIONAL='TRUE';
      PINUSE='BI';
    'SDA_OUT':
      PIN_NUMBER='(7)';
      INPUT_LOAD='(-0.01,0.01)';
      OUTPUT_LOAD='(1.0,-1.0)';
      BIDIRECTIONAL='TRUE';
      PINUSE='BI';
    'READY':
      PIN_NUMBER='(5)';
      OUTPUT_LOAD='(1.0,-1.0)';
      PINUSE='OUT';
    'GND':
      PIN_NUMBER='(4)';
      PINUSE='POWER';
    'VCC':
      PIN_NUMBER='(8)';
      PINUSE='POWER';
  end_pin;
  body
      CLASS='IC';
      PART_NAME='LTC4307CMS8';
      PHYS_DES_PREFIX='U';
      JEDEC_TYPE='MSOP8';
      DESCRIPTION='IC OTHER(8P) LTC4307CMS8#TRPBF(MSOP)';
      MANUFTR='LIN';
      MANUF_PN='LTC4307CMS8#TRPBF';
      RD_CMPLS_LVL='';
      CMPLS_LVL='EP_Tmp';
      FROM_PJ='LU1-EASON';
      DIP_SMD='';
      DATA='LIN_LTC4307.pdf';
      EE_CHECK_LIST='';
      FP_ECN='';
      PSL='';
      LIFECYCLE='';
      CREATOR='';
      STANDARD='';
      CREATEDAY='20111202';
      STATUS='';
      PARENT_PART_TYPE='LTC4307CMS8';
      PARENT_PPT='LTC4307CMS8';
      PARENT_PPT_PART='LTC4307CMS8-LTC4307CMS8,SMLF,IC,AL004307000';
  end_body;
end_primitive;
primitive 'M24128BWMN6TP-M24128-BWMN6TP,SA';
  pin
    'VCC':
      PIN_NUMBER='(8)';
      PINUSE='POWER';
      NO_LOAD_CHECK='Both';
      NO_IO_CHECK='Both';
      NO_ASSERT_CHECK='TRUE';
      NO_DIR_CHECK='TRUE';
      ALLOW_CONNECT='TRUE';
    'WC#':
      PIN_NUMBER='(7)';
      INPUT_LOAD='(-0.01,0.01)';
      PINUSE='IN';
    'SCL':
      PIN_NUMBER='(6)';
      INPUT_LOAD='(-0.01,0.01)';
      PINUSE='IN';
    'SDA':
      PIN_NUMBER='(5)';
      BIDIRECTIONAL='TRUE';
      INPUT_LOAD='(-0.01,0.01)';
      OUTPUT_LOAD='(1.0,-1.0)';
      PINUSE='BI';
    'VSS':
      PIN_NUMBER='(4)';
      PINUSE='POWER';
      NO_LOAD_CHECK='Both';
      NO_IO_CHECK='Both';
      NO_ASSERT_CHECK='TRUE';
      NO_DIR_CHECK='TRUE';
      ALLOW_CONNECT='TRUE';
    'E2':
      PIN_NUMBER='(3)';
      INPUT_LOAD='(-0.01,0.01)';
      PINUSE='IN';
    'E1':
      PIN_NUMBER='(2)';
      INPUT_LOAD='(-0.01,0.01)';
      PINUSE='IN';
    'E0':
      PIN_NUMBER='(1)';
      INPUT_LOAD='(-0.01,0.01)';
      PINUSE='IN';
  end_pin;
  body
      PART_NAME='M24128BWMN6TP';
      BODY_NAME='M24128BWMN6TP';
      PHYS_DES_PREFIX='U';
      CLASS='IC';
      STANDARD='';
      LIFECYCLE='';
      JEDEC_TYPE='SOIC8XH';
      DESCRIPTION='IC(8P) EEPROM M24128-BWMN6TP(SO8)';
      MANUFTR='SGT';
      MANUF_PN='M24128-BWMN6TP';
      RD_CMPLS_LVL='EP(V1)';
      CMPLS_LVL='EP(V1)';
      FROM_PJ='S2D-TERRY';
      DIP_SMD='';
      DATA='SGT_M24256-B_M24128-B.pdf';
      EE_CHECK_LIST='';
      FP_ECN='';
      PSL='';
      CREATOR='';
      STATUS='';
      MSD='';
      ESD_CDM='';
      ESD_HBM='';
      ESD_MM='';
      PIN_LENGTH_SHORT_PIN='';
      PIN_LENGTH_LONG_PIN='';
      CREATEDAY='20200318';
      PARENT_PART_TYPE='M24128BWMN6TP';
      PARENT_PPT='M24128BWMN6TP';
      PARENT_PPT_PART='M24128BWMN6TP-M24128-BWMN6TP,SMLF,IC,AKE30Z00613';
  end_body;
end_primitive;
primitive 'MAX11617EEET-MAX11617EEE+T,SMLA';
  pin
    'AIN11||REF':
      PIN_NUMBER='(1)';
      BIDIRECTIONAL='TRUE';
      INPUT_LOAD='(-0.01,0.01)';
      OUTPUT_LOAD='(1.0,-1.0)';
      PINUSE='BI';
    'AIN10':
      PIN_NUMBER='(2)';
      BIDIRECTIONAL='TRUE';
      INPUT_LOAD='(-0.01,0.01)';
      OUTPUT_LOAD='(1.0,-1.0)';
      PINUSE='BI';
    'AIN9':
      PIN_NUMBER='(3)';
      BIDIRECTIONAL='TRUE';
      INPUT_LOAD='(-0.01,0.01)';
      OUTPUT_LOAD='(1.0,-1.0)';
      PINUSE='BI';
    'AIN8':
      PIN_NUMBER='(4)';
      BIDIRECTIONAL='TRUE';
      INPUT_LOAD='(-0.01,0.01)';
      OUTPUT_LOAD='(1.0,-1.0)';
      PINUSE='BI';
    'AIN0':
      PIN_NUMBER='(5)';
      BIDIRECTIONAL='TRUE';
      INPUT_LOAD='(-0.01,0.01)';
      OUTPUT_LOAD='(1.0,-1.0)';
      PINUSE='BI';
    'AIN1':
      PIN_NUMBER='(6)';
      BIDIRECTIONAL='TRUE';
      INPUT_LOAD='(-0.01,0.01)';
      OUTPUT_LOAD='(1.0,-1.0)';
      PINUSE='BI';
    'AIN2':
      PIN_NUMBER='(7)';
      BIDIRECTIONAL='TRUE';
      INPUT_LOAD='(-0.01,0.01)';
      OUTPUT_LOAD='(1.0,-1.0)';
      PINUSE='BI';
    'AIN3':
      PIN_NUMBER='(8)';
      BIDIRECTIONAL='TRUE';
      INPUT_LOAD='(-0.01,0.01)';
      OUTPUT_LOAD='(1.0,-1.0)';
      PINUSE='BI';
    'AIN4':
      PIN_NUMBER='(9)';
      BIDIRECTIONAL='TRUE';
      INPUT_LOAD='(-0.01,0.01)';
      OUTPUT_LOAD='(1.0,-1.0)';
      PINUSE='BI';
    'AIN5':
      PIN_NUMBER='(10)';
      BIDIRECTIONAL='TRUE';
      INPUT_LOAD='(-0.01,0.01)';
      OUTPUT_LOAD='(1.0,-1.0)';
      PINUSE='BI';
    'AIN6':
      PIN_NUMBER='(11)';
      BIDIRECTIONAL='TRUE';
      INPUT_LOAD='(-0.01,0.01)';
      OUTPUT_LOAD='(1.0,-1.0)';
      PINUSE='BI';
    'AIN7':
      PIN_NUMBER='(12)';
      BIDIRECTIONAL='TRUE';
      INPUT_LOAD='(-0.01,0.01)';
      OUTPUT_LOAD='(1.0,-1.0)';
      PINUSE='BI';
    'SCL':
      PIN_NUMBER='(13)';
      BIDIRECTIONAL='TRUE';
      INPUT_LOAD='(-0.01,0.01)';
      OUTPUT_LOAD='(1.0,-1.0)';
      PINUSE='BI';
    'SDA':
      PIN_NUMBER='(14)';
      BIDIRECTIONAL='TRUE';
      INPUT_LOAD='(-0.01,0.01)';
      OUTPUT_LOAD='(1.0,-1.0)';
      PINUSE='BI';
    'GND':
      PIN_NUMBER='(15)';
      PINUSE='POWER';
      NO_LOAD_CHECK='Both';
      NO_IO_CHECK='Both';
      NO_ASSERT_CHECK='TRUE';
      NO_DIR_CHECK='TRUE';
      ALLOW_CONNECT='TRUE';
    'VDD':
      PIN_NUMBER='(16)';
      PINUSE='POWER';
      NO_LOAD_CHECK='Both';
      NO_IO_CHECK='Both';
      NO_ASSERT_CHECK='TRUE';
      NO_DIR_CHECK='TRUE';
      ALLOW_CONNECT='TRUE';
  end_pin;
  body
      PART_NAME='MAX11617EEET';
      BODY_NAME='MAX11617EEET';
      PHYS_DES_PREFIX='U';
      CLASS='IC';
      STANDARD='';
      LIFECYCLE='';
      JEDEC_TYPE='QSOP16_0-635_4-9X3-89';
      DESCRIPTION='IC CTRL(16P)MAX11617EEE+T QSOP';
      MANUFTR='MAM';
      MANUF_PN='MAX11617EEE+T';
      RD_CMPLS_LVL='EP(V1)';
      CMPLS_LVL='EP(V1)';
      FROM_PJ='F0CE-JAMES';
      DIP_SMD='';
      DATA='MAM_MAX11617EEE+T.pdf';
      EE_CHECK_LIST='';
      FP_ECN='MAX11617EEE+T.msg';
      PSL='';
      CREATOR='';
      STATUS='';
      MSD='';
      ESD_CDM='';
      ESD_HBM='';
      ESD_MM='';
      PIN_LENGTH_SHORT_PIN='0 MILS';
      PIN_LENGTH_LONG_PIN='0 MILS';
      CREATEDAY='20210528';
      PARENT_PART_TYPE='MAX11617EEET';
      PARENT_PPT='MAX11617EEET';
      PARENT_PPT_PART='MAX11617EEET-MAX11617EEE+T,SMLF,EMPTY,AL011617W00';
  end_body;
end_primitive;
primitive 'MAX15090BEWIT-MAX15090BEWI+T,SA';
  pin
    'VCC':
      PIN_NUMBER='(A2)';
      PINUSE='POWER';
      NO_LOAD_CHECK='Both';
      NO_IO_CHECK='Both';
      NO_ASSERT_CHECK='TRUE';
      NO_DIR_CHECK='TRUE';
      ALLOW_CONNECT='TRUE';
    'IN_A3':
      PIN_NUMBER='(A3)';
      INPUT_LOAD='(-0.01,0.01)';
      PINUSE='IN';
    'IN_A5':
      PIN_NUMBER='(A5)';
      INPUT_LOAD='(-0.01,0.01)';
      PINUSE='IN';
    'IN_B3':
      PIN_NUMBER='(B3)';
      INPUT_LOAD='(-0.01,0.01)';
      PINUSE='IN';
    'IN_B5':
      PIN_NUMBER='(B5)';
      INPUT_LOAD='(-0.01,0.01)';
      PINUSE='IN';
    'IN_C3':
      PIN_NUMBER='(C3)';
      INPUT_LOAD='(-0.01,0.01)';
      PINUSE='IN';
    'IN_C5':
      PIN_NUMBER='(C5)';
      INPUT_LOAD='(-0.01,0.01)';
      PINUSE='IN';
    'IN_D5':
      PIN_NUMBER='(D5)';
      INPUT_LOAD='(-0.01,0.01)';
      PINUSE='IN';
    'CB':
      PIN_NUMBER='(B1)';
      BIDIRECTIONAL='TRUE';
      INPUT_LOAD='(-0.01,0.01)';
      OUTPUT_LOAD='(1.0,-1.0)';
      PINUSE='BI';
    'EN#':
      PIN_NUMBER='(B7)';
      INPUT_LOAD='(-0.01,0.01)';
      PINUSE='IN';
    'REG':
      PIN_NUMBER='(D1)';
      OUTPUT_LOAD='(1.0,-1.0)';
      PINUSE='OUT';
    'UV':
      PIN_NUMBER='(D2)';
      INPUT_LOAD='(-0.01,0.01)';
      PINUSE='IN';
    'OV':
      PIN_NUMBER='(D3)';
      INPUT_LOAD='(-0.01,0.01)';
      PINUSE='IN';
    'ISENSE':
      PIN_NUMBER='(A1)';
      OUTPUT_LOAD='(1.0,-1.0)';
      PINUSE='OUT';
    'OUT_A4':
      PIN_NUMBER='(A4)';
      OUTPUT_LOAD='(1.0,-1.0)';
      PINUSE='OUT';
    'OUT_B4':
      PIN_NUMBER='(B4)';
      OUTPUT_LOAD='(1.0,-1.0)';
      PINUSE='OUT';
    'OUT_B6':
      PIN_NUMBER='(B6)';
      OUTPUT_LOAD='(1.0,-1.0)';
      PINUSE='OUT';
    'OUT_C4':
      PIN_NUMBER='(C4)';
      OUTPUT_LOAD='(1.0,-1.0)';
      PINUSE='OUT';
    'OUT_C6':
      PIN_NUMBER='(C6)';
      OUTPUT_LOAD='(1.0,-1.0)';
      PINUSE='OUT';
    'OUT_D4':
      PIN_NUMBER='(D4)';
      OUTPUT_LOAD='(1.0,-1.0)';
      PINUSE='OUT';
    'OUT_D6':
      PIN_NUMBER='(D6)';
      OUTPUT_LOAD='(1.0,-1.0)';
      PINUSE='OUT';
    'GATE':
      PIN_NUMBER='(A6)';
      BIDIRECTIONAL='TRUE';
      INPUT_LOAD='(-0.01,0.01)';
      OUTPUT_LOAD='(1.0,-1.0)';
      PINUSE='BI';
    'CDLY':
      PIN_NUMBER='(A7)';
      INPUT_LOAD='(-0.01,0.01)';
      PINUSE='IN';
    'GND_B2':
      PIN_NUMBER='(B2)';
      PINUSE='POWER';
      NO_LOAD_CHECK='Both';
      NO_IO_CHECK='Both';
      NO_ASSERT_CHECK='TRUE';
      NO_DIR_CHECK='TRUE';
      ALLOW_CONNECT='TRUE';
    'GND_C1':
      PIN_NUMBER='(C1)';
      PINUSE='POWER';
      NO_LOAD_CHECK='Both';
      NO_IO_CHECK='Both';
      NO_ASSERT_CHECK='TRUE';
      NO_DIR_CHECK='TRUE';
      ALLOW_CONNECT='TRUE';
    'GND_C2':
      PIN_NUMBER='(C2)';
      PINUSE='POWER';
      NO_LOAD_CHECK='Both';
      NO_IO_CHECK='Both';
      NO_ASSERT_CHECK='TRUE';
      NO_DIR_CHECK='TRUE';
      ALLOW_CONNECT='TRUE';
    'FAULT#':
      PIN_NUMBER='(C7)';
      OUTPUT_LOAD='(1.0,-1.0)';
      PINUSE='OUT';
    'PG':
      PIN_NUMBER='(D7)';
      OUTPUT_LOAD='(1.0,-1.0)';
      PINUSE='OUT';
  end_pin;
  body
      PART_NAME='MAX15090BEWIT';
      BODY_NAME='MAX15090BEWIT';
      PHYS_DES_PREFIX='U';
      CLASS='IC';
      STANDARD='';
      LIFECYCLE='';
      JEDEC_TYPE='BGA28_0-5_3-525X2-065';
      DESCRIPTION='IC OTHER(28P)MAX15090BEWI+T(WLP)';
      MANUFTR='MAM';
      MANUF_PN='MAX15090BEWI+T';
      RD_CMPLS_LVL='EP(V1)';
      CMPLS_LVL='';
      FROM_PJ='UH3M-KEVIN';
      DIP_SMD='';
      DATA='MAM_MAX15090BEWI+T.pdf';
      EE_CHECK_LIST='';
      FP_ECN='';
      PSL='';
      CREATOR='';
      STATUS='';
      MSD='';
      ESD_CDM='';
      ESD_HBM='';
      ESD_MM='';
      PIN_LENGTH_SHORT_PIN='';
      PIN_LENGTH_LONG_PIN='';
      CREATEDAY='20160324';
      PARENT_PART_TYPE='MAX15090BEWIT';
      PARENT_PPT='MAX15090BEWIT';
      PARENT_PPT_PART='MAX15090BEWIT-MAX15090BEWI+T,SMLF,EMPTY,AL015080B00';
  end_body;
end_primitive;
primitive 'MAX15090BEWIT-MAX15090BEWI+T,SB';
  pin
    'VCC':
      PIN_NUMBER='(A2)';
      PINUSE='POWER';
      NO_LOAD_CHECK='Both';
      NO_IO_CHECK='Both';
      NO_ASSERT_CHECK='TRUE';
      NO_DIR_CHECK='TRUE';
      ALLOW_CONNECT='TRUE';
    'IN_A3':
      PIN_NUMBER='(A3)';
      INPUT_LOAD='(-0.01,0.01)';
      PINUSE='IN';
    'IN_A5':
      PIN_NUMBER='(A5)';
      INPUT_LOAD='(-0.01,0.01)';
      PINUSE='IN';
    'IN_B3':
      PIN_NUMBER='(B3)';
      INPUT_LOAD='(-0.01,0.01)';
      PINUSE='IN';
    'IN_B5':
      PIN_NUMBER='(B5)';
      INPUT_LOAD='(-0.01,0.01)';
      PINUSE='IN';
    'IN_C3':
      PIN_NUMBER='(C3)';
      INPUT_LOAD='(-0.01,0.01)';
      PINUSE='IN';
    'IN_C5':
      PIN_NUMBER='(C5)';
      INPUT_LOAD='(-0.01,0.01)';
      PINUSE='IN';
    'IN_D5':
      PIN_NUMBER='(D5)';
      INPUT_LOAD='(-0.01,0.01)';
      PINUSE='IN';
    'CB':
      PIN_NUMBER='(B1)';
      BIDIRECTIONAL='TRUE';
      INPUT_LOAD='(-0.01,0.01)';
      OUTPUT_LOAD='(1.0,-1.0)';
      PINUSE='BI';
    'EN#':
      PIN_NUMBER='(B7)';
      INPUT_LOAD='(-0.01,0.01)';
      PINUSE='IN';
    'REG':
      PIN_NUMBER='(D1)';
      OUTPUT_LOAD='(1.0,-1.0)';
      PINUSE='OUT';
    'UV':
      PIN_NUMBER='(D2)';
      INPUT_LOAD='(-0.01,0.01)';
      PINUSE='IN';
    'OV':
      PIN_NUMBER='(D3)';
      INPUT_LOAD='(-0.01,0.01)';
      PINUSE='IN';
    'ISENSE':
      PIN_NUMBER='(A1)';
      OUTPUT_LOAD='(1.0,-1.0)';
      PINUSE='OUT';
    'OUT_A4':
      PIN_NUMBER='(A4)';
      OUTPUT_LOAD='(1.0,-1.0)';
      PINUSE='OUT';
    'OUT_B4':
      PIN_NUMBER='(B4)';
      OUTPUT_LOAD='(1.0,-1.0)';
      PINUSE='OUT';
    'OUT_B6':
      PIN_NUMBER='(B6)';
      OUTPUT_LOAD='(1.0,-1.0)';
      PINUSE='OUT';
    'OUT_C4':
      PIN_NUMBER='(C4)';
      OUTPUT_LOAD='(1.0,-1.0)';
      PINUSE='OUT';
    'OUT_C6':
      PIN_NUMBER='(C6)';
      OUTPUT_LOAD='(1.0,-1.0)';
      PINUSE='OUT';
    'OUT_D4':
      PIN_NUMBER='(D4)';
      OUTPUT_LOAD='(1.0,-1.0)';
      PINUSE='OUT';
    'OUT_D6':
      PIN_NUMBER='(D6)';
      OUTPUT_LOAD='(1.0,-1.0)';
      PINUSE='OUT';
    'GATE':
      PIN_NUMBER='(A6)';
      BIDIRECTIONAL='TRUE';
      INPUT_LOAD='(-0.01,0.01)';
      OUTPUT_LOAD='(1.0,-1.0)';
      PINUSE='BI';
    'CDLY':
      PIN_NUMBER='(A7)';
      INPUT_LOAD='(-0.01,0.01)';
      PINUSE='IN';
    'GND_B2':
      PIN_NUMBER='(B2)';
      PINUSE='POWER';
      NO_LOAD_CHECK='Both';
      NO_IO_CHECK='Both';
      NO_ASSERT_CHECK='TRUE';
      NO_DIR_CHECK='TRUE';
      ALLOW_CONNECT='TRUE';
    'GND_C1':
      PIN_NUMBER='(C1)';
      PINUSE='POWER';
      NO_LOAD_CHECK='Both';
      NO_IO_CHECK='Both';
      NO_ASSERT_CHECK='TRUE';
      NO_DIR_CHECK='TRUE';
      ALLOW_CONNECT='TRUE';
    'GND_C2':
      PIN_NUMBER='(C2)';
      PINUSE='POWER';
      NO_LOAD_CHECK='Both';
      NO_IO_CHECK='Both';
      NO_ASSERT_CHECK='TRUE';
      NO_DIR_CHECK='TRUE';
      ALLOW_CONNECT='TRUE';
    'FAULT#':
      PIN_NUMBER='(C7)';
      OUTPUT_LOAD='(1.0,-1.0)';
      PINUSE='OUT';
    'PG':
      PIN_NUMBER='(D7)';
      OUTPUT_LOAD='(1.0,-1.0)';
      PINUSE='OUT';
  end_pin;
  body
      PART_NAME='MAX15090BEWIT';
      BODY_NAME='MAX15090BEWIT';
      PHYS_DES_PREFIX='U';
      CLASS='IC';
      STANDARD='';
      LIFECYCLE='';
      JEDEC_TYPE='BGA28_0-5_3-525X2-065';
      DESCRIPTION='IC OTHER(28P)MAX15090BEWI+T(WLP)';
      MANUFTR='MAM';
      MANUF_PN='MAX15090BEWI+T';
      RD_CMPLS_LVL='EP(V1)';
      CMPLS_LVL='';
      FROM_PJ='UH3M-KEVIN';
      DIP_SMD='';
      DATA='MAM_MAX15090BEWI+T.pdf';
      EE_CHECK_LIST='';
      FP_ECN='';
      PSL='';
      CREATOR='';
      STATUS='';
      MSD='';
      ESD_CDM='';
      ESD_HBM='';
      ESD_MM='';
      PIN_LENGTH_SHORT_PIN='';
      PIN_LENGTH_LONG_PIN='';
      CREATEDAY='20160324';
      PARENT_PART_TYPE='MAX15090BEWIT';
      PARENT_PPT='MAX15090BEWIT';
      PARENT_PPT_PART='MAX15090BEWIT-MAX15090BEWI+T,SMLF,IC,AL015080B00';
  end_body;
end_primitive;
primitive 'ME_DUMMY_SYMBOL-CBS_3X558-8,MEA';
  pin
  end_pin;
  body
      PART_NAME='ME_DUMMY_SYMBOL';
      BODY_NAME='ME_DUMMY_SYMBOL';
      PHYS_DES_PREFIX='ME';
      CLASS='MECHANICAL';
      STANDARD='';
      LIFECYCLE='';
      JEDEC_TYPE='CBS_3X558-8';
      DESCRIPTION='CBS_3MMX558-8MM';
      MANUFTR='';
      MANUF_PN='';
      RD_CMPLS_LVL='';
      CMPLS_LVL='';
      DIP_SMD='';
      FROM_PJ='';
      DATA='';
      FP_ECN='';
      EE_CHECK_LIST='';
      PSL='';
      PREFERENCE='';
      CREATOR='';
      CREATEDAY='20170731';
      STATUS='';
      ESD_CDM='';
      ESD_HBM='';
      ESD_MM='';
      MSD='';
      PIN_LENGTH_LONG_PIN='';
      PIN_LENGTH_SHORT_PIN='';
      PARENT_PART_TYPE='ME_DUMMY_SYMBOL';
      PARENT_PPT='ME_DUMMY_SYMBOL';
      PARENT_PPT_PART='ME_DUMMY_SYMBOL-CBS_3X558-8,MECH,EMPTY,DUMMY47';
  end_body;
end_primitive;
primitive 'ME_DUMMY_SYMBOL-EFI BIOS LABELA';
  pin
  end_pin;
  body
      PART_NAME='ME_DUMMY_SYMBOL';
      BODY_NAME='ME_DUMMY_SYMBOL';
      PHYS_DES_PREFIX='ME';
      CLASS='MECHANICAL';
      STANDARD='';
      LIFECYCLE='';
      JEDEC_TYPE='BIOS-BMCLABEL_10-5X10-5';
      DESCRIPTION='EFI BIOS LABEL LU2(HCLU2002,REV3A)';
      MANUFTR='';
      MANUF_PN='';
      RD_CMPLS_LVL='';
      CMPLS_LVL='';
      DIP_SMD='';
      FROM_PJ='';
      DATA='';
      FP_ECN='';
      EE_CHECK_LIST='';
      PSL='';
      PREFERENCE='';
      CREATOR='';
      CREATEDAY='20160105';
      STATUS='';
      ESD_CDM='';
      ESD_HBM='';
      ESD_MM='';
      MSD='';
      PIN_LENGTH_LONG_PIN='';
      PIN_LENGTH_SHORT_PIN='';
      PARENT_PART_TYPE='ME_DUMMY_SYMBOL';
      PARENT_PPT='ME_DUMMY_SYMBOL';
      PARENT_PPT_PART='ME_DUMMY_SYMBOL-EFI BIOS LABEL,MECH,EMPTY,DUMMY28_HCLU2002010';
  end_body;
end_primitive;
primitive 'ME_DUMMY_SYMBOL-PB-E1_SMALL,MEA';
  pin
  end_pin;
  body
      PART_NAME='ME_DUMMY_SYMBOL';
      BODY_NAME='ME_DUMMY_SYMBOL';
      PHYS_DES_PREFIX='ME';
      CLASS='MECHANICAL';
      STANDARD='';
      LIFECYCLE='';
      JEDEC_TYPE='PB-E1_SMALL';
      DESCRIPTION='PB-E1_SMALL';
      MANUFTR='';
      MANUF_PN='';
      RD_CMPLS_LVL='';
      CMPLS_LVL='';
      DIP_SMD='';
      FROM_PJ='';
      DATA='';
      FP_ECN='';
      EE_CHECK_LIST='';
      PSL='';
      PREFERENCE='';
      CREATOR='';
      CREATEDAY='20210923';
      STATUS='';
      ESD_CDM='';
      ESD_HBM='';
      ESD_MM='';
      MSD='';
      PIN_LENGTH_LONG_PIN='';
      PIN_LENGTH_SHORT_PIN='';
      PARENT_PART_TYPE='ME_DUMMY_SYMBOL';
      PARENT_PPT='ME_DUMMY_SYMBOL';
      PARENT_PPT_PART='ME_DUMMY_SYMBOL-PB-E1_SMALL,MECH,EMPTY,DUMMY3';
  end_body;
end_primitive;
primitive 'ME_DUMMY_SYMBOL-PCB_VENDOR_LOGA';
  pin
  end_pin;
  body
      PART_NAME='ME_DUMMY_SYMBOL';
      BODY_NAME='ME_DUMMY_SYMBOL';
      PHYS_DES_PREFIX='ME';
      CLASS='MECHANICAL';
      STANDARD='';
      LIFECYCLE='';
      JEDEC_TYPE='PCB_VENDOR_LOGO_15X8';
      DESCRIPTION='PCB_VENDOR_LOGO_15X8';
      MANUFTR='';
      MANUF_PN='';
      RD_CMPLS_LVL='';
      CMPLS_LVL='';
      DIP_SMD='';
      FROM_PJ='';
      DATA='';
      FP_ECN='';
      EE_CHECK_LIST='';
      PSL='';
      PREFERENCE='';
      CREATOR='';
      CREATEDAY='20210923';
      STATUS='';
      ESD_CDM='';
      ESD_HBM='';
      ESD_MM='';
      MSD='';
      PIN_LENGTH_LONG_PIN='';
      PIN_LENGTH_SHORT_PIN='';
      PARENT_PART_TYPE='ME_DUMMY_SYMBOL';
      PARENT_PPT='ME_DUMMY_SYMBOL';
      PARENT_PPT_PART='ME_DUMMY_SYMBOL-PCB_VENDOR_LOGO_15X8,MECH,EMPTY,DUMMY7';
  end_body;
end_primitive;
primitive 'ME_DUMMY_SYMBOL-PICKUP_SMDC20,A';
  pin
  end_pin;
  body
      PART_NAME='ME_DUMMY_SYMBOL';
      BODY_NAME='ME_DUMMY_SYMBOL';
      PHYS_DES_PREFIX='ME';
      CLASS='MECHANICAL';
      STANDARD='';
      LIFECYCLE='';
      JEDEC_TYPE='PICKUP_SMDC20';
      DESCRIPTION='PICKUP_SMDC20';
      MANUFTR='';
      MANUF_PN='';
      RD_CMPLS_LVL='';
      CMPLS_LVL='';
      DIP_SMD='';
      FROM_PJ='';
      DATA='';
      FP_ECN='';
      EE_CHECK_LIST='';
      PSL='';
      PREFERENCE='';
      CREATOR='';
      CREATEDAY='20170731';
      STATUS='';
      ESD_CDM='';
      ESD_HBM='';
      ESD_MM='';
      MSD='';
      PIN_LENGTH_LONG_PIN='';
      PIN_LENGTH_SHORT_PIN='';
      PARENT_PART_TYPE='ME_DUMMY_SYMBOL';
      PARENT_PPT='ME_DUMMY_SYMBOL';
      PARENT_PPT_PART='ME_DUMMY_SYMBOL-PICKUP_SMDC20,MECH,EMPTY,DUMMY48';
  end_body;
end_primitive;
primitive 'ME_DUMMY_SYMBOL-QUANTA_LOGO_7XA';
  pin
  end_pin;
  body
      PART_NAME='ME_DUMMY_SYMBOL';
      BODY_NAME='ME_DUMMY_SYMBOL';
      PHYS_DES_PREFIX='ME';
      CLASS='MECHANICAL';
      STANDARD='';
      LIFECYCLE='';
      JEDEC_TYPE='QUANTA_LOGO_7X26';
      DESCRIPTION='QUANTA_LOGO_7X26';
      MANUFTR='';
      MANUF_PN='';
      RD_CMPLS_LVL='';
      CMPLS_LVL='';
      DIP_SMD='';
      FROM_PJ='';
      DATA='';
      FP_ECN='';
      EE_CHECK_LIST='';
      PSL='';
      PREFERENCE='';
      CREATOR='';
      CREATEDAY='20141104';
      STATUS='';
      ESD_CDM='';
      ESD_HBM='';
      ESD_MM='';
      MSD='';
      PIN_LENGTH_LONG_PIN='';
      PIN_LENGTH_SHORT_PIN='';
      PARENT_PART_TYPE='ME_DUMMY_SYMBOL';
      PARENT_PPT='ME_DUMMY_SYMBOL';
      PARENT_PPT_PART='ME_DUMMY_SYMBOL-QUANTA_LOGO_7X26,MECH,EMPTY,DUMMY1';
  end_body;
end_primitive;
primitive 'ME_DUMMY_SYMBOL-SNLABEL_15X5,MA';
  pin
  end_pin;
  body
      PART_NAME='ME_DUMMY_SYMBOL';
      BODY_NAME='ME_DUMMY_SYMBOL';
      PHYS_DES_PREFIX='ME';
      CLASS='MECHANICAL';
      STANDARD='';
      LIFECYCLE='';
      JEDEC_TYPE='SNLABEL_15X5';
      DESCRIPTION='SNLABEL_15X5';
      MANUFTR='';
      MANUF_PN='';
      RD_CMPLS_LVL='';
      CMPLS_LVL='';
      DIP_SMD='';
      FROM_PJ='STUDY-CANDY';
      DATA='';
      FP_ECN='SNLABEL_50-8X6-35 & SNLABEL_15X5.msg';
      EE_CHECK_LIST='';
      PSL='';
      PREFERENCE='';
      CREATOR='';
      CREATEDAY='20210923';
      STATUS='';
      ESD_CDM='';
      ESD_HBM='';
      ESD_MM='';
      MSD='';
      PIN_LENGTH_LONG_PIN='';
      PIN_LENGTH_SHORT_PIN='';
      PARENT_PART_TYPE='ME_DUMMY_SYMBOL';
      PARENT_PPT='ME_DUMMY_SYMBOL';
      PARENT_PPT_PART='ME_DUMMY_SYMBOL-SNLABEL_15X5,MECH,EMPTY,DUMMY36';
  end_body;
end_primitive;
primitive 'ME_DUMMY_SYMBOL-SNLABEL_27X6,MA';
  pin
  end_pin;
  body
      PART_NAME='ME_DUMMY_SYMBOL';
      BODY_NAME='ME_DUMMY_SYMBOL';
      PHYS_DES_PREFIX='ME';
      CLASS='MECHANICAL';
      STANDARD='';
      LIFECYCLE='';
      JEDEC_TYPE='SNLABEL_27X6';
      DESCRIPTION='SNLABEL_27X6';
      MANUFTR='';
      MANUF_PN='';
      RD_CMPLS_LVL='';
      CMPLS_LVL='';
      DIP_SMD='';
      FROM_PJ='';
      DATA='';
      FP_ECN='FW DFx of the PCB and PCBA Discussion.msg';
      EE_CHECK_LIST='';
      PSL='';
      PREFERENCE='';
      CREATOR='';
      CREATEDAY='20210923';
      STATUS='';
      ESD_CDM='';
      ESD_HBM='';
      ESD_MM='';
      MSD='';
      PIN_LENGTH_LONG_PIN='';
      PIN_LENGTH_SHORT_PIN='';
      PARENT_PART_TYPE='ME_DUMMY_SYMBOL';
      PARENT_PPT='ME_DUMMY_SYMBOL';
      PARENT_PPT_PART='ME_DUMMY_SYMBOL-SNLABEL_27X6,MECH,EMPTY,DUMMY46';
  end_body;
end_primitive;
primitive 'ME_DUMMY_SYMBOL-WEEE,MECH,EMPTA';
  pin
  end_pin;
  body
      PART_NAME='ME_DUMMY_SYMBOL';
      BODY_NAME='ME_DUMMY_SYMBOL';
      PHYS_DES_PREFIX='ME';
      CLASS='MECHANICAL';
      STANDARD='';
      LIFECYCLE='';
      JEDEC_TYPE='WEEE';
      DESCRIPTION='WEEE';
      MANUFTR='';
      MANUF_PN='';
      RD_CMPLS_LVL='';
      CMPLS_LVL='';
      DIP_SMD='';
      FROM_PJ='';
      DATA='';
      FP_ECN='';
      EE_CHECK_LIST='';
      PSL='';
      PREFERENCE='';
      CREATOR='';
      CREATEDAY='20141104';
      STATUS='';
      ESD_CDM='';
      ESD_HBM='';
      ESD_MM='';
      MSD='';
      PIN_LENGTH_LONG_PIN='';
      PIN_LENGTH_SHORT_PIN='';
      PARENT_PART_TYPE='ME_DUMMY_SYMBOL';
      PARENT_PPT='ME_DUMMY_SYMBOL';
      PARENT_PPT_PART='ME_DUMMY_SYMBOL-WEEE,MECH,EMPTY,DUMMY2';
  end_body;
end_primitive;
primitive 'MMBT3904_SMLF-MMBT3904    ,EMPA';
  pin
    '1':
      PIN_NUMBER='(B)';
      INPUT_LOAD='(-0.01,0.01)';
      PINUSE='IN';
    '2':
      PIN_NUMBER='(E)';
      INPUT_LOAD='(-0.01,0.01)';
      OUTPUT_LOAD='(1.0,-1.0)';
      BIDIRECTIONAL='TRUE';
      PINUSE='BI';
    '3':
      PIN_NUMBER='(C)';
      INPUT_LOAD='(-0.01,0.01)';
      OUTPUT_LOAD='(1.0,-1.0)';
      BIDIRECTIONAL='TRUE';
      PINUSE='BI';
  end_pin;
  body
      CLASS='IO';
      PART_NAME='MMBT3904';
      PHYS_DES_PREFIX='Q';
      STANDARD='End of Design';
      LIFECYCLE='Comp-Approve';
      ENVCOMP='YES';
      JEDEC_TYPE='SOT23_BEC';
      DESCRIPTION='TRANS SMD MMBT3904(40V,200MA)SOT23';
      HEIGHT='.044IN';
      COMPONENT_TYPE='SMALLSMT';
      LEAD_LENGTH='';
      LPID='';
      DAY='20100819';
      PARENT_PART_TYPE='MMBT3904';
      PARENT_PPT='MMBT3904';
      PARENT_PPT_PART='MMBT3904_SMLF-MMBT3904    ,EMPTY,BA039040039';
  end_body;
end_primitive;
primitive 'MOSFET_NCH_1D3S-PSMNR58-30YLH,A';
  pin
    '3':
      PIN_NUMBER='(3)';
      BIDIRECTIONAL='TRUE';
      INPUT_LOAD='(-0.01,0.01)';
      OUTPUT_LOAD='(1.0,-1.0)';
      PINUSE='BI';
    '5':
      PIN_NUMBER='(5)';
      BIDIRECTIONAL='TRUE';
      INPUT_LOAD='(-0.01,0.01)';
      OUTPUT_LOAD='(1.0,-1.0)';
      PINUSE='BI';
    '2':
      PIN_NUMBER='(2)';
      BIDIRECTIONAL='TRUE';
      INPUT_LOAD='(-0.01,0.01)';
      OUTPUT_LOAD='(1.0,-1.0)';
      PINUSE='BI';
    '4':
      PIN_NUMBER='(4)';
      INPUT_LOAD='(-0.01,0.01)';
      PINUSE='IN';
    '1':
      PIN_NUMBER='(1)';
      BIDIRECTIONAL='TRUE';
      INPUT_LOAD='(-0.01,0.01)';
      OUTPUT_LOAD='(1.0,-1.0)';
      PINUSE='BI';
  end_pin;
  body
      PART_NAME='MOSFET_NCH_1D3S';
      BODY_NAME='MOSFET_NCH_1D3S';
      JEDEC_TYPE='SOT1023';
      PHYS_DES_PREFIX='PQ';
      CLASS='IC';
      STANDARD='';
      LIFECYCLE='';
      DESCRIPTION='TRANS MOS PSMNR58-30YLH(30V,380A,333W)';
      MANUFTR='NXE';
      MANUF_PN='PSMNR58-30YLH';
      RD_CMPLS_LVL='EP(V1)';
      CMPLS_LVL='';
      DIP_SMD='';
      FP_ECN='';
      FROM_PJ='S5Z-MIKE';
      DATA='NXE_PSMNR58-30YLH.pdf';
      EE_CHECK_LIST='';
      STATUS='';
      PSL='';
      PREFERENCE='';
      CREATOR='';
      CREATEDAY='20190423';
      PARENT_PART_TYPE='MOSFET_NCH_1D3S';
      PARENT_PPT='MOSFET_NCH_1D3S';
      PARENT_PPT_PART='MOSFET_NCH_1D3S-PSMNR58-30YLH,SMLF,IC,BAMNR580000';
  end_body;
end_primitive;
primitive 'MOSFET_NCH_1D3S-PSMNR58-30YLH,B';
  pin
    '3':
      PIN_NUMBER='(3)';
      BIDIRECTIONAL='TRUE';
      INPUT_LOAD='(-0.01,0.01)';
      OUTPUT_LOAD='(1.0,-1.0)';
      PINUSE='BI';
    '5':
      PIN_NUMBER='(5)';
      BIDIRECTIONAL='TRUE';
      INPUT_LOAD='(-0.01,0.01)';
      OUTPUT_LOAD='(1.0,-1.0)';
      PINUSE='BI';
    '2':
      PIN_NUMBER='(2)';
      BIDIRECTIONAL='TRUE';
      INPUT_LOAD='(-0.01,0.01)';
      OUTPUT_LOAD='(1.0,-1.0)';
      PINUSE='BI';
    '4':
      PIN_NUMBER='(4)';
      INPUT_LOAD='(-0.01,0.01)';
      PINUSE='IN';
    '1':
      PIN_NUMBER='(1)';
      BIDIRECTIONAL='TRUE';
      INPUT_LOAD='(-0.01,0.01)';
      OUTPUT_LOAD='(1.0,-1.0)';
      PINUSE='BI';
  end_pin;
  body
      PART_NAME='MOSFET_NCH_1D3S';
      BODY_NAME='MOSFET_NCH_1D3S';
      JEDEC_TYPE='SOT1023';
      PHYS_DES_PREFIX='PQ';
      CLASS='IC';
      STANDARD='';
      LIFECYCLE='';
      DESCRIPTION='TRANS MOS PSMNR58-30YLH(30V,380A,333W)';
      MANUFTR='NXE';
      MANUF_PN='PSMNR58-30YLH';
      RD_CMPLS_LVL='EP(V1)';
      CMPLS_LVL='';
      DIP_SMD='';
      FP_ECN='';
      FROM_PJ='S5Z-MIKE';
      DATA='NXE_PSMNR58-30YLH.pdf';
      EE_CHECK_LIST='';
      STATUS='';
      PSL='';
      PREFERENCE='';
      CREATOR='';
      CREATEDAY='20190423';
      PARENT_PART_TYPE='MOSFET_NCH_1D3S';
      PARENT_PPT='MOSFET_NCH_1D3S';
      PARENT_PPT_PART='MOSFET_NCH_1D3S-PSMNR58-30YLH,SMLF,EMPTY,BAMNR580000';
  end_body;
end_primitive;
primitive 'MOSFET_NCH_DUAL-NX6008NBKS,SMLA';
  pin
    'S1':
      PIN_NUMBER='(1,0)';
      BIDIRECTIONAL='TRUE';
      INPUT_LOAD='(-0.01,0.01)';
      OUTPUT_LOAD='(1.0,-1.0)';
      PINUSE='BI';
    'G1':
      PIN_NUMBER='(2,0)';
      BIDIRECTIONAL='TRUE';
      INPUT_LOAD='(-0.01,0.01)';
      OUTPUT_LOAD='(1.0,-1.0)';
      PINUSE='BI';
    'D1':
      PIN_NUMBER='(6,0)';
      BIDIRECTIONAL='TRUE';
      INPUT_LOAD='(-0.01,0.01)';
      OUTPUT_LOAD='(1.0,-1.0)';
      PINUSE='BI';
    'D2':
      PIN_NUMBER='(0,3)';
      BIDIRECTIONAL='TRUE';
      INPUT_LOAD='(-0.01,0.01)';
      OUTPUT_LOAD='(1.0,-1.0)';
      PINUSE='BI';
    'G2':
      PIN_NUMBER='(0,5)';
      BIDIRECTIONAL='TRUE';
      INPUT_LOAD='(-0.01,0.01)';
      OUTPUT_LOAD='(1.0,-1.0)';
      PINUSE='BI';
    'S2':
      PIN_NUMBER='(0,4)';
      BIDIRECTIONAL='TRUE';
      INPUT_LOAD='(-0.01,0.01)';
      OUTPUT_LOAD='(1.0,-1.0)';
      PINUSE='BI';
  end_pin;
  body
      PART_NAME='MOSFET_NCH_DUAL';
      BODY_NAME='MOSFET_NCH_DUAL';
      PHYS_DES_PREFIX='Q';
      CLASS='IC';
      STANDARD='';
      LIFECYCLE='';
      JEDEC_TYPE='SOT363XB';
      DESCRIPTION='TRANS MOS NX6008NBKS(60V, 0.22A,260W)';
      MANUFTR='NXE';
      MANUF_PN='NX6008NBKS';
      RD_CMPLS_LVL='EP(V1)';
      CMPLS_LVL='';
      DIP_SMD='';
      FP_ECN='';
      FROM_PJ='F0T-IVES';
      DATA='NXE_NX6008NBKS.pdf';
      EE_CHECK_LIST='';
      PSL='';
      PREFERENCE='';
      CREATOR='';
      CREATEDAY='20210927';
      STATUS='';
      PARENT_PART_TYPE='MOSFET_NCH_DUAL';
      PARENT_PPT='MOSFET_NCH_DUAL';
      PARENT_PPT_PART='MOSFET_NCH_DUAL-NX6008NBKS,SMLF,IC,BAM60080000';
  end_body;
end_primitive;
primitive 'MOSFET_NCH_DUAL-PJT138K,SMLF,EA';
  pin
    'S1':
      PIN_NUMBER='(1,0)';
      BIDIRECTIONAL='TRUE';
      INPUT_LOAD='(-0.01,0.01)';
      OUTPUT_LOAD='(1.0,-1.0)';
      PINUSE='BI';
    'G1':
      PIN_NUMBER='(2,0)';
      BIDIRECTIONAL='TRUE';
      INPUT_LOAD='(-0.01,0.01)';
      OUTPUT_LOAD='(1.0,-1.0)';
      PINUSE='BI';
    'D1':
      PIN_NUMBER='(6,0)';
      BIDIRECTIONAL='TRUE';
      INPUT_LOAD='(-0.01,0.01)';
      OUTPUT_LOAD='(1.0,-1.0)';
      PINUSE='BI';
    'D2':
      PIN_NUMBER='(0,3)';
      BIDIRECTIONAL='TRUE';
      INPUT_LOAD='(-0.01,0.01)';
      OUTPUT_LOAD='(1.0,-1.0)';
      PINUSE='BI';
    'G2':
      PIN_NUMBER='(0,5)';
      BIDIRECTIONAL='TRUE';
      INPUT_LOAD='(-0.01,0.01)';
      OUTPUT_LOAD='(1.0,-1.0)';
      PINUSE='BI';
    'S2':
      PIN_NUMBER='(0,4)';
      BIDIRECTIONAL='TRUE';
      INPUT_LOAD='(-0.01,0.01)';
      OUTPUT_LOAD='(1.0,-1.0)';
      PINUSE='BI';
  end_pin;
  body
      PART_NAME='MOSFET_NCH_DUAL';
      BODY_NAME='MOSFET_NCH_DUAL';
      PHYS_DES_PREFIX='Q';
      CLASS='IC';
      STANDARD='';
      LIFECYCLE='';
      JEDEC_TYPE='SOT363XD';
      DESCRIPTION='TRANS MOSFET PJT138K(50V,0.36A,0.236W)';
      MANUFTR='PJT';
      MANUF_PN='PJT138K';
      RD_CMPLS_LVL='EP(V1)';
      CMPLS_LVL='EP(V1)';
      DIP_SMD='';
      FP_ECN='';
      FROM_PJ='F09-MARK';
      DATA='PJT_PJT138K_revJULY-25-2013.pdf';
      EE_CHECK_LIST='';
      PSL='';
      PREFERENCE='';
      CREATOR='';
      CREATEDAY='20160617';
      STATUS='';
      PARENT_PART_TYPE='MOSFET_NCH_DUAL';
      PARENT_PPT='MOSFET_NCH_DUAL';
      PARENT_PPT_PART='MOSFET_NCH_DUAL-PJT138K,SMLF,EMPTY,BAM138K0003';
  end_body;
end_primitive;
primitive 'MOSFET_NCH_DUAL-PJT138K,SMLF,IA';
  pin
    'S1':
      PIN_NUMBER='(1,0)';
      BIDIRECTIONAL='TRUE';
      INPUT_LOAD='(-0.01,0.01)';
      OUTPUT_LOAD='(1.0,-1.0)';
      PINUSE='BI';
    'G1':
      PIN_NUMBER='(2,0)';
      BIDIRECTIONAL='TRUE';
      INPUT_LOAD='(-0.01,0.01)';
      OUTPUT_LOAD='(1.0,-1.0)';
      PINUSE='BI';
    'D1':
      PIN_NUMBER='(6,0)';
      BIDIRECTIONAL='TRUE';
      INPUT_LOAD='(-0.01,0.01)';
      OUTPUT_LOAD='(1.0,-1.0)';
      PINUSE='BI';
    'D2':
      PIN_NUMBER='(0,3)';
      BIDIRECTIONAL='TRUE';
      INPUT_LOAD='(-0.01,0.01)';
      OUTPUT_LOAD='(1.0,-1.0)';
      PINUSE='BI';
    'G2':
      PIN_NUMBER='(0,5)';
      BIDIRECTIONAL='TRUE';
      INPUT_LOAD='(-0.01,0.01)';
      OUTPUT_LOAD='(1.0,-1.0)';
      PINUSE='BI';
    'S2':
      PIN_NUMBER='(0,4)';
      BIDIRECTIONAL='TRUE';
      INPUT_LOAD='(-0.01,0.01)';
      OUTPUT_LOAD='(1.0,-1.0)';
      PINUSE='BI';
  end_pin;
  body
      PART_NAME='MOSFET_NCH_DUAL';
      BODY_NAME='MOSFET_NCH_DUAL';
      PHYS_DES_PREFIX='Q';
      CLASS='IC';
      STANDARD='';
      LIFECYCLE='';
      JEDEC_TYPE='SOT363XD';
      DESCRIPTION='TRANS MOSFET PJT138K(50V,0.36A,0.236W)';
      MANUFTR='PJT';
      MANUF_PN='PJT138K';
      RD_CMPLS_LVL='EP(V1)';
      CMPLS_LVL='EP(V1)';
      DIP_SMD='';
      FP_ECN='';
      FROM_PJ='F09-MARK';
      DATA='PJT_PJT138K_revJULY-25-2013.pdf';
      EE_CHECK_LIST='';
      PSL='';
      PREFERENCE='';
      CREATOR='';
      CREATEDAY='20160617';
      STATUS='';
      PARENT_PART_TYPE='MOSFET_NCH_DUAL';
      PARENT_PPT='MOSFET_NCH_DUAL';
      PARENT_PPT_PART='MOSFET_NCH_DUAL-PJT138K,SMLF,IC,BAM138K0003';
  end_body;
end_primitive;
primitive 'MOSFET_NCH_GDS_ESD_PROTECTED-2A';
  pin
    'D':
      PIN_NUMBER='(D)';
      BIDIRECTIONAL='TRUE';
      INPUT_LOAD='(-0.01,0.01)';
      OUTPUT_LOAD='(1.0,-1.0)';
      PINUSE='BI';
    'G':
      PIN_NUMBER='(G)';
      INPUT_LOAD='(-0.01,0.01)';
      PINUSE='IN';
    'S':
      PIN_NUMBER='(S)';
      BIDIRECTIONAL='TRUE';
      INPUT_LOAD='(-0.01,0.01)';
      OUTPUT_LOAD='(1.0,-1.0)';
      PINUSE='BI';
  end_pin;
  body
      PART_NAME='MOSFET_NCH_GDS_ESD_PROTECTED';
      BODY_NAME='MOSFET_NCH_GDS_ESD_PROTECTED';
      PHYS_DES_PREFIX='U';
      CLASS='IC';
      STANDARD='';
      LIFECYCLE='';
      JEDEC_TYPE='SOT23_GDSXC';
      DESCRIPTION='TR MOSFET 2N7002K(60V,300MA,0.35W)SOT-23';
      MANUFTR='PJT';
      MANUF_PN='2N7002K';
      RD_CMPLS_LVL='EP(V1)';
      CMPLS_LVL='EP(V1)';
      DIP_SMD='';
      FP_ECN='';
      FROM_PJ='S1F-TONY';
      DATA='PJT_2N7002K.pdf';
      EE_CHECK_LIST='';
      STATUS='';
      PSL='';
      PREFERENCE='';
      CREATOR='';
      CREATEDAY='20140122';
      PARENT_PART_TYPE='MOSFET_NCH_GDS_ESD_PROTECTED';
      PARENT_PPT='MOSFET_NCH_GDS_ESD_PROTECTED';
      PARENT_PPT_PART='MOSFET_NCH_GDS_ESD_PROTECTED-2N7002K,SMLF,IC,BAM70020002';
  end_body;
end_primitive;
primitive 'MOSFET_NCH_GDS_ESD_PROTECTED-2B';
  pin
    'D':
      PIN_NUMBER='(D)';
      BIDIRECTIONAL='TRUE';
      INPUT_LOAD='(-0.01,0.01)';
      OUTPUT_LOAD='(1.0,-1.0)';
      PINUSE='BI';
    'G':
      PIN_NUMBER='(G)';
      INPUT_LOAD='(-0.01,0.01)';
      PINUSE='IN';
    'S':
      PIN_NUMBER='(S)';
      BIDIRECTIONAL='TRUE';
      INPUT_LOAD='(-0.01,0.01)';
      OUTPUT_LOAD='(1.0,-1.0)';
      PINUSE='BI';
  end_pin;
  body
      PART_NAME='MOSFET_NCH_GDS_ESD_PROTECTED';
      BODY_NAME='MOSFET_NCH_GDS_ESD_PROTECTED';
      PHYS_DES_PREFIX='U';
      CLASS='IC';
      STANDARD='';
      LIFECYCLE='';
      JEDEC_TYPE='SOT23_GDSXC';
      DESCRIPTION='TR MOSFET 2N7002K(60V,300MA,0.35W)SOT-23';
      MANUFTR='PJT';
      MANUF_PN='2N7002K';
      RD_CMPLS_LVL='EP(V1)';
      CMPLS_LVL='EP(V1)';
      DIP_SMD='';
      FP_ECN='';
      FROM_PJ='S1F-TONY';
      DATA='PJT_2N7002K.pdf';
      EE_CHECK_LIST='';
      STATUS='';
      PSL='';
      PREFERENCE='';
      CREATOR='';
      CREATEDAY='20140122';
      PARENT_PART_TYPE='MOSFET_NCH_GDS_ESD_PROTECTED';
      PARENT_PPT='MOSFET_NCH_GDS_ESD_PROTECTED';
      PARENT_PPT_PART='MOSFET_NCH_GDS_ESD_PROTECTED-2N7002K,SMLF,EMPTY,BAM70020002';
  end_body;
end_primitive;
primitive 'MOSFET_N_SMLF-BSS138K,BSS138K,A';
  pin
    'GATE':
      PIN_NUMBER='(G)';
      INPUT_LOAD='(-0.01,0.01)';
      PINUSE='IN';
    'DRAIN':
      PIN_NUMBER='(D)';
      OUTPUT_LOAD='(1.0,-1.0)';
      PINUSE='OUT';
    'SOURCE':
      PIN_NUMBER='(S)';
      INPUT_LOAD='(-0.01,0.01)';
      OUTPUT_LOAD='(1.0,-1.0)';
      BIDIRECTIONAL='TRUE';
      PINUSE='BI';
  end_pin;
  body
      PHYS_DES_PREFIX='U';
      CLASS='IC';
      PART_NAME='MOSFET_N';
      BODY_NAME='MOSFET_N';
      STANDARD='End of Design';
      LIFECYCLE='Comp-Approve';
      JEDEC_TYPE='SOT23_GDSXD';
      DESCRIPTION='TRANS MOS BSS138K(50V,0.22A,0.35W)';
      COMPONENT_TYPE='SMALLSMT';
      LEAD_LENGTH='';
      LPID='';
      DAY='20150826';
      PARENT_PART_TYPE='MOSFET_N';
      PARENT_PPT='MOSFET_N';
      PARENT_PPT_PART='MOSFET_N_SMLF-BSS138K,BSS138K,IC,BAM138K0000';
  end_body;
end_primitive;
primitive 'MOSFET_N_SMLF-BSS138K,BSS138K,B';
  pin
    'GATE':
      PIN_NUMBER='(G)';
      INPUT_LOAD='(-0.01,0.01)';
      PINUSE='IN';
    'DRAIN':
      PIN_NUMBER='(D)';
      OUTPUT_LOAD='(1.0,-1.0)';
      PINUSE='OUT';
    'SOURCE':
      PIN_NUMBER='(S)';
      INPUT_LOAD='(-0.01,0.01)';
      OUTPUT_LOAD='(1.0,-1.0)';
      BIDIRECTIONAL='TRUE';
      PINUSE='BI';
  end_pin;
  body
      PHYS_DES_PREFIX='U';
      CLASS='IO';
      PART_NAME='MOSFET_N';
      BODY_NAME='MOSFET_N';
      STANDARD='End of Design';
      LIFECYCLE='Comp-Approve';
      JEDEC_TYPE='SOT23_GDSXD';
      DESCRIPTION='TRANS MOS BSS138K(50V,0.22A,0.35W)';
      COMPONENT_TYPE='SMALLSMT';
      LEAD_LENGTH='';
      LPID='';
      DAY='20150826';
      PARENT_PART_TYPE='MOSFET_N';
      PARENT_PPT='MOSFET_N';
      PARENT_PPT_PART='MOSFET_N_SMLF-BSS138K,BSS138K,EMPTY,BAM138K0000';
  end_body;
end_primitive;
primitive 'MP5016GQHLZ-MP5016GQH-L-Z,SMLFA';
  pin
    'EN':
      PIN_NUMBER='(9)';
      INPUT_LOAD='(-0.01,0.01)';
      PINUSE='IN';
    'MODE':
      PIN_NUMBER='(5)';
      INPUT_LOAD='(-0.01,0.01)';
      PINUSE='IN';
    'ILIMIT':
      PIN_NUMBER='(4)';
      OUTPUT_LOAD='(1.0,-1.0)';
      PINUSE='OUT';
    'GND':
      PIN_NUMBER='(3)';
      PINUSE='POWER';
      NO_LOAD_CHECK='Both';
      NO_IO_CHECK='Both';
      NO_ASSERT_CHECK='TRUE';
      NO_DIR_CHECK='TRUE';
      ALLOW_CONNECT='TRUE';
    'VCC':
      PIN_NUMBER='(1_2)';
      PINUSE='POWER';
      NO_LOAD_CHECK='Both';
      NO_IO_CHECK='Both';
      NO_ASSERT_CHECK='TRUE';
      NO_DIR_CHECK='TRUE';
      ALLOW_CONNECT='TRUE';
    'DV_DT':
      PIN_NUMBER='(10)';
      OUTPUT_LOAD='(1.0,-1.0)';
      PINUSE='OUT';
    'GATE':
      PIN_NUMBER='(8)';
      OUTPUT_LOAD='(1.0,-1.0)';
      PINUSE='OUT';
    'SOURCE':
      PIN_NUMBER='(6_7)';
      OUTPUT_LOAD='(1.0,-1.0)';
      PINUSE='OUT';
  end_pin;
  body
      PART_NAME='MP5016GQHLZ';
      BODY_NAME='MP5016GQHLZ';
      PHYS_DES_PREFIX='U';
      CLASS='IC';
      STANDARD='';
      LIFECYCLE='';
      JEDEC_TYPE='QFN8_2X1-5';
      DESCRIPTION='IC (10P) MP5016GQH-L-Z(QFN)';
      MANUFTR='MPS';
      MANUF_PN='MP5016GQH-L-Z';
      RD_CMPLS_LVL='EP(V1)';
      CMPLS_LVL='EP(V1)';
      FROM_PJ='F0CE-SAM';
      DIP_SMD='';
      DATA='MPS_MP5016GQH-L-Z.pdf';
      EE_CHECK_LIST='';
      FP_ECN='';
      PSL='';
      CREATOR='';
      STATUS='';
      MSD='';
      ESD_CDM='';
      ESD_HBM='';
      ESD_MM='';
      PIN_LENGTH_SHORT_PIN='0 MILS';
      PIN_LENGTH_LONG_PIN='0 MILS';
      CREATEDAY='20210519';
      PARENT_PART_TYPE='MP5016GQHLZ';
      PARENT_PPT='MP5016GQHLZ';
      PARENT_PPT_PART='MP5016GQHLZ-MP5016GQH-L-Z,SMLF,EMPTY,AL005016007';
  end_body;
end_primitive;
primitive 'MP5990GMA1111Z-MP5990GMA-1111-A';
  pin
    'VOUT3':
      PIN_NUMBER='(29)';
      OUTPUT_LOAD='(1.0,-1.0)';
      PINUSE='OUT';
    'VOUT2':
      PIN_NUMBER='(28)';
      OUTPUT_LOAD='(1.0,-1.0)';
      PINUSE='OUT';
    'VOUT1':
      PIN_NUMBER='(27)';
      OUTPUT_LOAD='(1.0,-1.0)';
      PINUSE='OUT';
    'VIN2':
      PIN_NUMBER='(2)';
      INPUT_LOAD='(-0.01,0.01)';
      PINUSE='IN';
    'EN':
      PIN_NUMBER='(26)';
      INPUT_LOAD='(-0.01,0.01)';
      PINUSE='IN';
    'VIN3':
      PIN_NUMBER='(3)';
      INPUT_LOAD='(-0.01,0.01)';
      PINUSE='IN';
    'VIN4':
      PIN_NUMBER='(4)';
      INPUT_LOAD='(-0.01,0.01)';
      PINUSE='IN';
    'GND1':
      PIN_NUMBER='(18)';
      PINUSE='POWER';
      NO_LOAD_CHECK='Both';
      NO_IO_CHECK='Both';
      NO_ASSERT_CHECK='TRUE';
      NO_DIR_CHECK='TRUE';
      ALLOW_CONNECT='TRUE';
    'SDA':
      PIN_NUMBER='(12)';
      BIDIRECTIONAL='TRUE';
      INPUT_LOAD='(-0.01,0.01)';
      OUTPUT_LOAD='(1.0,-1.0)';
      PINUSE='BI';
    'VIN_UVW#':
      PIN_NUMBER='(14)';
      OUTPUT_LOAD='(1.0,-1.0)';
      PINUSE='OUT';
    'SCL':
      PIN_NUMBER='(11)';
      INPUT_LOAD='(-0.01,0.01)';
      PINUSE='IN';
    'D_OC':
      PIN_NUMBER='(37)';
      OUTPUT_LOAD='(1.0,-1.0)';
      PINUSE='OUT';
    'VOUT5':
      PIN_NUMBER='(31)';
      OUTPUT_LOAD='(1.0,-1.0)';
      PINUSE='OUT';
    'VOUT9':
      PIN_NUMBER='(35)';
      OUTPUT_LOAD='(1.0,-1.0)';
      PINUSE='OUT';
    'ALT#':
      PIN_NUMBER='(10)';
      OUTPUT_LOAD='(1.0,-1.0)';
      PINUSE='OUT';
    'GOK':
      PIN_NUMBER='(39)';
      BIDIRECTIONAL='TRUE';
      INPUT_LOAD='(-0.01,0.01)';
      OUTPUT_LOAD='(1.0,-1.0)';
      PINUSE='BI';
    'VIN7':
      PIN_NUMBER='(7)';
      INPUT_LOAD='(-0.01,0.01)';
      PINUSE='IN';
    'VOUT7':
      PIN_NUMBER='(33)';
      OUTPUT_LOAD='(1.0,-1.0)';
      PINUSE='OUT';
    'MODE':
      PIN_NUMBER='(41)';
      INPUT_LOAD='(-0.01,0.01)';
      PINUSE='IN';
    'VIN8':
      PIN_NUMBER='(8)';
      INPUT_LOAD='(-0.01,0.01)';
      PINUSE='IN';
    'PG||OCW#':
      PIN_NUMBER='(13)';
      OUTPUT_LOAD='(1.0,-1.0)';
      PINUSE='OUT';
    'VOUT8':
      PIN_NUMBER='(34)';
      OUTPUT_LOAD='(1.0,-1.0)';
      PINUSE='OUT';
    'ON':
      PIN_NUMBER='(38)';
      OUTPUT_LOAD='(1.0,-1.0)';
      PINUSE='OUT';
    'VIN5':
      PIN_NUMBER='(5)';
      INPUT_LOAD='(-0.01,0.01)';
      PINUSE='IN';
    'VIN6':
      PIN_NUMBER='(6)';
      INPUT_LOAD='(-0.01,0.01)';
      PINUSE='IN';
    'VTEMP':
      PIN_NUMBER='(15)';
      INPUT_LOAD='(-0.01,0.01)';
      PINUSE='IN';
    'OCREF':
      PIN_NUMBER='(22)';
      OUTPUT_LOAD='(1.0,-1.0)';
      PINUSE='OUT';
    'SCREF_OCWREF':
      PIN_NUMBER='(25)';
      OUTPUT_LOAD='(1.0,-1.0)';
      PINUSE='OUT';
    'SS':
      PIN_NUMBER='(16)';
      OUTPUT_LOAD='(1.0,-1.0)';
      PINUSE='OUT';
    'VOUT6':
      PIN_NUMBER='(32)';
      OUTPUT_LOAD='(1.0,-1.0)';
      PINUSE='OUT';
    'IMON':
      PIN_NUMBER='(21)';
      BIDIRECTIONAL='TRUE';
      INPUT_LOAD='(-0.01,0.01)';
      OUTPUT_LOAD='(1.0,-1.0)';
      PINUSE='BI';
    'CS':
      PIN_NUMBER='(20)';
      OUTPUT_LOAD='(1.0,-1.0)';
      PINUSE='OUT';
    'VIN9':
      PIN_NUMBER='(42)';
      INPUT_LOAD='(-0.01,0.01)';
      PINUSE='IN';
    'VOUT10':
      PIN_NUMBER='(36)';
      OUTPUT_LOAD='(1.0,-1.0)';
      PINUSE='OUT';
    'VOSEN':
      PIN_NUMBER='(24)';
      INPUT_LOAD='(-0.01,0.01)';
      PINUSE='IN';
    'VOUT4':
      PIN_NUMBER='(30)';
      OUTPUT_LOAD='(1.0,-1.0)';
      PINUSE='OUT';
    'VIN1':
      PIN_NUMBER='(1)';
      INPUT_LOAD='(-0.01,0.01)';
      PINUSE='IN';
    'GND2':
      PIN_NUMBER='(44)';
      PINUSE='POWER';
      NO_LOAD_CHECK='Both';
      NO_IO_CHECK='Both';
      NO_ASSERT_CHECK='TRUE';
      NO_DIR_CHECK='TRUE';
      ALLOW_CONNECT='TRUE';
    'FLT_TYPE':
      PIN_NUMBER='(40)';
      INPUT_LOAD='(-0.01,0.01)';
      PINUSE='IN';
    'VIN10':
      PIN_NUMBER='(43)';
      INPUT_LOAD='(-0.01,0.01)';
      PINUSE='IN';
    'VINSEN':
      PIN_NUMBER='(9)';
      INPUT_LOAD='(-0.01,0.01)';
      PINUSE='IN';
    'VDD33_1':
      PIN_NUMBER='(17)';
      PINUSE='POWER';
      NO_LOAD_CHECK='Both';
      NO_IO_CHECK='Both';
      NO_ASSERT_CHECK='TRUE';
      NO_DIR_CHECK='TRUE';
      ALLOW_CONNECT='TRUE';
    'VDD33_2':
      PIN_NUMBER='(45)';
      PINUSE='POWER';
      NO_LOAD_CHECK='Both';
      NO_IO_CHECK='Both';
      NO_ASSERT_CHECK='TRUE';
      NO_DIR_CHECK='TRUE';
      ALLOW_CONNECT='TRUE';
    'VDD18':
      PIN_NUMBER='(19)';
      PINUSE='POWER';
      NO_LOAD_CHECK='Both';
      NO_IO_CHECK='Both';
      NO_ASSERT_CHECK='TRUE';
      NO_DIR_CHECK='TRUE';
      ALLOW_CONNECT='TRUE';
    'ADDR':
      PIN_NUMBER='(23)';
      INPUT_LOAD='(-0.01,0.01)';
      PINUSE='IN';
  end_pin;
  body
      PART_NAME='MP5990GMA1111Z';
      BODY_NAME='MP5990GMA1111Z';
      PHYS_DES_PREFIX='U';
      CLASS='IC';
      STANDARD='';
      LIFECYCLE='';
      JEDEC_TYPE='LGA45_TH_0-45_7X5';
      DESCRIPTION='IC(45P)MP5990GMA-1111-Z(LGA)';
      MANUFTR='MPS';
      MANUF_PN='MP5990GMA-1111-Z';
      RD_CMPLS_LVL='EP(V1)';
      CMPLS_LVL='';
      FROM_PJ='F0T-WILL';
      DIP_SMD='';
      DATA='MPS_MP5990GMA-1111-Z.pdf';
      EE_CHECK_LIST='';
      FP_ECN='';
      PSL='';
      CREATOR='';
      STATUS='';
      MSD='';
      ESD_CDM='';
      ESD_HBM='';
      ESD_MM='';
      PIN_LENGTH_SHORT_PIN='0 MILS';
      PIN_LENGTH_LONG_PIN='0 MILS';
      CREATEDAY='20211122';
      PARENT_PART_TYPE='MP5990GMA1111Z';
      PARENT_PPT='MP5990GMA1111Z';
      PARENT_PPT_PART='MP5990GMA1111Z-MP5990GMA-1111-Z,SMLF,IC,AL005990A03';
  end_body;
end_primitive;
primitive 'MP5991GLUZ-MP5991GLU-Z,SMLF,ICA';
  pin
    'VIN1':
      PIN_NUMBER='(9)';
      INPUT_LOAD='(-0.01,0.01)';
      PINUSE='IN';
    'VIN2':
      PIN_NUMBER='(10)';
      INPUT_LOAD='(-0.01,0.01)';
      PINUSE='IN';
    'VIN3':
      PIN_NUMBER='(11)';
      INPUT_LOAD='(-0.01,0.01)';
      PINUSE='IN';
    'VIN4':
      PIN_NUMBER='(12)';
      INPUT_LOAD='(-0.01,0.01)';
      PINUSE='IN';
    'VIN5':
      PIN_NUMBER='(13)';
      INPUT_LOAD='(-0.01,0.01)';
      PINUSE='IN';
    'ON':
      PIN_NUMBER='(4)';
      INPUT_LOAD='(-0.01,0.01)';
      PINUSE='IN';
    'OCREF':
      PIN_NUMBER='(24)';
      OUTPUT_LOAD='(1.0,-1.0)';
      PINUSE='OUT';
    'CS':
      PIN_NUMBER='(23)';
      OUTPUT_LOAD='(1.0,-1.0)';
      PINUSE='OUT';
    'IMON':
      PIN_NUMBER='(22)';
      OUTPUT_LOAD='(1.0,-1.0)';
      PINUSE='OUT';
    'VDD33':
      PIN_NUMBER='(21)';
      PINUSE='POWER';
      NO_LOAD_CHECK='Both';
      NO_IO_CHECK='Both';
      NO_ASSERT_CHECK='TRUE';
      NO_DIR_CHECK='TRUE';
      ALLOW_CONNECT='TRUE';
    'GND':
      PIN_NUMBER='(20)';
      PINUSE='POWER';
      NO_LOAD_CHECK='Both';
      NO_IO_CHECK='Both';
      NO_ASSERT_CHECK='TRUE';
      NO_DIR_CHECK='TRUE';
      ALLOW_CONNECT='TRUE';
    'SS':
      PIN_NUMBER='(19)';
      INPUT_LOAD='(-0.01,0.01)';
      PINUSE='IN';
    'GOK':
      PIN_NUMBER='(5)';
      OUTPUT_LOAD='(1.0,-1.0)';
      PINUSE='OUT';
    'VTEMP':
      PIN_NUMBER='(18)';
      OUTPUT_LOAD='(1.0,-1.0)';
      PINUSE='OUT';
    'VOUT1':
      PIN_NUMBER='(1)';
      OUTPUT_LOAD='(1.0,-1.0)';
      PINUSE='OUT';
    'VOUT2':
      PIN_NUMBER='(2)';
      OUTPUT_LOAD='(1.0,-1.0)';
      PINUSE='OUT';
    'VOUT3':
      PIN_NUMBER='(25)';
      OUTPUT_LOAD='(1.0,-1.0)';
      PINUSE='OUT';
    'VOUT4':
      PIN_NUMBER='(26)';
      OUTPUT_LOAD='(1.0,-1.0)';
      PINUSE='OUT';
    'D_OC':
      PIN_NUMBER='(3)';
      OUTPUT_LOAD='(1.0,-1.0)';
      PINUSE='OUT';
    'VIN6':
      PIN_NUMBER='(14)';
      INPUT_LOAD='(-0.01,0.01)';
      PINUSE='IN';
    'VIN7':
      PIN_NUMBER='(15)';
      INPUT_LOAD='(-0.01,0.01)';
      PINUSE='IN';
    'VIN8':
      PIN_NUMBER='(16)';
      INPUT_LOAD='(-0.01,0.01)';
      PINUSE='IN';
    'VIN9':
      PIN_NUMBER='(33)';
      INPUT_LOAD='(-0.01,0.01)';
      PINUSE='IN';
    'VOUT5':
      PIN_NUMBER='(27)';
      OUTPUT_LOAD='(1.0,-1.0)';
      PINUSE='OUT';
    'VOUT6':
      PIN_NUMBER='(28)';
      OUTPUT_LOAD='(1.0,-1.0)';
      PINUSE='OUT';
    'VOUT7':
      PIN_NUMBER='(29)';
      OUTPUT_LOAD='(1.0,-1.0)';
      PINUSE='OUT';
    'VOUT8':
      PIN_NUMBER='(30)';
      OUTPUT_LOAD='(1.0,-1.0)';
      PINUSE='OUT';
    'VOUT9':
      PIN_NUMBER='(31)';
      OUTPUT_LOAD='(1.0,-1.0)';
      PINUSE='OUT';
    'VOUT10':
      PIN_NUMBER='(32)';
      OUTPUT_LOAD='(1.0,-1.0)';
      PINUSE='OUT';
    'MODE':
      PIN_NUMBER='(8)';
      INPUT_LOAD='(-0.01,0.01)';
      PINUSE='IN';
    'SCREF_OCWREF':
      PIN_NUMBER='(17)';
      INPUT_LOAD='(-0.01,0.01)';
      PINUSE='IN';
    'FLT_TYPE':
      PIN_NUMBER='(6)';
      INPUT_LOAD='(-0.01,0.01)';
      PINUSE='IN';
    'NC1':
      PIN_NUMBER='(7)';
      OUTPUT_TYPE='(TS,TS)';
      INPUT_LOAD='(-0.01,0.01)';
      OUTPUT_LOAD='(1.0,-1.0)';
      PINUSE='TRI';
  end_pin;
  body
      PART_NAME='MP5991GLUZ';
      BODY_NAME='MP5991GLUZ';
      PHYS_DES_PREFIX='U';
      CLASS='IC';
      STANDARD='';
      LIFECYCLE='';
      JEDEC_TYPE='LGA32_TH_0-5_5X5';
      DESCRIPTION='IC(32P)MP5991GLU-Z(LGA)';
      MANUFTR='MPS';
      MANUF_PN='MP5991GLU-Z';
      RD_CMPLS_LVL='EP(V1)';
      CMPLS_LVL='';
      FROM_PJ='F0E-GREG';
      DIP_SMD='';
      DATA='MPS_MP5991GLU-Z.pdf';
      EE_CHECK_LIST='';
      FP_ECN='';
      PSL='';
      CREATOR='';
      STATUS='';
      MSD='';
      ESD_CDM='';
      ESD_HBM='';
      ESD_MM='';
      PIN_LENGTH_SHORT_PIN='0 MILS';
      PIN_LENGTH_LONG_PIN='0 MILS';
      CREATEDAY='20211019';
      PARENT_PART_TYPE='MP5991GLUZ';
      PARENT_PPT='MP5991GLUZ';
      PARENT_PPT_PART='MP5991GLUZ-MP5991GLU-Z,SMLF,IC,AL005991A00';
  end_body;
end_primitive;
primitive 'NB682GDZ-NB682GD-Z,SMLF,IC,AL0A';
  pin
    'VIN':
      PIN_NUMBER='(1)';
      PINUSE='POWER';
      NO_LOAD_CHECK='Both';
      NO_IO_CHECK='Both';
      NO_ASSERT_CHECK='TRUE';
      NO_DIR_CHECK='TRUE';
      ALLOW_CONNECT='TRUE';
    'PG':
      PIN_NUMBER='(13)';
      OUTPUT_LOAD='(1.0,-1.0)';
      PINUSE='OUT';
    'PGND':
      PIN_NUMBER='(2)';
      PINUSE='POWER';
      NO_LOAD_CHECK='Both';
      NO_IO_CHECK='Both';
      NO_ASSERT_CHECK='TRUE';
      NO_DIR_CHECK='TRUE';
      ALLOW_CONNECT='TRUE';
    'EN':
      PIN_NUMBER='(5)';
      INPUT_LOAD='(-0.01,0.01)';
      PINUSE='IN';
    'BST':
      PIN_NUMBER='(9)';
      PINUSE='POWER';
      NO_LOAD_CHECK='Both';
      NO_IO_CHECK='Both';
      NO_ASSERT_CHECK='TRUE';
      NO_DIR_CHECK='TRUE';
      ALLOW_CONNECT='TRUE';
    'AGND':
      PIN_NUMBER='(11)';
      PINUSE='POWER';
      NO_LOAD_CHECK='Both';
      NO_IO_CHECK='Both';
      NO_ASSERT_CHECK='TRUE';
      NO_DIR_CHECK='TRUE';
      ALLOW_CONNECT='TRUE';
    'LP#':
      PIN_NUMBER='(6)';
      INPUT_LOAD='(-0.01,0.01)';
      PINUSE='IN';
    'C1':
      PIN_NUMBER='(3)';
      INPUT_LOAD='(-0.01,0.01)';
      PINUSE='IN';
    'C0':
      PIN_NUMBER='(4)';
      INPUT_LOAD='(-0.01,0.01)';
      PINUSE='IN';
    'MODE':
      PIN_NUMBER='(7)';
      INPUT_LOAD='(-0.01,0.01)';
      PINUSE='IN';
    'VOUT':
      PIN_NUMBER='(12)';
      PINUSE='POWER';
      NO_LOAD_CHECK='Both';
      NO_IO_CHECK='Both';
      NO_ASSERT_CHECK='TRUE';
      NO_DIR_CHECK='TRUE';
      ALLOW_CONNECT='TRUE';
    'SW':
      PIN_NUMBER='(8)';
      PINUSE='POWER';
      NO_LOAD_CHECK='Both';
      NO_IO_CHECK='Both';
      NO_ASSERT_CHECK='TRUE';
      NO_DIR_CHECK='TRUE';
      ALLOW_CONNECT='TRUE';
    '3V3':
      PIN_NUMBER='(10)';
      PINUSE='POWER';
      NO_LOAD_CHECK='Both';
      NO_IO_CHECK='Both';
      NO_ASSERT_CHECK='TRUE';
      NO_DIR_CHECK='TRUE';
      ALLOW_CONNECT='TRUE';
  end_pin;
  body
      PART_NAME='NB682GDZ';
      BODY_NAME='NB682GDZ';
      PHYS_DES_PREFIX='U';
      CLASS='IC';
      STANDARD='';
      LIFECYCLE='';
      JEDEC_TYPE='QFN13_2X3';
      DESCRIPTION='IC CTRL(13P)NB682GD-Z(QFN)';
      MANUFTR='MPS';
      MANUF_PN='NB682GD-Z';
      RD_CMPLS_LVL='EP(V1)';
      CMPLS_LVL='';
      FROM_PJ='S5T-GREG';
      DIP_SMD='';
      DATA='MPS_NB682GD-Z.pdf';
      EE_CHECK_LIST='';
      FP_ECN='';
      PSL='';
      CREATOR='';
      STATUS='';
      MSD='NA';
      ESD_CDM='NA';
      ESD_HBM='NA';
      ESD_MM='NA';
      PIN_LENGTH_SHORT_PIN='0 MILS';
      PIN_LENGTH_LONG_PIN='0 MILS';
      CREATEDAY='20171019';
      PARENT_PART_TYPE='NB682GDZ';
      PARENT_PPT='NB682GDZ';
      PARENT_PPT_PART='NB682GDZ-NB682GD-Z,SMLF,IC,AL000682001';
  end_body;
end_primitive;
primitive 'NC7SB3157_SMLF-NC7SB3157P6X,NCA';
  pin
    'B1':
      PIN_NUMBER='(1)';
      INPUT_LOAD='(-0.01,0.01)';
      OUTPUT_LOAD='(1.0,-1.0)';
      BIDIRECTIONAL='TRUE';
      PINUSE='BI';
    'GND':
      PIN_NUMBER='(2)';
      PINUSE='POWER';
    'B0':
      PIN_NUMBER='(3)';
      INPUT_LOAD='(-0.01,0.01)';
      OUTPUT_LOAD='(1.0,-1.0)';
      BIDIRECTIONAL='TRUE';
      PINUSE='BI';
    'S':
      PIN_NUMBER='(6)';
      INPUT_LOAD='(-0.01,0.01)';
      PINUSE='IN';
    'VCC':
      PIN_NUMBER='(5)';
      PINUSE='POWER';
    'A':
      PIN_NUMBER='(4)';
      INPUT_LOAD='(-0.01,0.01)';
      OUTPUT_LOAD='(1.0,-1.0)';
      BIDIRECTIONAL='TRUE';
      PINUSE='BI';
  end_pin;
  body
      PHYS_DES_PREFIX='U';
      CLASS='IC';
      PART_NAME='NC7SB3157';
      BODY_NAME='NC7SB3157';
      STANDARD='End of Design';
      LIFECYCLE='Comp-Approve';
      ENVCOMP='YES';
      JEDEC_TYPE='SC70-6';
      DESCRIPTION='IC(6P) NC7SB3157P6X(SC70-6)';
      HEIGHT='.044IN';
      COMPONENT_TYPE='SMALLSMT';
      LEAD_LENGTH='';
      LPID='';
      DAY='20100709';
      PARENT_PART_TYPE='NC7SB3157';
      PARENT_PPT='NC7SB3157';
      PARENT_PPT_PART='NC7SB3157_SMLF-NC7SB3157P6X,NC7SB3157P6X,IC,ALSB3157000';
  end_body;
end_primitive;
primitive 'NC7SB3157_SMLF-NC7SB3157P6X,NCB';
  pin
    'B1':
      PIN_NUMBER='(1)';
      INPUT_LOAD='(-0.01,0.01)';
      OUTPUT_LOAD='(1.0,-1.0)';
      BIDIRECTIONAL='TRUE';
      PINUSE='BI';
    'GND':
      PIN_NUMBER='(2)';
      PINUSE='POWER';
    'B0':
      PIN_NUMBER='(3)';
      INPUT_LOAD='(-0.01,0.01)';
      OUTPUT_LOAD='(1.0,-1.0)';
      BIDIRECTIONAL='TRUE';
      PINUSE='BI';
    'S':
      PIN_NUMBER='(6)';
      INPUT_LOAD='(-0.01,0.01)';
      PINUSE='IN';
    'VCC':
      PIN_NUMBER='(5)';
      PINUSE='POWER';
    'A':
      PIN_NUMBER='(4)';
      INPUT_LOAD='(-0.01,0.01)';
      OUTPUT_LOAD='(1.0,-1.0)';
      BIDIRECTIONAL='TRUE';
      PINUSE='BI';
  end_pin;
  body
      PHYS_DES_PREFIX='U';
      CLASS='IO';
      PART_NAME='NC7SB3157';
      BODY_NAME='NC7SB3157';
      STANDARD='End of Design';
      LIFECYCLE='Comp-Approve';
      ENVCOMP='YES';
      JEDEC_TYPE='SC70-6';
      DESCRIPTION='IC(6P) NC7SB3157P6X(SC70-6)';
      HEIGHT='.044IN';
      COMPONENT_TYPE='SMALLSMT';
      LEAD_LENGTH='';
      LPID='';
      DAY='20100709';
      PARENT_PART_TYPE='NC7SB3157';
      PARENT_PPT='NC7SB3157';
      PARENT_PPT_PART='NC7SB3157_SMLF-NC7SB3157P6X,NC7SB3157P6X,EMPTY,ALSB3157000';
  end_body;
end_primitive;
primitive 'NCT7718W-NCT7718W,SMLF,EMPTY,AA';
  pin
    'VDD':
      PIN_NUMBER='(1)';
      PINUSE='POWER';
      NO_LOAD_CHECK='Both';
      NO_IO_CHECK='Both';
      NO_ASSERT_CHECK='TRUE';
      NO_DIR_CHECK='TRUE';
      ALLOW_CONNECT='TRUE';
    'D+':
      PIN_NUMBER='(2)';
      INPUT_LOAD='(-0.01,0.01)';
      PINUSE='IN';
    'D-':
      PIN_NUMBER='(3)';
      INPUT_LOAD='(-0.01,0.01)';
      PINUSE='IN';
    'T_CRIT#':
      PIN_NUMBER='(4)';
      OUTPUT_TYPE='(OC,AND)';
      OUTPUT_LOAD='(1.0,*)';
      PINUSE='OCA';
    'GND':
      PIN_NUMBER='(5)';
      PINUSE='POWER';
      NO_LOAD_CHECK='Both';
      NO_IO_CHECK='Both';
      NO_ASSERT_CHECK='TRUE';
      NO_DIR_CHECK='TRUE';
      ALLOW_CONNECT='TRUE';
    'ALERT#':
      PIN_NUMBER='(6)';
      OUTPUT_TYPE='(OC,AND)';
      OUTPUT_LOAD='(1.0,*)';
      PINUSE='OCA';
    'SDA':
      PIN_NUMBER='(7)';
      BIDIRECTIONAL='TRUE';
      INPUT_LOAD='(-0.01,0.01)';
      OUTPUT_LOAD='(1.0,-1.0)';
      PINUSE='BI';
    'SCL':
      PIN_NUMBER='(8)';
      INPUT_LOAD='(-0.01,0.01)';
      PINUSE='IN';
  end_pin;
  body
      PART_NAME='NCT7718W';
      BODY_NAME='NCT7718W';
      PHYS_DES_PREFIX='U';
      CLASS='IC';
      STANDARD='';
      LIFECYCLE='';
      JEDEC_TYPE='MSOP8_0-65_3X3XE';
      DESCRIPTION='IC OTHER(8P) NCT7718W(MSOP)';
      MANUFTR='NVT';
      MANUF_PN='NCT7718W';
      RD_CMPLS_LVL='EP(V1)';
      CMPLS_LVL='EP(V1)';
      FROM_PJ='F0EG-RAY';
      DIP_SMD='';
      DATA='NVT_NCT7718W.pdf';
      EE_CHECK_LIST='';
      FP_ECN='NCT7718W.msg';
      PSL='';
      CREATOR='';
      STATUS='';
      MSD='';
      ESD_CDM='';
      ESD_HBM='';
      ESD_MM='';
      PIN_LENGTH_SHORT_PIN='0 MILS';
      PIN_LENGTH_LONG_PIN='0 MILS';
      CREATEDAY='20220317';
      PARENT_PART_TYPE='NCT7718W';
      PARENT_PPT='NCT7718W';
      PARENT_PPT_PART='NCT7718W-NCT7718W,SMLF,EMPTY,AL007718001';
  end_body;
end_primitive;
primitive 'NX3L2267GM-NX3L2267GM,SMLF,IC,A';
  pin
    'VCC':
      PIN_NUMBER='(10)';
      PINUSE='POWER';
      NO_LOAD_CHECK='Both';
      NO_IO_CHECK='Both';
      NO_ASSERT_CHECK='TRUE';
      NO_DIR_CHECK='TRUE';
      ALLOW_CONNECT='TRUE';
    '2Z':
      PIN_NUMBER='(6)';
      BIDIRECTIONAL='TRUE';
      INPUT_LOAD='(-0.01,0.01)';
      OUTPUT_LOAD='(1.0,-1.0)';
      PINUSE='BI';
    '1Y0':
      PIN_NUMBER='(1)';
      BIDIRECTIONAL='TRUE';
      INPUT_LOAD='(-0.01,0.01)';
      OUTPUT_LOAD='(1.0,-1.0)';
      PINUSE='BI';
    'GND':
      PIN_NUMBER='(5)';
      PINUSE='POWER';
      NO_LOAD_CHECK='Both';
      NO_IO_CHECK='Both';
      NO_ASSERT_CHECK='TRUE';
      NO_DIR_CHECK='TRUE';
      ALLOW_CONNECT='TRUE';
    '1Y1':
      PIN_NUMBER='(2)';
      BIDIRECTIONAL='TRUE';
      INPUT_LOAD='(-0.01,0.01)';
      OUTPUT_LOAD='(1.0,-1.0)';
      PINUSE='BI';
    '2S':
      PIN_NUMBER='(7)';
      INPUT_LOAD='(-0.01,0.01)';
      PINUSE='IN';
    '2Y1':
      PIN_NUMBER='(4)';
      BIDIRECTIONAL='TRUE';
      INPUT_LOAD='(-0.01,0.01)';
      OUTPUT_LOAD='(1.0,-1.0)';
      PINUSE='BI';
    '1Z':
      PIN_NUMBER='(9)';
      BIDIRECTIONAL='TRUE';
      INPUT_LOAD='(-0.01,0.01)';
      OUTPUT_LOAD='(1.0,-1.0)';
      PINUSE='BI';
    '1S':
      PIN_NUMBER='(8)';
      INPUT_LOAD='(-0.01,0.01)';
      PINUSE='IN';
    '2Y0':
      PIN_NUMBER='(3)';
      BIDIRECTIONAL='TRUE';
      INPUT_LOAD='(-0.01,0.01)';
      OUTPUT_LOAD='(1.0,-1.0)';
      PINUSE='BI';
  end_pin;
  body
      PART_NAME='NX3L2267GM';
      BODY_NAME='NX3L2267GM';
      PHYS_DES_PREFIX='U';
      CLASS='IC';
      STANDARD='';
      LIFECYCLE='';
      JEDEC_TYPE='XQFN10';
      DESCRIPTION='IC(10P)NX3L2267GM(XQFN)';
      MANUFTR='NXP';
      MANUF_PN='NX3L2267GM';
      RD_CMPLS_LVL='EP(V1)';
      CMPLS_LVL='';
      FROM_PJ='F0C-IVES';
      DIP_SMD='';
      DATA='NXP_NX3L2267GM.pdf';
      EE_CHECK_LIST='';
      FP_ECN='';
      PSL='';
      CREATOR='';
      STATUS='';
      MSD='';
      ESD_CDM='';
      ESD_HBM='';
      ESD_MM='';
      PIN_LENGTH_SHORT_PIN='0 MILS';
      PIN_LENGTH_LONG_PIN='0 MILS';
      CREATEDAY='20210622';
      PARENT_PART_TYPE='NX3L2267GM';
      PARENT_PPT='NX3L2267GM';
      PARENT_PPT_PART='NX3L2267GM-NX3L2267GM,SMLF,IC,AL002267000';
  end_body;
end_primitive;
primitive 'PCA9306DP1-PCA9306DP1,SMLF,IC,A';
  pin
    'VREF1':
      PIN_NUMBER='(2)';
      PINUSE='POWER';
      NO_LOAD_CHECK='Both';
      NO_IO_CHECK='Both';
      NO_ASSERT_CHECK='TRUE';
      NO_DIR_CHECK='TRUE';
      ALLOW_CONNECT='TRUE';
    'SCL1':
      PIN_NUMBER='(3)';
      BIDIRECTIONAL='TRUE';
      INPUT_LOAD='(-0.01,0.01)';
      OUTPUT_LOAD='(1.0,-1.0)';
      PINUSE='BI';
    'SDA1':
      PIN_NUMBER='(4)';
      BIDIRECTIONAL='TRUE';
      INPUT_LOAD='(-0.01,0.01)';
      OUTPUT_LOAD='(1.0,-1.0)';
      PINUSE='BI';
    'SDA2':
      PIN_NUMBER='(5)';
      BIDIRECTIONAL='TRUE';
      INPUT_LOAD='(-0.01,0.01)';
      OUTPUT_LOAD='(1.0,-1.0)';
      PINUSE='BI';
    'SCL2':
      PIN_NUMBER='(6)';
      BIDIRECTIONAL='TRUE';
      INPUT_LOAD='(-0.01,0.01)';
      OUTPUT_LOAD='(1.0,-1.0)';
      PINUSE='BI';
    'VREF2':
      PIN_NUMBER='(7)';
      PINUSE='POWER';
      NO_LOAD_CHECK='Both';
      NO_IO_CHECK='Both';
      NO_ASSERT_CHECK='TRUE';
      NO_DIR_CHECK='TRUE';
      ALLOW_CONNECT='TRUE';
    'EN':
      PIN_NUMBER='(8)';
      INPUT_LOAD='(-0.01,0.01)';
      PINUSE='IN';
    'GND':
      PIN_NUMBER='(1)';
      PINUSE='POWER';
      NO_LOAD_CHECK='Both';
      NO_IO_CHECK='Both';
      NO_ASSERT_CHECK='TRUE';
      NO_DIR_CHECK='TRUE';
      ALLOW_CONNECT='TRUE';
  end_pin;
  body
      PART_NAME='PCA9306DP1';
      BODY_NAME='PCA9306DP1';
      PHYS_DES_PREFIX='U';
      CLASS='IC';
      JEDEC_TYPE='TSSOP8_3';
      DESCRIPTION='IC OTHER(8P)PCA9306DP1(TSSOP)';
      MANUFTR='NXP';
      MANUF_PN='PCA9306DP1';
      RD_CMPLS_LVL='EP(V1)';
      CMPLS_LVL='';
      FROM_PJ='T2L-MARK';
      DIP_SMD='';
      DATA='NXP_PCA9306.pdf';
      EE_CHECK_LIST='';
      FP_ECN='';
      PSL='';
      LIFECYCLE='';
      CREATOR='';
      STANDARD='';
      CREATEDAY='20120224';
      STATUS='';
      PARENT_PART_TYPE='PCA9306DP1';
      PARENT_PPT='PCA9306DP1';
      PARENT_PPT_PART='PCA9306DP1-PCA9306DP1,SMLF,IC,AL009306K04';
  end_body;
end_primitive;
primitive 'PCA9517AD-PCA9517AD,SMLF,IC,ALA';
  pin
    'ENABLE':
      PIN_NUMBER='(5)';
      BIDIRECTIONAL='TRUE';
      INPUT_LOAD='(-0.01,0.01)';
      OUTPUT_LOAD='(1.0,-1.0)';
      PINUSE='BI';
    'VCCA':
      PIN_NUMBER='(1)';
      PINUSE='POWER';
    'VCCB':
      PIN_NUMBER='(8)';
      BIDIRECTIONAL='TRUE';
      INPUT_LOAD='(-0.01,0.01)';
      OUTPUT_LOAD='(1.0,-1.0)';
      PINUSE='BI';
    'SCLA':
      PIN_NUMBER='(2)';
      BIDIRECTIONAL='TRUE';
      INPUT_LOAD='(-0.01,0.01)';
      OUTPUT_LOAD='(1.0,-1.0)';
      PINUSE='BI';
    'SDAA':
      PIN_NUMBER='(3)';
      BIDIRECTIONAL='TRUE';
      INPUT_LOAD='(-0.01,0.01)';
      OUTPUT_LOAD='(1.0,-1.0)';
      PINUSE='BI';
    'SDAB':
      PIN_NUMBER='(6)';
      BIDIRECTIONAL='TRUE';
      INPUT_LOAD='(-0.01,0.01)';
      OUTPUT_LOAD='(1.0,-1.0)';
      PINUSE='BI';
    'SCLB':
      PIN_NUMBER='(7)';
      BIDIRECTIONAL='TRUE';
      INPUT_LOAD='(-0.01,0.01)';
      OUTPUT_LOAD='(1.0,-1.0)';
      PINUSE='BI';
    'GND':
      PIN_NUMBER='(4)';
      PINUSE='POWER';
  end_pin;
  body
      PART_NAME='PCA9517AD';
      BODY_NAME='PCA9517AD';
      PHYS_DES_PREFIX='U';
      CLASS='IC';
      STANDARD='';
      LIFECYCLE='';
      JEDEC_TYPE='SOIC8';
      DESCRIPTION='IC OTHER (8P) I2C PCA9517AD (SO8)';
      MANUFTR='NXP';
      MANUF_PN='PCA9517AD';
      RD_CMPLS_LVL='EP(V1)';
      CMPLS_LVL='EP(V1)';
      FROM_PJ='JB5_CHINWEI';
      DIP_SMD='';
      DATA='PCA9517A.pdf';
      EE_CHECK_LIST='';
      FP_ECN='';
      PSL='';
      CREATOR='';
      STATUS='';
      MSD='';
      ESD_CDM='';
      ESD_HBM='';
      ESD_MM='';
      PIN_LENGTH_SHORT_PIN='0 MILS';
      PIN_LENGTH_LONG_PIN='0 MILS';
      CREATEDAY='20200116';
      PARENT_PART_TYPE='PCA9517AD';
      PARENT_PPT='PCA9517AD';
      PARENT_PPT_PART='PCA9517AD-PCA9517AD,SMLF,IC,AL009517000';
  end_body;
end_primitive;
primitive 'PCA9539RPW-PCA9539RPW,SMLF,IC,A';
  pin
    'INT':
      PIN_NUMBER='(1)';
      BIDIRECTIONAL='TRUE';
      INPUT_LOAD='(-0.01,0.01)';
      OUTPUT_LOAD='(1.0,-1.0)';
      PINUSE='BI';
    'A1':
      PIN_NUMBER='(2)';
      INPUT_LOAD='(-0.01,0.01)';
      PINUSE='IN';
    'RESET':
      PIN_NUMBER='(3)';
      BIDIRECTIONAL='TRUE';
      INPUT_LOAD='(-0.01,0.01)';
      OUTPUT_LOAD='(1.0,-1.0)';
      PINUSE='BI';
    'IO0_0':
      PIN_NUMBER='(4)';
      BIDIRECTIONAL='TRUE';
      INPUT_LOAD='(-0.01,0.01)';
      OUTPUT_LOAD='(1.0,-1.0)';
      PINUSE='BI';
    'IO0_1':
      PIN_NUMBER='(5)';
      BIDIRECTIONAL='TRUE';
      INPUT_LOAD='(-0.01,0.01)';
      OUTPUT_LOAD='(1.0,-1.0)';
      PINUSE='BI';
    'IO0_2':
      PIN_NUMBER='(6)';
      BIDIRECTIONAL='TRUE';
      INPUT_LOAD='(-0.01,0.01)';
      OUTPUT_LOAD='(1.0,-1.0)';
      PINUSE='BI';
    'IO0_3':
      PIN_NUMBER='(7)';
      BIDIRECTIONAL='TRUE';
      INPUT_LOAD='(-0.01,0.01)';
      OUTPUT_LOAD='(1.0,-1.0)';
      PINUSE='BI';
    'IO0_4':
      PIN_NUMBER='(8)';
      BIDIRECTIONAL='TRUE';
      INPUT_LOAD='(-0.01,0.01)';
      OUTPUT_LOAD='(1.0,-1.0)';
      PINUSE='BI';
    'IO0_5':
      PIN_NUMBER='(9)';
      BIDIRECTIONAL='TRUE';
      INPUT_LOAD='(-0.01,0.01)';
      OUTPUT_LOAD='(1.0,-1.0)';
      PINUSE='BI';
    'IO0_6':
      PIN_NUMBER='(10)';
      BIDIRECTIONAL='TRUE';
      INPUT_LOAD='(-0.01,0.01)';
      OUTPUT_LOAD='(1.0,-1.0)';
      PINUSE='BI';
    'IO0_7':
      PIN_NUMBER='(11)';
      BIDIRECTIONAL='TRUE';
      INPUT_LOAD='(-0.01,0.01)';
      OUTPUT_LOAD='(1.0,-1.0)';
      PINUSE='BI';
    'VSS':
      PIN_NUMBER='(12)';
      PINUSE='POWER';
      NO_LOAD_CHECK='Both';
      NO_IO_CHECK='Both';
      NO_ASSERT_CHECK='TRUE';
      NO_DIR_CHECK='TRUE';
      ALLOW_CONNECT='TRUE';
    'IO1_0':
      PIN_NUMBER='(13)';
      BIDIRECTIONAL='TRUE';
      INPUT_LOAD='(-0.01,0.01)';
      OUTPUT_LOAD='(1.0,-1.0)';
      PINUSE='BI';
    'IO1_1':
      PIN_NUMBER='(14)';
      BIDIRECTIONAL='TRUE';
      INPUT_LOAD='(-0.01,0.01)';
      OUTPUT_LOAD='(1.0,-1.0)';
      PINUSE='BI';
    'IO1_2':
      PIN_NUMBER='(15)';
      BIDIRECTIONAL='TRUE';
      INPUT_LOAD='(-0.01,0.01)';
      OUTPUT_LOAD='(1.0,-1.0)';
      PINUSE='BI';
    'IO1_3':
      PIN_NUMBER='(16)';
      BIDIRECTIONAL='TRUE';
      INPUT_LOAD='(-0.01,0.01)';
      OUTPUT_LOAD='(1.0,-1.0)';
      PINUSE='BI';
    'IO1_4':
      PIN_NUMBER='(17)';
      BIDIRECTIONAL='TRUE';
      INPUT_LOAD='(-0.01,0.01)';
      OUTPUT_LOAD='(1.0,-1.0)';
      PINUSE='BI';
    'IO1_5':
      PIN_NUMBER='(18)';
      BIDIRECTIONAL='TRUE';
      INPUT_LOAD='(-0.01,0.01)';
      OUTPUT_LOAD='(1.0,-1.0)';
      PINUSE='BI';
    'IO1_6':
      PIN_NUMBER='(19)';
      BIDIRECTIONAL='TRUE';
      INPUT_LOAD='(-0.01,0.01)';
      OUTPUT_LOAD='(1.0,-1.0)';
      PINUSE='BI';
    'IO1_7':
      PIN_NUMBER='(20)';
      BIDIRECTIONAL='TRUE';
      INPUT_LOAD='(-0.01,0.01)';
      OUTPUT_LOAD='(1.0,-1.0)';
      PINUSE='BI';
    'A0':
      PIN_NUMBER='(21)';
      INPUT_LOAD='(-0.01,0.01)';
      PINUSE='IN';
    'SCL':
      PIN_NUMBER='(22)';
      BIDIRECTIONAL='TRUE';
      INPUT_LOAD='(-0.01,0.01)';
      OUTPUT_LOAD='(1.0,-1.0)';
      PINUSE='BI';
    'SDA':
      PIN_NUMBER='(23)';
      BIDIRECTIONAL='TRUE';
      INPUT_LOAD='(-0.01,0.01)';
      OUTPUT_LOAD='(1.0,-1.0)';
      PINUSE='BI';
    'VDD':
      PIN_NUMBER='(24)';
      PINUSE='POWER';
      NO_LOAD_CHECK='Both';
      NO_IO_CHECK='Both';
      NO_ASSERT_CHECK='TRUE';
      NO_DIR_CHECK='TRUE';
      ALLOW_CONNECT='TRUE';
  end_pin;
  body
      PART_NAME='PCA9539RPW';
      BODY_NAME='PCA9539RPW';
      PHYS_DES_PREFIX='U';
      CLASS='IC';
      STANDARD='';
      LIFECYCLE='';
      JEDEC_TYPE='TSSOP24XB';
      DESCRIPTION='IC OTHER(24P)PCA9539RPW(TSSOP)';
      MANUFTR='NXP';
      MANUF_PN='PCA9539RPW';
      RD_CMPLS_LVL='EP(V1)';
      CMPLS_LVL='EP(V1)';
      FROM_PJ='S5C-KEVIN';
      DIP_SMD='';
      DATA='NXP_PCA9539RPW.pdf';
      EE_CHECK_LIST='';
      FP_ECN='';
      PSL='';
      CREATOR='';
      STATUS='';
      MSD='NA';
      ESD_CDM='NA';
      ESD_HBM='NA';
      ESD_MM='NA';
      PIN_LENGTH_SHORT_PIN='0 MILS';
      PIN_LENGTH_LONG_PIN='0 MILS';
      CREATEDAY='20180717';
      PARENT_PART_TYPE='PCA9539RPW';
      PARENT_PPT='PCA9539RPW';
      PARENT_PPT_PART='PCA9539RPW-PCA9539RPW,SMLF,IC,AL009539K07';
  end_body;
end_primitive;
primitive 'PCA9545APW-PCA9545APW,SMLF,IC,A';
  pin
    'A0':
      PIN_NUMBER='(1)';
      INPUT_LOAD='(-0.01,0.01)';
      PINUSE='IN';
    'A1':
      PIN_NUMBER='(2)';
      INPUT_LOAD='(-0.01,0.01)';
      PINUSE='IN';
    'RESET#':
      PIN_NUMBER='(3)';
      INPUT_LOAD='(-0.01,0.01)';
      PINUSE='IN';
    'INT#':
      PIN_NUMBER='(17)';
      OUTPUT_LOAD='(1.0,-1.0)';
      PINUSE='OUT';
    'SCL':
      PIN_NUMBER='(18)';
      INPUT_LOAD='(-0.01,0.01)';
      PINUSE='IN';
    'SDA':
      PIN_NUMBER='(19)';
      BIDIRECTIONAL='TRUE';
      INPUT_LOAD='(-0.01,0.01)';
      OUTPUT_LOAD='(1.0,-1.0)';
      PINUSE='BI';
    'VSS':
      PIN_NUMBER='(10)';
      PINUSE='POWER';
      NO_LOAD_CHECK='Both';
      NO_IO_CHECK='Both';
      NO_ASSERT_CHECK='TRUE';
      NO_DIR_CHECK='TRUE';
      ALLOW_CONNECT='TRUE';
    'VDD':
      PIN_NUMBER='(20)';
      PINUSE='POWER';
      NO_LOAD_CHECK='Both';
      NO_IO_CHECK='Both';
      NO_ASSERT_CHECK='TRUE';
      NO_DIR_CHECK='TRUE';
      ALLOW_CONNECT='TRUE';
    'SD0':
      PIN_NUMBER='(5)';
      BIDIRECTIONAL='TRUE';
      INPUT_LOAD='(-0.01,0.01)';
      OUTPUT_LOAD='(1.0,-1.0)';
      PINUSE='BI';
    'SC0':
      PIN_NUMBER='(6)';
      INPUT_LOAD='(-0.01,0.01)';
      PINUSE='IN';
    'INT0#':
      PIN_NUMBER='(4)';
      INPUT_LOAD='(-0.01,0.01)';
      PINUSE='IN';
    'SD1':
      PIN_NUMBER='(8)';
      BIDIRECTIONAL='TRUE';
      INPUT_LOAD='(-0.01,0.01)';
      OUTPUT_LOAD='(1.0,-1.0)';
      PINUSE='BI';
    'SC1':
      PIN_NUMBER='(9)';
      INPUT_LOAD='(-0.01,0.01)';
      PINUSE='IN';
    'INT1#':
      PIN_NUMBER='(7)';
      INPUT_LOAD='(-0.01,0.01)';
      PINUSE='IN';
    'SD2':
      PIN_NUMBER='(12)';
      BIDIRECTIONAL='TRUE';
      INPUT_LOAD='(-0.01,0.01)';
      OUTPUT_LOAD='(1.0,-1.0)';
      PINUSE='BI';
    'SC2':
      PIN_NUMBER='(13)';
      INPUT_LOAD='(-0.01,0.01)';
      PINUSE='IN';
    'INT2#':
      PIN_NUMBER='(11)';
      INPUT_LOAD='(-0.01,0.01)';
      PINUSE='IN';
    'SD3':
      PIN_NUMBER='(15)';
      BIDIRECTIONAL='TRUE';
      INPUT_LOAD='(-0.01,0.01)';
      OUTPUT_LOAD='(1.0,-1.0)';
      PINUSE='BI';
    'SC3':
      PIN_NUMBER='(16)';
      INPUT_LOAD='(-0.01,0.01)';
      PINUSE='IN';
    'INT3#':
      PIN_NUMBER='(14)';
      INPUT_LOAD='(-0.01,0.01)';
      PINUSE='IN';
  end_pin;
  body
      PART_NAME='PCA9545APW';
      BODY_NAME='PCA9545APW';
      PHYS_DES_PREFIX='U';
      CLASS='IC';
      STANDARD='';
      LIFECYCLE='';
      JEDEC_TYPE='TSSOP20_0-65_6-5X4-4';
      DESCRIPTION='IC (20P) PCA9545APW (TSSOP)';
      MANUFTR='PHI';
      MANUF_PN='PCA9545APW';
      RD_CMPLS_LVL='EP';
      CMPLS_LVL='EP(V1)';
      FROM_PJ='S8A-LUKE';
      DIP_SMD='';
      DATA='PHI_ PCA9545APW.pdf';
      EE_CHECK_LIST='';
      FP_ECN='';
      PSL='';
      CREATOR='';
      STATUS='';
      MSD='';
      ESD_CDM='';
      ESD_HBM='';
      ESD_MM='';
      PIN_LENGTH_SHORT_PIN='0 MILS';
      PIN_LENGTH_LONG_PIN='0 MILS';
      CREATEDAY='20210723';
      PARENT_PART_TYPE='PCA9545APW';
      PARENT_PPT='PCA9545APW';
      PARENT_PPT_PART='PCA9545APW-PCA9545APW,SMLF,IC,AL009545K17';
  end_body;
end_primitive;
primitive 'PCA9555APW-PCA9555APW,SMLF,IC,A';
  pin
    'VDD':
      PIN_NUMBER='(24)';
      PINUSE='POWER';
      NO_LOAD_CHECK='Both';
      NO_IO_CHECK='Both';
      NO_ASSERT_CHECK='TRUE';
      NO_DIR_CHECK='TRUE';
      ALLOW_CONNECT='TRUE';
    'VSS':
      PIN_NUMBER='(12)';
      PINUSE='POWER';
      NO_LOAD_CHECK='Both';
      NO_IO_CHECK='Both';
      NO_ASSERT_CHECK='TRUE';
      NO_DIR_CHECK='TRUE';
      ALLOW_CONNECT='TRUE';
    'INT#':
      PIN_NUMBER='(1)';
      OUTPUT_LOAD='(1.0,-1.0)';
      PINUSE='OUT';
    'SDA':
      PIN_NUMBER='(23)';
      BIDIRECTIONAL='TRUE';
      INPUT_LOAD='(-0.01,0.01)';
      OUTPUT_LOAD='(1.0,-1.0)';
      PINUSE='BI';
    'SCL':
      PIN_NUMBER='(22)';
      INPUT_LOAD='(-0.01,0.01)';
      PINUSE='IN';
    'P0_0':
      PIN_NUMBER='(4)';
      BIDIRECTIONAL='TRUE';
      INPUT_LOAD='(-0.01,0.01)';
      OUTPUT_LOAD='(1.0,-1.0)';
      PINUSE='BI';
    'P0_1':
      PIN_NUMBER='(5)';
      BIDIRECTIONAL='TRUE';
      INPUT_LOAD='(-0.01,0.01)';
      OUTPUT_LOAD='(1.0,-1.0)';
      PINUSE='BI';
    'P0_2':
      PIN_NUMBER='(6)';
      BIDIRECTIONAL='TRUE';
      INPUT_LOAD='(-0.01,0.01)';
      OUTPUT_LOAD='(1.0,-1.0)';
      PINUSE='BI';
    'P0_3':
      PIN_NUMBER='(7)';
      BIDIRECTIONAL='TRUE';
      INPUT_LOAD='(-0.01,0.01)';
      OUTPUT_LOAD='(1.0,-1.0)';
      PINUSE='BI';
    'P0_4':
      PIN_NUMBER='(8)';
      BIDIRECTIONAL='TRUE';
      INPUT_LOAD='(-0.01,0.01)';
      OUTPUT_LOAD='(1.0,-1.0)';
      PINUSE='BI';
    'P0_5':
      PIN_NUMBER='(9)';
      BIDIRECTIONAL='TRUE';
      INPUT_LOAD='(-0.01,0.01)';
      OUTPUT_LOAD='(1.0,-1.0)';
      PINUSE='BI';
    'P0_6':
      PIN_NUMBER='(10)';
      BIDIRECTIONAL='TRUE';
      INPUT_LOAD='(-0.01,0.01)';
      OUTPUT_LOAD='(1.0,-1.0)';
      PINUSE='BI';
    'P0_7':
      PIN_NUMBER='(11)';
      BIDIRECTIONAL='TRUE';
      INPUT_LOAD='(-0.01,0.01)';
      OUTPUT_LOAD='(1.0,-1.0)';
      PINUSE='BI';
    'P1_0':
      PIN_NUMBER='(13)';
      BIDIRECTIONAL='TRUE';
      INPUT_LOAD='(-0.01,0.01)';
      OUTPUT_LOAD='(1.0,-1.0)';
      PINUSE='BI';
    'P1_1':
      PIN_NUMBER='(14)';
      BIDIRECTIONAL='TRUE';
      INPUT_LOAD='(-0.01,0.01)';
      OUTPUT_LOAD='(1.0,-1.0)';
      PINUSE='BI';
    'P1_2':
      PIN_NUMBER='(15)';
      BIDIRECTIONAL='TRUE';
      INPUT_LOAD='(-0.01,0.01)';
      OUTPUT_LOAD='(1.0,-1.0)';
      PINUSE='BI';
    'P1_3':
      PIN_NUMBER='(16)';
      BIDIRECTIONAL='TRUE';
      INPUT_LOAD='(-0.01,0.01)';
      OUTPUT_LOAD='(1.0,-1.0)';
      PINUSE='BI';
    'P1_4':
      PIN_NUMBER='(17)';
      BIDIRECTIONAL='TRUE';
      INPUT_LOAD='(-0.01,0.01)';
      OUTPUT_LOAD='(1.0,-1.0)';
      PINUSE='BI';
    'P1_5':
      PIN_NUMBER='(18)';
      BIDIRECTIONAL='TRUE';
      INPUT_LOAD='(-0.01,0.01)';
      OUTPUT_LOAD='(1.0,-1.0)';
      PINUSE='BI';
    'P1_6':
      PIN_NUMBER='(19)';
      BIDIRECTIONAL='TRUE';
      INPUT_LOAD='(-0.01,0.01)';
      OUTPUT_LOAD='(1.0,-1.0)';
      PINUSE='BI';
    'P1_7':
      PIN_NUMBER='(20)';
      BIDIRECTIONAL='TRUE';
      INPUT_LOAD='(-0.01,0.01)';
      OUTPUT_LOAD='(1.0,-1.0)';
      PINUSE='BI';
    'A0':
      PIN_NUMBER='(21)';
      INPUT_LOAD='(-0.01,0.01)';
      PINUSE='IN';
    'A1':
      PIN_NUMBER='(2)';
      INPUT_LOAD='(-0.01,0.01)';
      PINUSE='IN';
    'A2':
      PIN_NUMBER='(3)';
      INPUT_LOAD='(-0.01,0.01)';
      PINUSE='IN';
  end_pin;
  body
      PART_NAME='PCA9555APW';
      BODY_NAME='PCA9555APW';
      PHYS_DES_PREFIX='U';
      CLASS='IC';
      STANDARD='';
      LIFECYCLE='';
      JEDEC_TYPE='TSSOP24XB';
      DESCRIPTION='IC OTHER(24P)PCA9555APW(TSSOP)';
      MANUFTR='NXP';
      MANUF_PN='PCA9555APW';
      RD_CMPLS_LVL='EP(V1)';
      CMPLS_LVL='EP(V1)';
      FROM_PJ='IX5-BRYANT';
      DIP_SMD='';
      DATA='NXP_PCA9555APW.pdf';
      EE_CHECK_LIST='';
      FP_ECN='';
      PSL='';
      CREATOR='';
      STATUS='';
      MSD='';
      ESD_CDM='';
      ESD_HBM='';
      ESD_MM='';
      PIN_LENGTH_SHORT_PIN='0 MILS';
      PIN_LENGTH_LONG_PIN='0 MILS';
      CREATEDAY='20210721';
      PARENT_PART_TYPE='PCA9555APW';
      PARENT_PPT='PCA9555APW';
      PARENT_PPT_PART='PCA9555APW-PCA9555APW,SMLF,IC,AL009555K07';
  end_body;
end_primitive;
primitive 'PCA9617ADP-PCA9617ADP,SMLF,IC,A';
  pin
    'EN':
      PIN_NUMBER='(5)';
      INPUT_LOAD='(-0.01,0.01)';
      PINUSE='IN';
    'VCCA':
      PIN_NUMBER='(1)';
      PINUSE='POWER';
      NO_LOAD_CHECK='Both';
      NO_IO_CHECK='Both';
      NO_ASSERT_CHECK='TRUE';
      NO_DIR_CHECK='TRUE';
      ALLOW_CONNECT='TRUE';
    'VCCB':
      PIN_NUMBER='(8)';
      PINUSE='POWER';
      NO_LOAD_CHECK='Both';
      NO_IO_CHECK='Both';
      NO_ASSERT_CHECK='TRUE';
      NO_DIR_CHECK='TRUE';
      ALLOW_CONNECT='TRUE';
    'SCLA':
      PIN_NUMBER='(2)';
      BIDIRECTIONAL='TRUE';
      INPUT_LOAD='(-0.01,0.01)';
      OUTPUT_LOAD='(1.0,-1.0)';
      PINUSE='BI';
    'SDAA':
      PIN_NUMBER='(3)';
      BIDIRECTIONAL='TRUE';
      INPUT_LOAD='(-0.01,0.01)';
      OUTPUT_LOAD='(1.0,-1.0)';
      PINUSE='BI';
    'SDAB':
      PIN_NUMBER='(6)';
      BIDIRECTIONAL='TRUE';
      INPUT_LOAD='(-0.01,0.01)';
      OUTPUT_LOAD='(1.0,-1.0)';
      PINUSE='BI';
    'SCLB':
      PIN_NUMBER='(7)';
      BIDIRECTIONAL='TRUE';
      INPUT_LOAD='(-0.01,0.01)';
      OUTPUT_LOAD='(1.0,-1.0)';
      PINUSE='BI';
    'GND':
      PIN_NUMBER='(4)';
      PINUSE='POWER';
      NO_LOAD_CHECK='Both';
      NO_IO_CHECK='Both';
      NO_ASSERT_CHECK='TRUE';
      NO_DIR_CHECK='TRUE';
      ALLOW_CONNECT='TRUE';
  end_pin;
  body
      PART_NAME='PCA9617ADP';
      BODY_NAME='PCA9617ADP';
      PHYS_DES_PREFIX='U';
      CLASS='IC';
      STANDARD='';
      LIFECYCLE='';
      JEDEC_TYPE='TSSOP8_3XB';
      DESCRIPTION='IC OTHER(8P) PCA9617ADP(TSSOP)';
      MANUFTR='NXP';
      MANUF_PN='PCA9617ADP';
      RD_CMPLS_LVL='EP(V1)';
      CMPLS_LVL='';
      FROM_PJ='S1U-OWEN';
      DIP_SMD='';
      DATA='NXP_PCA9617A.pdf';
      EE_CHECK_LIST='';
      FP_ECN='';
      PSL='';
      CREATOR='';
      STATUS='';
      CREATEDAY='20140410';
      PARENT_PART_TYPE='PCA9617ADP';
      PARENT_PPT='PCA9617ADP';
      PARENT_PPT_PART='PCA9617ADP-PCA9617ADP,SMLF,IC,AL009617K02';
  end_body;
end_primitive;
primitive 'PI3EQX1002EZREX-PI3EQX1002EZREA';
  pin
    'GND_2':
      PIN_NUMBER='(9)';
      PINUSE='POWER';
      NO_LOAD_CHECK='Both';
      NO_IO_CHECK='Both';
      NO_ASSERT_CHECK='TRUE';
      NO_DIR_CHECK='TRUE';
      ALLOW_CONNECT='TRUE';
    'VDD_2':
      PIN_NUMBER='(17)';
      PINUSE='POWER';
      NO_LOAD_CHECK='Both';
      NO_IO_CHECK='Both';
      NO_ASSERT_CHECK='TRUE';
      NO_DIR_CHECK='TRUE';
      ALLOW_CONNECT='TRUE';
    'EN':
      PIN_NUMBER='(4)';
      INPUT_LOAD='(-0.01,0.01)';
      PINUSE='IN';
    'VDD_1':
      PIN_NUMBER='(5)';
      PINUSE='POWER';
      NO_LOAD_CHECK='Both';
      NO_IO_CHECK='Both';
      NO_ASSERT_CHECK='TRUE';
      NO_DIR_CHECK='TRUE';
      ALLOW_CONNECT='TRUE';
    'AON':
      PIN_NUMBER='(23)';
      OUTPUT_LOAD='(1.0,-1.0)';
      PINUSE='OUT';
    'AOP':
      PIN_NUMBER='(24)';
      OUTPUT_LOAD='(1.0,-1.0)';
      PINUSE='OUT';
    'GND_6':
      PIN_NUMBER='(22)';
      PINUSE='POWER';
      NO_LOAD_CHECK='Both';
      NO_IO_CHECK='Both';
      NO_ASSERT_CHECK='TRUE';
      NO_DIR_CHECK='TRUE';
      ALLOW_CONNECT='TRUE';
    'AIN':
      PIN_NUMBER='(7)';
      INPUT_LOAD='(-0.01,0.01)';
      PINUSE='IN';
    'EQA':
      PIN_NUMBER='(1)';
      INPUT_LOAD='(-0.01,0.01)';
      PINUSE='IN';
    'FGA':
      PIN_NUMBER='(2)';
      INPUT_LOAD='(-0.01,0.01)';
      PINUSE='IN';
    'RXDET_EN':
      PIN_NUMBER='(13)';
      INPUT_LOAD='(-0.01,0.01)';
      PINUSE='IN';
    'AIP':
      PIN_NUMBER='(6)';
      INPUT_LOAD='(-0.01,0.01)';
      PINUSE='IN';
    'TH_GND':
      PIN_NUMBER='(TH)';
      PINUSE='POWER';
      NO_LOAD_CHECK='Both';
      NO_IO_CHECK='Both';
      NO_ASSERT_CHECK='TRUE';
      NO_DIR_CHECK='TRUE';
      ALLOW_CONNECT='TRUE';
    'FGB':
      PIN_NUMBER='(15)';
      INPUT_LOAD='(-0.01,0.01)';
      PINUSE='IN';
    'BIN':
      PIN_NUMBER='(19)';
      INPUT_LOAD='(-0.01,0.01)';
      PINUSE='IN';
    'SWB':
      PIN_NUMBER='(14)';
      INPUT_LOAD='(-0.01,0.01)';
      PINUSE='IN';
    'BIP':
      PIN_NUMBER='(18)';
      INPUT_LOAD='(-0.01,0.01)';
      PINUSE='IN';
    'SWA':
      PIN_NUMBER='(3)';
      INPUT_LOAD='(-0.01,0.01)';
      PINUSE='IN';
    'GND_1':
      PIN_NUMBER='(8)';
      PINUSE='POWER';
      NO_LOAD_CHECK='Both';
      NO_IO_CHECK='Both';
      NO_ASSERT_CHECK='TRUE';
      NO_DIR_CHECK='TRUE';
      ALLOW_CONNECT='TRUE';
    'EQB':
      PIN_NUMBER='(16)';
      INPUT_LOAD='(-0.01,0.01)';
      PINUSE='IN';
    'GND_3':
      PIN_NUMBER='(10)';
      PINUSE='POWER';
      NO_LOAD_CHECK='Both';
      NO_IO_CHECK='Both';
      NO_ASSERT_CHECK='TRUE';
      NO_DIR_CHECK='TRUE';
      ALLOW_CONNECT='TRUE';
    'GND_5':
      PIN_NUMBER='(21)';
      PINUSE='POWER';
      NO_LOAD_CHECK='Both';
      NO_IO_CHECK='Both';
      NO_ASSERT_CHECK='TRUE';
      NO_DIR_CHECK='TRUE';
      ALLOW_CONNECT='TRUE';
    'BON':
      PIN_NUMBER='(11)';
      OUTPUT_LOAD='(1.0,-1.0)';
      PINUSE='OUT';
    'BOP':
      PIN_NUMBER='(12)';
      OUTPUT_LOAD='(1.0,-1.0)';
      PINUSE='OUT';
    'GND_4':
      PIN_NUMBER='(20)';
      PINUSE='POWER';
      NO_LOAD_CHECK='Both';
      NO_IO_CHECK='Both';
      NO_ASSERT_CHECK='TRUE';
      NO_DIR_CHECK='TRUE';
      ALLOW_CONNECT='TRUE';
  end_pin;
  body
      PART_NAME='PI3EQX1002EZREX';
      BODY_NAME='PI3EQX1002EZREX';
      PHYS_DES_PREFIX='U';
      CLASS='IC';
      STANDARD='';
      LIFECYCLE='';
      JEDEC_TYPE='TQFN24_TH_0-35_2-5X2-5';
      DESCRIPTION='IC OTHERS(24P) PI3EQX1002EZREX(TQFN)';
      MANUFTR='DDS';
      MANUF_PN='PI3EQX1002EZREX';
      RD_CMPLS_LVL='EP(V1)';
      CMPLS_LVL='EP(V1)';
      FROM_PJ='F0T-KEN';
      DIP_SMD='';
      DATA='DDS_PI3EQX1002EZREX.pdf';
      EE_CHECK_LIST='';
      FP_ECN='PI3EQX1002EZREX.msg';
      PSL='';
      CREATOR='';
      STATUS='';
      MSD='';
      ESD_CDM='';
      ESD_HBM='';
      ESD_MM='';
      PIN_LENGTH_SHORT_PIN='0 MILS';
      PIN_LENGTH_LONG_PIN='0 MILS';
      CREATEDAY='20211208';
      PARENT_PART_TYPE='PI3EQX1002EZREX';
      PARENT_PPT='PI3EQX1002EZREX';
      PARENT_PPT_PART='PI3EQX1002EZREX-PI3EQX1002EZREX,SMLF,IC,AL001002007';
  end_body;
end_primitive;
primitive 'PI3EQX12902AZLEX-PI3EQX12902AZA';
  pin
    'VDD1':
      PIN_NUMBER='(1)';
      PINUSE='POWER';
      NO_LOAD_CHECK='Both';
      NO_IO_CHECK='Both';
      NO_ASSERT_CHECK='TRUE';
      NO_DIR_CHECK='TRUE';
      ALLOW_CONNECT='TRUE';
    'AIP':
      PIN_NUMBER='(2)';
      INPUT_LOAD='(-0.01,0.01)';
      PINUSE='IN';
    'AIN':
      PIN_NUMBER='(3)';
      INPUT_LOAD='(-0.01,0.01)';
      PINUSE='IN';
    'GND1':
      PIN_NUMBER='(4)';
      PINUSE='POWER';
      NO_LOAD_CHECK='Both';
      NO_IO_CHECK='Both';
      NO_ASSERT_CHECK='TRUE';
      NO_DIR_CHECK='TRUE';
      ALLOW_CONNECT='TRUE';
    'TEST#':
      PIN_NUMBER='(5)';
      INPUT_LOAD='(-0.01,0.01)';
      PINUSE='IN';
    'GND2':
      PIN_NUMBER='(6)';
      PINUSE='POWER';
      NO_LOAD_CHECK='Both';
      NO_IO_CHECK='Both';
      NO_ASSERT_CHECK='TRUE';
      NO_DIR_CHECK='TRUE';
      ALLOW_CONNECT='TRUE';
    'GND3':
      PIN_NUMBER='(7)';
      PINUSE='POWER';
      NO_LOAD_CHECK='Both';
      NO_IO_CHECK='Both';
      NO_ASSERT_CHECK='TRUE';
      NO_DIR_CHECK='TRUE';
      ALLOW_CONNECT='TRUE';
    'BON':
      PIN_NUMBER='(8)';
      OUTPUT_LOAD='(1.0,-1.0)';
      PINUSE='OUT';
    'BOP':
      PIN_NUMBER='(9)';
      OUTPUT_LOAD='(1.0,-1.0)';
      PINUSE='OUT';
    'VDD2':
      PIN_NUMBER='(10)';
      PINUSE='POWER';
      NO_LOAD_CHECK='Both';
      NO_IO_CHECK='Both';
      NO_ASSERT_CHECK='TRUE';
      NO_DIR_CHECK='TRUE';
      ALLOW_CONNECT='TRUE';
    'EN#':
      PIN_NUMBER='(11)';
      INPUT_LOAD='(-0.01,0.01)';
      PINUSE='IN';
    'SWB':
      PIN_NUMBER='(12)';
      INPUT_LOAD='(-0.01,0.01)';
      PINUSE='IN';
    'GND4':
      PIN_NUMBER='(13)';
      PINUSE='POWER';
      NO_LOAD_CHECK='Both';
      NO_IO_CHECK='Both';
      NO_ASSERT_CHECK='TRUE';
      NO_DIR_CHECK='TRUE';
      ALLOW_CONNECT='TRUE';
    'FGB':
      PIN_NUMBER='(14)';
      INPUT_LOAD='(-0.01,0.01)';
      PINUSE='IN';
    'EQB1':
      PIN_NUMBER='(15)';
      INPUT_LOAD='(-0.01,0.01)';
      PINUSE='IN';
    'VDD3':
      PIN_NUMBER='(16)';
      PINUSE='POWER';
      NO_LOAD_CHECK='Both';
      NO_IO_CHECK='Both';
      NO_ASSERT_CHECK='TRUE';
      NO_DIR_CHECK='TRUE';
      ALLOW_CONNECT='TRUE';
    'BIP':
      PIN_NUMBER='(17)';
      INPUT_LOAD='(-0.01,0.01)';
      PINUSE='IN';
    'BIN':
      PIN_NUMBER='(18)';
      INPUT_LOAD='(-0.01,0.01)';
      PINUSE='IN';
    'GND5':
      PIN_NUMBER='(19)';
      PINUSE='POWER';
      NO_LOAD_CHECK='Both';
      NO_IO_CHECK='Both';
      NO_ASSERT_CHECK='TRUE';
      NO_DIR_CHECK='TRUE';
      ALLOW_CONNECT='TRUE';
    'EQB0':
      PIN_NUMBER='(20)';
      INPUT_LOAD='(-0.01,0.01)';
      PINUSE='IN';
    'EQA0':
      PIN_NUMBER='(21)';
      INPUT_LOAD='(-0.01,0.01)';
      PINUSE='IN';
    'GND6':
      PIN_NUMBER='(22)';
      PINUSE='POWER';
      NO_LOAD_CHECK='Both';
      NO_IO_CHECK='Both';
      NO_ASSERT_CHECK='TRUE';
      NO_DIR_CHECK='TRUE';
      ALLOW_CONNECT='TRUE';
    'AON':
      PIN_NUMBER='(23)';
      OUTPUT_LOAD='(1.0,-1.0)';
      PINUSE='OUT';
    'AOP':
      PIN_NUMBER='(24)';
      OUTPUT_LOAD='(1.0,-1.0)';
      PINUSE='OUT';
    'VDD4':
      PIN_NUMBER='(25)';
      PINUSE='POWER';
      NO_LOAD_CHECK='Both';
      NO_IO_CHECK='Both';
      NO_ASSERT_CHECK='TRUE';
      NO_DIR_CHECK='TRUE';
      ALLOW_CONNECT='TRUE';
    'EQA1':
      PIN_NUMBER='(26)';
      INPUT_LOAD='(-0.01,0.01)';
      PINUSE='IN';
    'FGA':
      PIN_NUMBER='(27)';
      INPUT_LOAD='(-0.01,0.01)';
      PINUSE='IN';
    'GND7':
      PIN_NUMBER='(28)';
      PINUSE='POWER';
      NO_LOAD_CHECK='Both';
      NO_IO_CHECK='Both';
      NO_ASSERT_CHECK='TRUE';
      NO_DIR_CHECK='TRUE';
      ALLOW_CONNECT='TRUE';
    'SWA':
      PIN_NUMBER='(29)';
      INPUT_LOAD='(-0.01,0.01)';
      PINUSE='IN';
    'MODE':
      PIN_NUMBER='(30)';
      INPUT_LOAD='(-0.01,0.01)';
      PINUSE='IN';
    'GND_TH':
      PIN_NUMBER='(TH)';
      PINUSE='POWER';
      NO_LOAD_CHECK='Both';
      NO_IO_CHECK='Both';
      NO_ASSERT_CHECK='TRUE';
      NO_DIR_CHECK='TRUE';
      ALLOW_CONNECT='TRUE';
  end_pin;
  body
      PART_NAME='PI3EQX12902AZLEX';
      BODY_NAME='PI3EQX12902AZLEX';
      PHYS_DES_PREFIX='U';
      CLASS='IC';
      STANDARD='';
      LIFECYCLE='';
      JEDEC_TYPE='TQFN30_TH_0-4_4-5X2-5';
      DESCRIPTION='IC OTHER(30P)PI3EQX12902AZLEX(TQFN)';
      MANUFTR='PIM';
      MANUF_PN='PI3EQX12902AZLEX';
      RD_CMPLS_LVL='EP(V1)';
      CMPLS_LVL='';
      FROM_PJ='MF5-KYLE';
      DIP_SMD='';
      DATA='PIM_PI3EQX12902AZLEX.pdf';
      EE_CHECK_LIST='';
      FP_ECN='';
      PSL='';
      CREATOR='';
      STATUS='';
      MSD='NA';
      ESD_CDM='+-500V';
      ESD_HBM='+-2kV';
      ESD_MM='NA';
      PIN_LENGTH_SHORT_PIN='0 MILS';
      PIN_LENGTH_LONG_PIN='0 MILS';
      CREATEDAY='20170824';
      PARENT_PART_TYPE='PI3EQX12902AZLEX';
      PARENT_PPT='PI3EQX12902AZLEX';
      PARENT_PPT_PART='PI3EQX12902AZLEX-PI3EQX12902AZLEX,SMLF,IC,AL012902001';
  end_body;
end_primitive;
primitive 'PI6CV304LE-PI6CV304LE,SMLF,IC,A';
  pin
    'CLK_IN':
      PIN_NUMBER='(1)';
      INPUT_LOAD='(-0.01,0.01)';
      PINUSE='IN';
    'OE':
      PIN_NUMBER='(2)';
      INPUT_LOAD='(-0.01,0.01)';
      PINUSE='IN';
    'Y0':
      PIN_NUMBER='(3)';
      OUTPUT_LOAD='(1.0,-1.0)';
      PINUSE='OUT';
    'Y1':
      PIN_NUMBER='(5)';
      OUTPUT_LOAD='(1.0,-1.0)';
      PINUSE='OUT';
    'Y2':
      PIN_NUMBER='(7)';
      OUTPUT_LOAD='(1.0,-1.0)';
      PINUSE='OUT';
    'Y3':
      PIN_NUMBER='(8)';
      OUTPUT_LOAD='(1.0,-1.0)';
      PINUSE='OUT';
    'VDD':
      PIN_NUMBER='(6)';
      PINUSE='POWER';
      NO_LOAD_CHECK='Both';
      NO_IO_CHECK='Both';
      NO_ASSERT_CHECK='TRUE';
      NO_DIR_CHECK='TRUE';
      ALLOW_CONNECT='TRUE';
    'GND':
      PIN_NUMBER='(4)';
      PINUSE='POWER';
      NO_LOAD_CHECK='Both';
      NO_IO_CHECK='Both';
      NO_ASSERT_CHECK='TRUE';
      NO_DIR_CHECK='TRUE';
      ALLOW_CONNECT='TRUE';
  end_pin;
  body
      PART_NAME='PI6CV304LE';
      BODY_NAME='PI6CV304LE';
      PHYS_DES_PREFIX='U';
      CLASS='IC';
      JEDEC_TYPE='TSSOP8';
      DESCRIPTION='IC OTHER(8P) PI6CV304LE(TSSOP)';
      MANUFTR='PIM';
      MANUF_PN='PI6CV304LE';
      RD_CMPLS_LVL='EP';
      CMPLS_LVL='EP';
      FROM_PJ='S4E-JAMES';
      DIP_SMD='';
      DATA='PI6CV304_PI6CV2304.pdf';
      EE_CHECK_LIST='';
      FP_ECN='';
      PSL='';
      LIFECYCLE='';
      CREATOR='';
      STANDARD='';
      CREATEDAY='20111206';
      STATUS='';
      PARENT_PART_TYPE='PI6CV304LE';
      PARENT_PPT='PI6CV304LE';
      PARENT_PPT_PART='PI6CV304LE-PI6CV304LE,SMLF,IC,AL000304K01';
  end_body;
end_primitive;
primitive 'PICOPROBE_BXA-DELTA-L 4.0,SMLFA';
  pin
    '2_N':
      PIN_NUMBER='(2)';
      PINUSE='POWER';
      NO_LOAD_CHECK='Both';
      NO_IO_CHECK='Both';
      NO_ASSERT_CHECK='TRUE';
      NO_DIR_CHECK='TRUE';
      ALLOW_CONNECT='TRUE';
    '3_G':
      PIN_NUMBER='(3)';
      PINUSE='POWER';
      NO_LOAD_CHECK='Both';
      NO_IO_CHECK='Both';
      NO_ASSERT_CHECK='TRUE';
      NO_DIR_CHECK='TRUE';
      ALLOW_CONNECT='TRUE';
    '1_P':
      PIN_NUMBER='(1)';
      PINUSE='POWER';
      NO_LOAD_CHECK='Both';
      NO_IO_CHECK='Both';
      NO_ASSERT_CHECK='TRUE';
      NO_DIR_CHECK='TRUE';
      ALLOW_CONNECT='TRUE';
  end_pin;
  body
      PART_NAME='PICOPROBE_BXA';
      BODY_NAME='PICOPROBE_BXA';
      PHYS_DES_PREFIX='J';
      CLASS='IO';
      STANDARD='';
      LIFECYCLE='';
      JEDEC_TYPE='TRIANG_LAUNCH_3PXB';
      ALT_SYMBOLS='';
      DESCRIPTION='Probe for DELTA-L 4.0 measurement';
      MANUFTR='';
      MANUF_PN='';
      RD_CMPLS_LVL='';
      CMPLS_LVL='';
      DIP_SMD='';
      FROM_PJ='';
      DATA='TRIANG_LAUNCH_3PXB.pdf';
      FP_ECN='TRIANG_LAUNCH_3PXB.xlsx';
      EE_CHECK_LIST='';
      STATUS='';
      PSL='';
      PREFERENCE='';
      CREATOR='';
      CREATEDAY='20200107';
      ESD_CDM='';
      ESD_HBM='';
      ESD_MM='';
      MSD='';
      PIN_LENGTH_LONG_PIN='';
      PIN_LENGTH_SHORT_PIN='';
      PARENT_PART_TYPE='PICOPROBE_BXA';
      PARENT_PPT='PICOPROBE_BXA';
      PARENT_PPT_PART='PICOPROBE_BXA-DELTA-L 4.0,SMLF,EMPTY,TP33';
  end_body;
end_primitive;
primitive 'QS3VH257QG8_SMLF-QS3VH257QG8,IA';
  pin
    'S':
      PIN_NUMBER='(1)';
      INPUT_LOAD='(-0.01,0.01)';
      PINUSE='IN';
    'E*':
      PIN_NUMBER='(15)';
      INPUT_LOAD='(-0.01,0.01)';
      PINUSE='IN';
    'YA':
      PIN_NUMBER='(4)';
      OUTPUT_LOAD='(1.0,-1.0)';
      PINUSE='OUT';
    'I0A':
      PIN_NUMBER='(2)';
      INPUT_LOAD='(-0.01,0.01)';
      PINUSE='IN';
    'I1A':
      PIN_NUMBER='(3)';
      INPUT_LOAD='(-0.01,0.01)';
      PINUSE='IN';
    'I0B':
      PIN_NUMBER='(5)';
      INPUT_LOAD='(-0.01,0.01)';
      PINUSE='IN';
    'I1B':
      PIN_NUMBER='(6)';
      INPUT_LOAD='(-0.01,0.01)';
      PINUSE='IN';
    'YB':
      PIN_NUMBER='(7)';
      OUTPUT_LOAD='(1.0,-1.0)';
      PINUSE='OUT';
    'I0C':
      PIN_NUMBER='(11)';
      INPUT_LOAD='(-0.01,0.01)';
      PINUSE='IN';
    'I1C':
      PIN_NUMBER='(10)';
      INPUT_LOAD='(-0.01,0.01)';
      PINUSE='IN';
    'YC':
      PIN_NUMBER='(9)';
      OUTPUT_LOAD='(1.0,-1.0)';
      PINUSE='OUT';
    'YD':
      PIN_NUMBER='(12)';
      OUTPUT_LOAD='(1.0,-1.0)';
      PINUSE='OUT';
    'I0D':
      PIN_NUMBER='(14)';
      INPUT_LOAD='(-0.01,0.01)';
      PINUSE='IN';
    'I1D':
      PIN_NUMBER='(13)';
      INPUT_LOAD='(-0.01,0.01)';
      PINUSE='IN';
    'GND':
      PIN_NUMBER='(8)';
      PINUSE='POWER';
    'VCC':
      PIN_NUMBER='(16)';
      PINUSE='POWER';
  end_pin;
  body
      PART_NAME='QS3VH257QG8';
      BODY_NAME='QS3VH257QG8';
      JEDEC_TYPE='QSOP16_0-635_4-89X3-9';
      PHYS_DES_PREFIX='U';
      CLASS='IC';
      STANDARD='';
      LIFECYCLE='';
      DESCRIPTION='IC OTHER(16P)QS3VH257QG8(QSOP)';
      HEIGHT='.068IN';
      COMPONENT_TYPE='SMALLSMT';
      LEAD_LENGTH='';
      DFM_EXCLUSION='';
      DAY='20210902';
      PARENT_PART_TYPE='QS3VH257QG8';
      PARENT_PPT='QS3VH257QG8';
      PARENT_PPT_PART='QS3VH257QG8_SMLF-QS3VH257QG8,IC,AL000257W24';
  end_body;
end_primitive;
primitive 'Q_CAPP_SMLF-100UF,16V,20%,OSCOA';
  pin
    'A':
      PIN_NUMBER='(1)';
      PIN_TYPE='UNSPEC';
      NO_LOAD_CHECK='BOTH';
      NO_IO_CHECK='BOTH';
      PINUSE='UNSPEC';
    'B':
      PIN_NUMBER='(2)';
      PIN_TYPE='UNSPEC';
      NO_LOAD_CHECK='BOTH';
      NO_IO_CHECK='BOTH';
      PINUSE='UNSPEC';
  end_pin;
  body
      PART_NAME='Q_CAPP';
      PHYS_DES_PREFIX='C';
      STANDARD='';
      LIFECYCLE='';
      JEDEC_TYPE='EC56_197_229SXA';
      VALUE='100UF';
      RATED_VOLTAGE='16V';
      TOL='20%';
      CLASS='DISCRETE';
      DESCRIPTION='CAP OSCON SMD 100U 16V(20%,5*5.8)NPN';
      COMPONENT_TYPE='SMT';
      LEAD_LENGTH='';
      DFM_EXCLUSION='';
      DAY='20190627';
      PARENT_PART_TYPE='Q_CAPP';
      PARENT_PPT='Q_CAPP';
      PARENT_PPT_PART='Q_CAPP_SMLF-100UF,16V,20%,OSCON,CC71003MZ30';
  end_body;
end_primitive;
primitive 'Q_CAPP_SMLF-220UF,6.3V,20%,ALUA';
  pin
    'A':
      PIN_NUMBER='(1)';
      PIN_TYPE='UNSPEC';
      NO_LOAD_CHECK='BOTH';
      NO_IO_CHECK='BOTH';
      PINUSE='UNSPEC';
    'B':
      PIN_NUMBER='(2)';
      PIN_TYPE='UNSPEC';
      NO_LOAD_CHECK='BOTH';
      NO_IO_CHECK='BOTH';
      PINUSE='UNSPEC';
  end_pin;
  body
      PART_NAME='Q_CAPP';
      PHYS_DES_PREFIX='C';
      STANDARD='';
      LIFECYCLE='';
      JEDEC_TYPE='EC56_197_229SXA';
      VALUE='220UF';
      RATED_VOLTAGE='6.3V';
      TOL='20%';
      CLASS='DISCRETE';
      DESCRIPTION='CAP OSCON SMD 220U 6.3V(20%,5*5.8)NPN';
      COMPONENT_TYPE='SMT';
      LEAD_LENGTH='';
      DFM_EXCLUSION='';
      DAY='20170503';
      PARENT_PART_TYPE='Q_CAPP';
      PARENT_PPT='Q_CAPP';
      PARENT_PPT_PART='Q_CAPP_SMLF-220UF,6.3V,20%,ALUM,CC72201MZ28';
  end_body;
end_primitive;
primitive 'Q_CAPP_SMLF-330UF,2.5V,+10/-35A';
  pin
    'A':
      PIN_NUMBER='(1)';
      PIN_TYPE='UNSPEC';
      NO_LOAD_CHECK='BOTH';
      NO_IO_CHECK='BOTH';
      PINUSE='UNSPEC';
    'B':
      PIN_NUMBER='(2)';
      PIN_TYPE='UNSPEC';
      NO_LOAD_CHECK='BOTH';
      NO_IO_CHECK='BOTH';
      PINUSE='UNSPEC';
  end_pin;
  body
      PART_NAME='Q_CAPP';
      PHYS_DES_PREFIX='C';
      STANDARD='';
      LIFECYCLE='';
      JEDEC_TYPE='TAJ_SX';
      VALUE='330UF';
      RATED_VOLTAGE='2.5V';
      TOL='+10/-35%';
      CLASS='IO';
      DESCRIPTION='CAPCHIP 330U 2.5V(10/-35%,SPCAP,7343)MAT';
      COMPONENT_TYPE='SMT';
      LEAD_LENGTH='';
      DFM_EXCLUSION='';
      DAY='20200326';
      PARENT_PART_TYPE='Q_CAPP';
      PARENT_PPT='Q_CAPP';
      PARENT_PPT_PART='Q_CAPP_SMLF-330UF,2.5V,+10/-35%,EMPTY,CH733LY8802';
  end_body;
end_primitive;
primitive 'Q_CAPP_SMLF-330UF,2.5V,+10/-35B';
  pin
    'A':
      PIN_NUMBER='(1)';
      PIN_TYPE='UNSPEC';
      NO_LOAD_CHECK='BOTH';
      NO_IO_CHECK='BOTH';
      PINUSE='UNSPEC';
    'B':
      PIN_NUMBER='(2)';
      PIN_TYPE='UNSPEC';
      NO_LOAD_CHECK='BOTH';
      NO_IO_CHECK='BOTH';
      PINUSE='UNSPEC';
  end_pin;
  body
      PART_NAME='Q_CAPP';
      PHYS_DES_PREFIX='C';
      STANDARD='';
      LIFECYCLE='';
      JEDEC_TYPE='TAJ_SX';
      VALUE='330UF';
      RATED_VOLTAGE='2.5V';
      TOL='+10/-35%';
      CLASS='DISCRETE';
      DESCRIPTION='CAPCHIP 330U 2.5V(10/-35%,SPCAP,7343)MAT';
      COMPONENT_TYPE='SMT';
      LEAD_LENGTH='';
      DFM_EXCLUSION='';
      DAY='20200326';
      PARENT_PART_TYPE='Q_CAPP';
      PARENT_PPT='Q_CAPP';
      PARENT_PPT_PART='Q_CAPP_SMLF-330UF,2.5V,+10/-35%,SPCAP,CH733LY8802';
  end_body;
end_primitive;
primitive 'Q_CAPP_SMLF-330UF,2V,35%,SPCAPA';
  pin
    'A':
      PIN_NUMBER='(1)';
      PIN_TYPE='UNSPEC';
      NO_LOAD_CHECK='BOTH';
      NO_IO_CHECK='BOTH';
      PINUSE='UNSPEC';
    'B':
      PIN_NUMBER='(2)';
      PIN_TYPE='UNSPEC';
      NO_LOAD_CHECK='BOTH';
      NO_IO_CHECK='BOTH';
      PINUSE='UNSPEC';
  end_pin;
  body
      PART_NAME='Q_CAPP';
      PHYS_DES_PREFIX='C';
      STANDARD='';
      LIFECYCLE='';
      JEDEC_TYPE='TAJ_DXC';
      VALUE='330U';
      RATED_VOLTAGE='2V';
      TOL='35%';
      CLASS='DISCRETE';
      DESCRIPTION='CAP CHIP 330U 2V(+10-35%,SPCAP,7343)MAT';
      COMPONENT_TYPE='SMT';
      LEAD_LENGTH='';
      DFM_EXCLUSION='';
      DAY='20171206';
      PARENT_PART_TYPE='Q_CAPP';
      PARENT_PPT='Q_CAPP';
      PARENT_PPT_PART='Q_CAPP_SMLF-330UF,2V,35%,SPCAP,CH733RY8807';
  end_body;
end_primitive;
primitive 'Q_CAPP_THLF-270UF,16V,20%,OSCOA';
  pin
    'A':
      PIN_NUMBER='(1)';
      PIN_TYPE='UNSPEC';
      NO_LOAD_CHECK='BOTH';
      NO_IO_CHECK='BOTH';
      PINUSE='UNSPEC';
    'B':
      PIN_NUMBER='(2)';
      PIN_TYPE='UNSPEC';
      NO_LOAD_CHECK='BOTH';
      NO_IO_CHECK='BOTH';
      PINUSE='UNSPEC';
  end_pin;
  body
      PART_NAME='Q_CAPP';
      PHYS_DES_PREFIX='C';
      STANDARD='';
      LIFECYCLE='';
      JEDEC_TYPE='EC2-5_6-8_9-2';
      VALUE='270UF';
      RATED_VOLTAGE='16V';
      TOL='20%';
      CLASS='DISCRETE';
      DESCRIPTION='CAPOSCON DIP 270U16V(20%,ESR10,6.3*8)NPN';
      COMPONENT_TYPE='DIP';
      LEAD_LENGTH='';
      DFM_EXCLUSION='';
      DAY='20190701';
      PARENT_PART_TYPE='Q_CAPP';
      PARENT_PPT='Q_CAPP';
      PARENT_PPT_PART='Q_CAPP_THLF-270UF,16V,20%,OSCON,CC72703MD38';
  end_body;
end_primitive;
primitive 'Q_CAPP_THLF-560UF,2.5V,20%,OSCA';
  pin
    'A':
      PIN_NUMBER='(1)';
      PIN_TYPE='UNSPEC';
      NO_LOAD_CHECK='BOTH';
      NO_IO_CHECK='BOTH';
      PINUSE='UNSPEC';
    'B':
      PIN_NUMBER='(2)';
      PIN_TYPE='UNSPEC';
      NO_LOAD_CHECK='BOTH';
      NO_IO_CHECK='BOTH';
      PINUSE='UNSPEC';
  end_pin;
  body
      PART_NAME='Q_CAPP';
      PHYS_DES_PREFIX='C';
      STANDARD='End of Design';
      LIFECYCLE='Comp-Approve';
      JEDEC_TYPE='EC2_5-5_9XB';
      VALUE='560UF';
      RATED_VOLTAGE='2.5V';
      TOL='20%';
      CLASS='DISCRETE';
      DESCRIPTION='CAP OSCON DIP 560U 2.5V(20%,5*8)SAY';
      COMPONENT_TYPE='DIP';
      LEAD_LENGTH='';
      DFM_EXCLUSION='';
      DAY='20190701';
      PARENT_PART_TYPE='Q_CAPP';
      PARENT_PPT='Q_CAPP';
      PARENT_PPT_PART='Q_CAPP_THLF-560UF,2.5V,20%,OSCON,CC7560JMD16';
  end_body;
end_primitive;
primitive 'Q_CAPP_THLF-560UF,6.3V,20%,OSCA';
  pin
    'A':
      PIN_NUMBER='(1)';
      PIN_TYPE='UNSPEC';
      NO_LOAD_CHECK='BOTH';
      NO_IO_CHECK='BOTH';
      PINUSE='UNSPEC';
    'B':
      PIN_NUMBER='(2)';
      PIN_TYPE='UNSPEC';
      NO_LOAD_CHECK='BOTH';
      NO_IO_CHECK='BOTH';
      PINUSE='UNSPEC';
  end_pin;
  body
      PART_NAME='Q_CAPP';
      PHYS_DES_PREFIX='C';
      STANDARD='';
      LIFECYCLE='';
      JEDEC_TYPE='EC2-5_6-8_9-5';
      VALUE='560UF';
      RATED_VOLTAGE='6.3V';
      TOL='20%';
      CLASS='DISCRETE';
      DESCRIPTION='CAP OSCON DIP 560U 6.3V(+-20%,6.3*8)NPN';
      COMPONENT_TYPE='DIP';
      LEAD_LENGTH='';
      DFM_EXCLUSION='';
      DAY='20190701';
      PARENT_PART_TYPE='Q_CAPP';
      PARENT_PPT='Q_CAPP';
      PARENT_PPT_PART='Q_CAPP_THLF-560UF,6.3V,20%,OSCON,CC75601MD16';
  end_body;
end_primitive;
primitive 'Q_CAP_0402-0.01UF,25V,10%,X7R,A';
  pin
    'A':
      PIN_NUMBER='(1)';
      PINUSE='UNSPEC';
      NO_LOAD_CHECK='BOTH';
      NO_IO_CHECK='BOTH';
      ALLOW_CONNECT='TRUE';
      PIN_GROUP='1';
    'B':
      PIN_NUMBER='(2)';
      PINUSE='UNSPEC';
      NO_LOAD_CHECK='BOTH';
      NO_IO_CHECK='BOTH';
      ALLOW_CONNECT='TRUE';
      PIN_GROUP='1';
  end_pin;
  body
      PART_NAME='Q_CAP';
      PHYS_DES_PREFIX='C';
      STANDARD='End of Design';
      LIFECYCLE='Comp-Release Qty';
      ASS_PART='';
      JEDEC_TYPE='C0402';
      ALT_SYMBOLS='(C0402-0201,C0402_OCTAGONXA)';
      VALUE='0.01UF';
      RATED_VOLTAGE='25V';
      TOL='10%';
      CLASS='DISCRETE';
      DESCRIPTION='CAP CHIP 0.01U 25V(+-10%,X7R,0402)';
      COMPONENT_TYPE='CHIP0402';
      LEAD_LENGTH='';
      LPID='';
      DATE='20100528';
      PARENT_PART_TYPE='Q_CAP';
      PARENT_PPT='Q_CAP';
      PARENT_PPT_PART='Q_CAP_0402-0.01UF,25V,10%,X7R,TMP_QCH31004KB17';
  end_body;
end_primitive;
primitive 'Q_CAP_0402-0.022UF,16V,10%,X7RA';
  pin
    'A':
      PIN_NUMBER='(1)';
      PINUSE='UNSPEC';
      NO_LOAD_CHECK='BOTH';
      NO_IO_CHECK='BOTH';
      ALLOW_CONNECT='TRUE';
      PIN_GROUP='1';
    'B':
      PIN_NUMBER='(2)';
      PINUSE='UNSPEC';
      NO_LOAD_CHECK='BOTH';
      NO_IO_CHECK='BOTH';
      ALLOW_CONNECT='TRUE';
      PIN_GROUP='1';
  end_pin;
  body
      PART_NAME='Q_CAP';
      PHYS_DES_PREFIX='C';
      STANDARD='';
      LIFECYCLE='';
      ASS_PART='';
      JEDEC_TYPE='C0402';
      ALT_SYMBOLS='(C0402-0201,C0402_OCTAGONXA)';
      VALUE='0.022UF';
      RATED_VOLTAGE='16V';
      TOL='10%';
      CLASS='DISCRETE';
      DESCRIPTION='CAP CHIP 0.022U 16V(+-10%,X7R,0402)';
      COMPONENT_TYPE='CHIP0402';
      LEAD_LENGTH='';
      LPID='';
      DATE='';
      PARENT_PART_TYPE='Q_CAP';
      PARENT_PPT='Q_CAP';
      PARENT_PPT_PART='Q_CAP_0402-0.022UF,16V,10%,X7R,TMP_QCH32203KB11';
  end_body;
end_primitive;
primitive 'Q_CAP_0402-0.068UF,16V,10%,EMPA';
  pin
    'A':
      PIN_NUMBER='(1)';
      PINUSE='UNSPEC';
      NO_LOAD_CHECK='BOTH';
      NO_IO_CHECK='BOTH';
      ALLOW_CONNECT='TRUE';
      PIN_GROUP='1';
    'B':
      PIN_NUMBER='(2)';
      PINUSE='UNSPEC';
      NO_LOAD_CHECK='BOTH';
      NO_IO_CHECK='BOTH';
      ALLOW_CONNECT='TRUE';
      PIN_GROUP='1';
  end_pin;
  body
      PART_NAME='Q_CAP';
      PHYS_DES_PREFIX='C';
      STANDARD='';
      LIFECYCLE='';
      ASS_PART='';
      JEDEC_TYPE='C0402';
      ALT_SYMBOLS='(C0402-0201)';
      VALUE='NA';
      RATED_VOLTAGE='16V';
      TOL='10%';
      CLASS='IO';
      DESCRIPTION='CAP CHIP 0.068UF 16V(+-10%,X7R 0402)';
      COMPONENT_TYPE='CHIP0402';
      LEAD_LENGTH='';
      LPID='';
      DATE='20100630';
      PARENT_PART_TYPE='Q_CAP';
      PARENT_PPT='Q_CAP';
      PARENT_PPT_PART='Q_CAP_0402-0.068UF,16V,10%,EMPTY,CH3683K1B09';
  end_body;
end_primitive;
primitive 'Q_CAP_0402-0.068UF,16V,10%,X7RA';
  pin
    'A':
      PIN_NUMBER='(1)';
      PINUSE='UNSPEC';
      NO_LOAD_CHECK='BOTH';
      NO_IO_CHECK='BOTH';
      ALLOW_CONNECT='TRUE';
      PIN_GROUP='1';
    'B':
      PIN_NUMBER='(2)';
      PINUSE='UNSPEC';
      NO_LOAD_CHECK='BOTH';
      NO_IO_CHECK='BOTH';
      ALLOW_CONNECT='TRUE';
      PIN_GROUP='1';
  end_pin;
  body
      PART_NAME='Q_CAP';
      PHYS_DES_PREFIX='C';
      STANDARD='';
      LIFECYCLE='';
      ASS_PART='';
      JEDEC_TYPE='C0402';
      ALT_SYMBOLS='(C0402-0201)';
      VALUE='0.068UF';
      RATED_VOLTAGE='16V';
      TOL='10%';
      CLASS='DISCRETE';
      DESCRIPTION='CAP CHIP 0.068UF 16V(+-10%,X7R 0402)';
      COMPONENT_TYPE='CHIP0402';
      LEAD_LENGTH='';
      LPID='';
      DATE='20100630';
      PARENT_PART_TYPE='Q_CAP';
      PARENT_PPT='Q_CAP';
      PARENT_PPT_PART='Q_CAP_0402-0.068UF,16V,10%,X7R,CH3683K1B09';
  end_body;
end_primitive;
primitive 'Q_CAP_0402-0.1UF,25V,10%,EMPTYA';
  pin
    'A':
      PIN_NUMBER='(1)';
      PINUSE='UNSPEC';
      NO_LOAD_CHECK='BOTH';
      NO_IO_CHECK='BOTH';
      ALLOW_CONNECT='TRUE';
      PIN_GROUP='1';
    'B':
      PIN_NUMBER='(2)';
      PINUSE='UNSPEC';
      NO_LOAD_CHECK='BOTH';
      NO_IO_CHECK='BOTH';
      ALLOW_CONNECT='TRUE';
      PIN_GROUP='1';
  end_pin;
  body
      PART_NAME='Q_CAP';
      PHYS_DES_PREFIX='C';
      STANDARD='';
      LIFECYCLE='';
      ASS_PART='';
      JEDEC_TYPE='C0402';
      ALT_SYMBOLS='(C0402_OCTAGONXA,C0402-0201)';
      VALUE='NA';
      RATED_VOLTAGE='25V';
      TOL='10%';
      CLASS='IO';
      DESCRIPTION='CAP CHIP 0.1U 25V(+-10%,X7R,0402)';
      COMPONENT_TYPE='CHIP0402';
      LEAD_LENGTH='';
      LPID='';
      DATE='20160113';
      PARENT_PART_TYPE='Q_CAP';
      PARENT_PPT='Q_CAP';
      PARENT_PPT_PART='Q_CAP_0402-0.1UF,25V,10%,EMPTY,CH4104K1B00';
  end_body;
end_primitive;
primitive 'Q_CAP_0402-0.1UF,25V,10%,X7R,CA';
  pin
    'A':
      PIN_NUMBER='(1)';
      PINUSE='UNSPEC';
      NO_LOAD_CHECK='BOTH';
      NO_IO_CHECK='BOTH';
      ALLOW_CONNECT='TRUE';
      PIN_GROUP='1';
    'B':
      PIN_NUMBER='(2)';
      PINUSE='UNSPEC';
      NO_LOAD_CHECK='BOTH';
      NO_IO_CHECK='BOTH';
      ALLOW_CONNECT='TRUE';
      PIN_GROUP='1';
  end_pin;
  body
      PART_NAME='Q_CAP';
      PHYS_DES_PREFIX='C';
      STANDARD='';
      LIFECYCLE='';
      ASS_PART='';
      JEDEC_TYPE='C0402';
      ALT_SYMBOLS='(C0402_OCTAGONXA,C0402-0201)';
      VALUE='0.1UF';
      RATED_VOLTAGE='25V';
      TOL='10%';
      CLASS='DISCRETE';
      DESCRIPTION='CAP CHIP 0.1U 25V(+-10%,X7R,0402)';
      COMPONENT_TYPE='CHIP0402';
      LEAD_LENGTH='';
      LPID='';
      DATE='20160113';
      PARENT_PART_TYPE='Q_CAP';
      PARENT_PPT='Q_CAP';
      PARENT_PPT_PART='Q_CAP_0402-0.1UF,25V,10%,X7R,CH4104K1B00';
  end_body;
end_primitive;
primitive 'Q_CAP_0402-0.22UF,16V,10%,X7R,A';
  pin
    'A':
      PIN_NUMBER='(1)';
      PINUSE='UNSPEC';
      NO_LOAD_CHECK='BOTH';
      NO_IO_CHECK='BOTH';
      ALLOW_CONNECT='TRUE';
      PIN_GROUP='1';
    'B':
      PIN_NUMBER='(2)';
      PINUSE='UNSPEC';
      NO_LOAD_CHECK='BOTH';
      NO_IO_CHECK='BOTH';
      ALLOW_CONNECT='TRUE';
      PIN_GROUP='1';
  end_pin;
  body
      PART_NAME='Q_CAP';
      PHYS_DES_PREFIX='C';
      STANDARD='End of Design';
      LIFECYCLE='Comp-Approve';
      ASS_PART='';
      JEDEC_TYPE='C0402';
      ALT_SYMBOLS='(C0402_OCTAGONXA,C0402-0201)';
      VALUE='0.22UF';
      RATED_VOLTAGE='16V';
      TOL='10%';
      CLASS='DISCRETE';
      DESCRIPTION='CAP CHIP 0.22U 16V(10%,X7R,0402)';
      COMPONENT_TYPE='CHIP0402';
      LEAD_LENGTH='';
      LPID='';
      DATE='20100916';
      PARENT_PART_TYPE='Q_CAP';
      PARENT_PPT='Q_CAP';
      PARENT_PPT_PART='Q_CAP_0402-0.22UF,16V,10%,X7R,CH4223K1B00';
  end_body;
end_primitive;
primitive 'Q_CAP_0402-1000PF,50V,5%,EMPTYA';
  pin
    'A':
      PIN_NUMBER='(1)';
      PINUSE='UNSPEC';
      NO_LOAD_CHECK='BOTH';
      NO_IO_CHECK='BOTH';
      ALLOW_CONNECT='TRUE';
      PIN_GROUP='1';
    'B':
      PIN_NUMBER='(2)';
      PINUSE='UNSPEC';
      NO_LOAD_CHECK='BOTH';
      NO_IO_CHECK='BOTH';
      ALLOW_CONNECT='TRUE';
      PIN_GROUP='1';
  end_pin;
  body
      PART_NAME='Q_CAP';
      PHYS_DES_PREFIX='C';
      STANDARD='';
      LIFECYCLE='';
      ASS_PART='';
      JEDEC_TYPE='C0402';
      ALT_SYMBOLS='(C0402-0201,C0402_OCTAGONXA)';
      VALUE='NA';
      RATED_VOLTAGE='50V';
      TOL='5%';
      CLASS='IO';
      DESCRIPTION='CAP CHIP 1000P 50V(+-5%,X7R,0402)';
      COMPONENT_TYPE='CHIP0402';
      LEAD_LENGTH='';
      LPID='';
      DATE='20100528';
      PARENT_PART_TYPE='Q_CAP';
      PARENT_PPT='Q_CAP';
      PARENT_PPT_PART='Q_CAP_0402-1000PF,50V,5%,EMPTY,TMP_QCH21006JB10';
  end_body;
end_primitive;
primitive 'Q_CAP_0402-1000PF,50V,5%,X7R,TA';
  pin
    'A':
      PIN_NUMBER='(1)';
      PINUSE='UNSPEC';
      NO_LOAD_CHECK='BOTH';
      NO_IO_CHECK='BOTH';
      ALLOW_CONNECT='TRUE';
      PIN_GROUP='1';
    'B':
      PIN_NUMBER='(2)';
      PINUSE='UNSPEC';
      NO_LOAD_CHECK='BOTH';
      NO_IO_CHECK='BOTH';
      ALLOW_CONNECT='TRUE';
      PIN_GROUP='1';
  end_pin;
  body
      PART_NAME='Q_CAP';
      PHYS_DES_PREFIX='C';
      STANDARD='';
      LIFECYCLE='';
      ASS_PART='';
      JEDEC_TYPE='C0402';
      ALT_SYMBOLS='(C0402-0201,C0402_OCTAGONXA)';
      VALUE='1000PF';
      RATED_VOLTAGE='50V';
      TOL='5%';
      CLASS='DISCRETE';
      DESCRIPTION='CAP CHIP 1000P 50V(+-5%,X7R,0402)';
      COMPONENT_TYPE='CHIP0402';
      LEAD_LENGTH='';
      LPID='';
      DATE='20100528';
      PARENT_PART_TYPE='Q_CAP';
      PARENT_PPT='Q_CAP';
      PARENT_PPT_PART='Q_CAP_0402-1000PF,50V,5%,X7R,TMP_QCH21006JB10';
  end_body;
end_primitive;
primitive 'Q_CAP_0402-100PF,50V,5%,EMPTY,A';
  pin
    'A':
      PIN_NUMBER='(1)';
      PINUSE='UNSPEC';
      NO_LOAD_CHECK='BOTH';
      NO_IO_CHECK='BOTH';
      ALLOW_CONNECT='TRUE';
      PIN_GROUP='1';
    'B':
      PIN_NUMBER='(2)';
      PINUSE='UNSPEC';
      NO_LOAD_CHECK='BOTH';
      NO_IO_CHECK='BOTH';
      ALLOW_CONNECT='TRUE';
      PIN_GROUP='1';
  end_pin;
  body
      PART_NAME='Q_CAP';
      PHYS_DES_PREFIX='C';
      STANDARD='End of Design';
      LIFECYCLE='Comp-Approve';
      ASS_PART='';
      JEDEC_TYPE='C0402';
      ALT_SYMBOLS='(C0402-0201)';
      VALUE='NA';
      RATED_VOLTAGE='50V';
      TOL='5%';
      CLASS='IO';
      DESCRIPTION='CAP CHIP 100P 50V(+-5%.X7R.0402)';
      COMPONENT_TYPE='CHIP0402';
      LEAD_LENGTH='';
      LPID='';
      DATE='20100929';
      PARENT_PART_TYPE='Q_CAP';
      PARENT_PPT='Q_CAP';
      PARENT_PPT_PART='Q_CAP_0402-100PF,50V,5%,EMPTY,CH11006JB18';
  end_body;
end_primitive;
primitive 'Q_CAP_0402-100PF,50V,5%,NPO,CHA';
  pin
    'A':
      PIN_NUMBER='(1)';
      PINUSE='UNSPEC';
      NO_LOAD_CHECK='BOTH';
      NO_IO_CHECK='BOTH';
      ALLOW_CONNECT='TRUE';
      PIN_GROUP='1';
    'B':
      PIN_NUMBER='(2)';
      PINUSE='UNSPEC';
      NO_LOAD_CHECK='BOTH';
      NO_IO_CHECK='BOTH';
      ALLOW_CONNECT='TRUE';
      PIN_GROUP='1';
  end_pin;
  body
      PART_NAME='Q_CAP';
      PHYS_DES_PREFIX='C';
      STANDARD='';
      LIFECYCLE='';
      ASS_PART='';
      JEDEC_TYPE='C0402';
      ALT_SYMBOLS='(C0402-0201)';
      VALUE='100PF';
      RATED_VOLTAGE='50V';
      TOL='5%';
      CLASS='DISCRETE';
      DESCRIPTION='CAP CHIP 100P 50V(+-5%,NPO,0402)';
      COMPONENT_TYPE='CHIP0402';
      LEAD_LENGTH='';
      LPID='';
      DATE='20100618';
      PARENT_PART_TYPE='Q_CAP';
      PARENT_PPT='Q_CAP';
      PARENT_PPT_PART='Q_CAP_0402-100PF,50V,5%,NPO,CH11006JB00';
  end_body;
end_primitive;
primitive 'Q_CAP_0402-100PF,50V,5%,X7R,CHA';
  pin
    'A':
      PIN_NUMBER='(1)';
      PINUSE='UNSPEC';
      NO_LOAD_CHECK='BOTH';
      NO_IO_CHECK='BOTH';
      ALLOW_CONNECT='TRUE';
      PIN_GROUP='1';
    'B':
      PIN_NUMBER='(2)';
      PINUSE='UNSPEC';
      NO_LOAD_CHECK='BOTH';
      NO_IO_CHECK='BOTH';
      ALLOW_CONNECT='TRUE';
      PIN_GROUP='1';
  end_pin;
  body
      PART_NAME='Q_CAP';
      PHYS_DES_PREFIX='C';
      STANDARD='End of Design';
      LIFECYCLE='Comp-Approve';
      ASS_PART='';
      JEDEC_TYPE='C0402';
      ALT_SYMBOLS='(C0402-0201)';
      VALUE='100PF';
      RATED_VOLTAGE='50V';
      TOL='5%';
      CLASS='DISCRETE';
      DESCRIPTION='CAP CHIP 100P 50V(+-5%.X7R.0402)';
      COMPONENT_TYPE='CHIP0402';
      LEAD_LENGTH='';
      LPID='';
      DATE='20100929';
      PARENT_PART_TYPE='Q_CAP';
      PARENT_PPT='Q_CAP';
      PARENT_PPT_PART='Q_CAP_0402-100PF,50V,5%,X7R,CH11006JB18';
  end_body;
end_primitive;
primitive 'Q_CAP_0402-18PF,50V,5%,C0G,CH0A';
  pin
    'A':
      PIN_NUMBER='(1)';
      PINUSE='UNSPEC';
      NO_LOAD_CHECK='BOTH';
      NO_IO_CHECK='BOTH';
      ALLOW_CONNECT='TRUE';
      PIN_GROUP='1';
    'B':
      PIN_NUMBER='(2)';
      PINUSE='UNSPEC';
      NO_LOAD_CHECK='BOTH';
      NO_IO_CHECK='BOTH';
      ALLOW_CONNECT='TRUE';
      PIN_GROUP='1';
  end_pin;
  body
      PART_NAME='Q_CAP';
      PHYS_DES_PREFIX='C';
      STANDARD='';
      LIFECYCLE='';
      ASS_PART='';
      JEDEC_TYPE='C0402';
      ALT_SYMBOLS='(C0402-0201)';
      VALUE='18PF';
      RATED_VOLTAGE='50V';
      TOL='5%';
      CLASS='DISCRETE';
      DESCRIPTION='CAP CHIP 18P 50V(+-5% C0G 0402)';
      COMPONENT_TYPE='CHIP0402';
      LEAD_LENGTH='';
      LPID='';
      DATE='20110119';
      PARENT_PART_TYPE='Q_CAP';
      PARENT_PPT='Q_CAP';
      PARENT_PPT_PART='Q_CAP_0402-18PF,50V,5%,C0G,CH01806JB07';
  end_body;
end_primitive;
primitive 'Q_CAP_0402-1NF,50V,10%,EMPTY,CA';
  pin
    'A':
      PIN_NUMBER='(1)';
      PINUSE='UNSPEC';
      NO_LOAD_CHECK='BOTH';
      NO_IO_CHECK='BOTH';
      ALLOW_CONNECT='TRUE';
      PIN_GROUP='1';
    'B':
      PIN_NUMBER='(2)';
      PINUSE='UNSPEC';
      NO_LOAD_CHECK='BOTH';
      NO_IO_CHECK='BOTH';
      ALLOW_CONNECT='TRUE';
      PIN_GROUP='1';
  end_pin;
  body
      PART_NAME='Q_CAP';
      PHYS_DES_PREFIX='C';
      STANDARD='';
      LIFECYCLE='';
      ASS_PART='';
      JEDEC_TYPE='C0402';
      ALT_SYMBOLS='(C0402-0201)';
      VALUE='NA';
      RATED_VOLTAGE='50V';
      TOL='10%';
      CLASS='IO';
      DESCRIPTION='CAP CHIP 1N 50V(+-10%,X7R,0402)EP';
      COMPONENT_TYPE='CHIP0402';
      LEAD_LENGTH='';
      LPID='';
      DATE='20100811';
      PARENT_PART_TYPE='Q_CAP';
      PARENT_PPT='Q_CAP';
      PARENT_PPT_PART='Q_CAP_0402-1NF,50V,10%,EMPTY,CH21006KB16';
  end_body;
end_primitive;
primitive 'Q_CAP_0402-1UF,6.3V,10%,EMPTY,A';
  pin
    'A':
      PIN_NUMBER='(1)';
      PINUSE='UNSPEC';
      NO_LOAD_CHECK='BOTH';
      NO_IO_CHECK='BOTH';
      ALLOW_CONNECT='TRUE';
      PIN_GROUP='1';
    'B':
      PIN_NUMBER='(2)';
      PINUSE='UNSPEC';
      NO_LOAD_CHECK='BOTH';
      NO_IO_CHECK='BOTH';
      ALLOW_CONNECT='TRUE';
      PIN_GROUP='1';
  end_pin;
  body
      PART_NAME='Q_CAP';
      PHYS_DES_PREFIX='C';
      STANDARD='';
      LIFECYCLE='';
      ASS_PART='';
      JEDEC_TYPE='C0402';
      ALT_SYMBOLS='(C0402_OCTAGONXA,C0402-0201)';
      VALUE='NA';
      RATED_VOLTAGE='6.3V';
      TOL='10%';
      CLASS='IO';
      DESCRIPTION='CAP CHIP 1U,6.3V(+-10%,X7R,0402)';
      COMPONENT_TYPE='CHIP0402';
      LEAD_LENGTH='';
      LPID='';
      DATE='20150410';
      PARENT_PART_TYPE='Q_CAP';
      PARENT_PPT='Q_CAP';
      PARENT_PPT_PART='Q_CAP_0402-1UF,6.3V,10%,EMPTY,CH5101K1B01';
  end_body;
end_primitive;
primitive 'Q_CAP_0402-220PF,50V,10%,EMPTYA';
  pin
    'A':
      PIN_NUMBER='(1)';
      PINUSE='UNSPEC';
      NO_LOAD_CHECK='BOTH';
      NO_IO_CHECK='BOTH';
      ALLOW_CONNECT='TRUE';
      PIN_GROUP='1';
    'B':
      PIN_NUMBER='(2)';
      PINUSE='UNSPEC';
      NO_LOAD_CHECK='BOTH';
      NO_IO_CHECK='BOTH';
      ALLOW_CONNECT='TRUE';
      PIN_GROUP='1';
  end_pin;
  body
      PART_NAME='Q_CAP';
      PHYS_DES_PREFIX='C';
      STANDARD='';
      LIFECYCLE='';
      ASS_PART='';
      JEDEC_TYPE='C0402';
      ALT_SYMBOLS='(C0402-0201)';
      VALUE='NA';
      RATED_VOLTAGE='50V';
      TOL='10%';
      CLASS='IO';
      DESCRIPTION='CAP CHIP 220P 50V(+-10%,X7R,0402)';
      COMPONENT_TYPE='CHIP0402';
      LEAD_LENGTH='';
      LPID='';
      DATE='';
      PARENT_PART_TYPE='Q_CAP';
      PARENT_PPT='Q_CAP';
      PARENT_PPT_PART='Q_CAP_0402-220PF,50V,10%,EMPTY,TMP_QCH12206KB14';
  end_body;
end_primitive;
primitive 'Q_CAP_0402-220PF,50V,10%,X7R,TA';
  pin
    'A':
      PIN_NUMBER='(1)';
      PINUSE='UNSPEC';
      NO_LOAD_CHECK='BOTH';
      NO_IO_CHECK='BOTH';
      ALLOW_CONNECT='TRUE';
      PIN_GROUP='1';
    'B':
      PIN_NUMBER='(2)';
      PINUSE='UNSPEC';
      NO_LOAD_CHECK='BOTH';
      NO_IO_CHECK='BOTH';
      ALLOW_CONNECT='TRUE';
      PIN_GROUP='1';
  end_pin;
  body
      PART_NAME='Q_CAP';
      PHYS_DES_PREFIX='C';
      STANDARD='';
      LIFECYCLE='';
      ASS_PART='';
      JEDEC_TYPE='C0402';
      ALT_SYMBOLS='(C0402-0201)';
      VALUE='220PF';
      RATED_VOLTAGE='50V';
      TOL='10%';
      CLASS='DISCRETE';
      DESCRIPTION='CAP CHIP 220P 50V(+-10%,X7R,0402)';
      COMPONENT_TYPE='CHIP0402';
      LEAD_LENGTH='';
      LPID='';
      DATE='';
      PARENT_PART_TYPE='Q_CAP';
      PARENT_PPT='Q_CAP';
      PARENT_PPT_PART='Q_CAP_0402-220PF,50V,10%,X7R,TMP_QCH12206KB14';
  end_body;
end_primitive;
primitive 'Q_CAP_0402-27PF  ,50V ,5% ,EMPA';
  pin
    'A':
      PIN_NUMBER='(1)';
      PINUSE='UNSPEC';
      NO_LOAD_CHECK='BOTH';
      NO_IO_CHECK='BOTH';
      ALLOW_CONNECT='TRUE';
      PIN_GROUP='1';
    'B':
      PIN_NUMBER='(2)';
      PINUSE='UNSPEC';
      NO_LOAD_CHECK='BOTH';
      NO_IO_CHECK='BOTH';
      ALLOW_CONNECT='TRUE';
      PIN_GROUP='1';
  end_pin;
  body
      PART_NAME='Q_CAP';
      PHYS_DES_PREFIX='C';
      STANDARD='';
      LIFECYCLE='';
      ASS_PART='';
      JEDEC_TYPE='C0402';
      ALT_SYMBOLS='(C0402-0201)';
      VALUE='NA';
      RATED_VOLTAGE='50V';
      TOL='5% ';
      CLASS='IO';
      DESCRIPTION='CAP CHIP 27P 50V(+-5% NPO 0402)          ';
      COMPONENT_TYPE='CHIP0402';
      LEAD_LENGTH='';
      LPID='';
      DATE='20100811';
      PARENT_PART_TYPE='Q_CAP';
      PARENT_PPT='Q_CAP';
      PARENT_PPT_PART='Q_CAP_0402-27PF  ,50V ,5% ,EMPTY,CH02706JB06';
  end_body;
end_primitive;
primitive 'Q_CAP_0402-3300PF,50V,10%,X7R,A';
  pin
    'A':
      PIN_NUMBER='(1)';
      PINUSE='UNSPEC';
      NO_LOAD_CHECK='BOTH';
      NO_IO_CHECK='BOTH';
      ALLOW_CONNECT='TRUE';
      PIN_GROUP='1';
    'B':
      PIN_NUMBER='(2)';
      PINUSE='UNSPEC';
      NO_LOAD_CHECK='BOTH';
      NO_IO_CHECK='BOTH';
      ALLOW_CONNECT='TRUE';
      PIN_GROUP='1';
  end_pin;
  body
      PART_NAME='Q_CAP';
      PHYS_DES_PREFIX='C';
      STANDARD='';
      LIFECYCLE='';
      ASS_PART='';
      JEDEC_TYPE='C0402';
      ALT_SYMBOLS='(C0402-0201)';
      VALUE='3300PF';
      RATED_VOLTAGE='50V';
      TOL='10%';
      CLASS='DISCRETE';
      DESCRIPTION='CHIP0402';
      COMPONENT_TYPE='CHIP0402';
      LEAD_LENGTH='';
      LPID='';
      DATE='';
      PARENT_PART_TYPE='Q_CAP';
      PARENT_PPT='Q_CAP';
      PARENT_PPT_PART='Q_CAP_0402-3300PF,50V,10%,X7R,TMP_QCH2336K1B12';
  end_body;
end_primitive;
primitive 'Q_CAP_0402-470PF,50V,10%,X7R,TA';
  pin
    'A':
      PIN_NUMBER='(1)';
      PINUSE='UNSPEC';
      NO_LOAD_CHECK='BOTH';
      NO_IO_CHECK='BOTH';
      ALLOW_CONNECT='TRUE';
      PIN_GROUP='1';
    'B':
      PIN_NUMBER='(2)';
      PINUSE='UNSPEC';
      NO_LOAD_CHECK='BOTH';
      NO_IO_CHECK='BOTH';
      ALLOW_CONNECT='TRUE';
      PIN_GROUP='1';
  end_pin;
  body
      PART_NAME='Q_CAP';
      PHYS_DES_PREFIX='C';
      STANDARD='';
      LIFECYCLE='';
      ASS_PART='';
      JEDEC_TYPE='C0402';
      ALT_SYMBOLS='(C0402-0201)';
      VALUE='470PF';
      RATED_VOLTAGE='50V';
      TOL='10%';
      CLASS='DISCRETE';
      DESCRIPTION='CHIP0402';
      COMPONENT_TYPE='CHIP0402';
      LEAD_LENGTH='';
      LPID='';
      DATE='';
      PARENT_PART_TYPE='Q_CAP';
      PARENT_PPT='Q_CAP';
      PARENT_PPT_PART='Q_CAP_0402-470PF,50V,10%,X7R,TMP_QCH14706KB18';
  end_body;
end_primitive;
primitive 'Q_CAP_0402-47PF,50V,5%,NPO,TMPA';
  pin
    'A':
      PIN_NUMBER='(1)';
      PINUSE='UNSPEC';
      NO_LOAD_CHECK='BOTH';
      NO_IO_CHECK='BOTH';
      ALLOW_CONNECT='TRUE';
      PIN_GROUP='1';
    'B':
      PIN_NUMBER='(2)';
      PINUSE='UNSPEC';
      NO_LOAD_CHECK='BOTH';
      NO_IO_CHECK='BOTH';
      ALLOW_CONNECT='TRUE';
      PIN_GROUP='1';
  end_pin;
  body
      PART_NAME='Q_CAP';
      PHYS_DES_PREFIX='C';
      STANDARD='';
      LIFECYCLE='';
      ASS_PART='';
      JEDEC_TYPE='C0402';
      ALT_SYMBOLS='(C0402-0201)';
      VALUE='47PF';
      RATED_VOLTAGE='50V';
      TOL='5%';
      CLASS='DISCRETE';
      DESCRIPTION='CHIP0402';
      COMPONENT_TYPE='CHIP0402';
      LEAD_LENGTH='';
      LPID='';
      DATE='';
      PARENT_PART_TYPE='Q_CAP';
      PARENT_PPT='Q_CAP';
      PARENT_PPT_PART='Q_CAP_0402-47PF,50V,5%,NPO,TMP_QCH04706JB01';
  end_body;
end_primitive;
primitive 'Q_CAP_0402-680PF,50V,10%,X7R,TA';
  pin
    'A':
      PIN_NUMBER='(1)';
      PINUSE='UNSPEC';
      NO_LOAD_CHECK='BOTH';
      NO_IO_CHECK='BOTH';
      ALLOW_CONNECT='TRUE';
      PIN_GROUP='1';
    'B':
      PIN_NUMBER='(2)';
      PINUSE='UNSPEC';
      NO_LOAD_CHECK='BOTH';
      NO_IO_CHECK='BOTH';
      ALLOW_CONNECT='TRUE';
      PIN_GROUP='1';
  end_pin;
  body
      PART_NAME='Q_CAP';
      PHYS_DES_PREFIX='C';
      STANDARD='';
      LIFECYCLE='';
      ASS_PART='';
      JEDEC_TYPE='C0402';
      ALT_SYMBOLS='(C0402-0201)';
      VALUE='680PF';
      RATED_VOLTAGE='50V';
      TOL='10%';
      CLASS='DISCRETE';
      DESCRIPTION='CAP CHIP 680P 50V(+-10%,X7R,0402)';
      COMPONENT_TYPE='CHIP0402';
      LEAD_LENGTH='';
      LPID='';
      DATE='';
      PARENT_PART_TYPE='Q_CAP';
      PARENT_PPT='Q_CAP';
      PARENT_PPT_PART='Q_CAP_0402-680PF,50V,10%,X7R,TMP_QCH16806KB17';
  end_body;
end_primitive;
primitive 'Q_CAP_0603-1000PF,50V,10%,EMPTA';
  pin
    'A':
      PIN_NUMBER='(1)';
      PINUSE='UNSPEC';
      NO_LOAD_CHECK='BOTH';
      NO_IO_CHECK='BOTH';
      ALLOW_CONNECT='TRUE';
      PIN_GROUP='1';
    'B':
      PIN_NUMBER='(2)';
      PINUSE='UNSPEC';
      NO_LOAD_CHECK='BOTH';
      NO_IO_CHECK='BOTH';
      ALLOW_CONNECT='TRUE';
      PIN_GROUP='1';
  end_pin;
  body
      PART_NAME='Q_CAP';
      PHYS_DES_PREFIX='C';
      STANDARD='End of Design';
      LIFECYCLE='Comp-Approve';
      ASS_PART='';
      JEDEC_TYPE='C0603';
      ALT_SYMBOLS='(SMC0603AW)';
      VALUE='NA';
      RATED_VOLTAGE='50V';
      TOL='10%';
      CLASS='IO';
      DESCRIPTION='CAP CHIP 1000P 50V(+-10%,X7R,0603)';
      COMPONENT_TYPE='CHIP0603';
      LEAD_LENGTH='';
      LPID='';
      DATE='20100528';
      PARENT_PART_TYPE='Q_CAP';
      PARENT_PPT='Q_CAP';
      PARENT_PPT_PART='Q_CAP_0603-1000PF,50V,10%,EMPTY,TMP_QCH21006K917';
  end_body;
end_primitive;
primitive 'Q_CAP_C0201-0.1UF,6.3V,10%,X6SA';
  pin
    'A':
      PIN_NUMBER='(1)';
      PINUSE='UNSPEC';
      NO_LOAD_CHECK='BOTH';
      NO_IO_CHECK='BOTH';
      ALLOW_CONNECT='TRUE';
      PIN_GROUP='1';
    'B':
      PIN_NUMBER='(2)';
      PINUSE='UNSPEC';
      NO_LOAD_CHECK='BOTH';
      NO_IO_CHECK='BOTH';
      ALLOW_CONNECT='TRUE';
      PIN_GROUP='1';
  end_pin;
  body
      PART_NAME='Q_CAP';
      PHYS_DES_PREFIX='C';
      STANDARD='';
      LIFECYCLE='';
      ASS_PART='';
      JEDEC_TYPE='C0201';
      ALT_SYMBOLS='(SMC0201AW)';
      VALUE='0.1UF';
      RATED_VOLTAGE='6.3V';
      TOL='10%';
      CLASS='DISCRETE';
      DESCRIPTION='CAP CHIP 0.1UF 6.3V(10%,X6S,0201,H0.3)';
      COMPONENT_TYPE='CHIP0201';
      LEAD_LENGTH='';
      LPID='';
      DATE='20140508';
      PARENT_PART_TYPE='Q_CAP';
      PARENT_PPT='Q_CAP';
      PARENT_PPT_PART='Q_CAP_C0201-0.1UF,6.3V,10%,X6S,CH4101KEE01';
  end_body;
end_primitive;
primitive 'Q_CAP_C0201-0.22UF,6.3V,10%,X6A';
  pin
    'A':
      PIN_NUMBER='(1)';
      PINUSE='UNSPEC';
      NO_LOAD_CHECK='BOTH';
      NO_IO_CHECK='BOTH';
      ALLOW_CONNECT='TRUE';
      PIN_GROUP='1';
    'B':
      PIN_NUMBER='(2)';
      PINUSE='UNSPEC';
      NO_LOAD_CHECK='BOTH';
      NO_IO_CHECK='BOTH';
      ALLOW_CONNECT='TRUE';
      PIN_GROUP='1';
  end_pin;
  body
      PART_NAME='Q_CAP';
      PHYS_DES_PREFIX='C';
      STANDARD='';
      LIFECYCLE='';
      ASS_PART='';
      JEDEC_TYPE='C0201';
      ALT_SYMBOLS='(SMC0201AW)';
      VALUE='0.22UF';
      RATED_VOLTAGE='6.3V';
      TOL='10%';
      CLASS='DISCRETE';
      DESCRIPTION='CAP CHIP 0.22UF 6.3V(+-10%,X6S,0201)';
      COMPONENT_TYPE='CHIP0201';
      LEAD_LENGTH='';
      LPID='';
      DATE='20171116';
      PARENT_PART_TYPE='Q_CAP';
      PARENT_PPT='Q_CAP';
      PARENT_PPT_PART='Q_CAP_C0201-0.22UF,6.3V,10%,X6S,CH4221KEE00';
  end_body;
end_primitive;
primitive 'Q_CAP_C0402-0.001UF,50V,10%,X7A';
  pin
    'A':
      PIN_NUMBER='(1)';
      PINUSE='UNSPEC';
      NO_LOAD_CHECK='BOTH';
      NO_IO_CHECK='BOTH';
      ALLOW_CONNECT='TRUE';
      PIN_GROUP='1';
    'B':
      PIN_NUMBER='(2)';
      PINUSE='UNSPEC';
      NO_LOAD_CHECK='BOTH';
      NO_IO_CHECK='BOTH';
      ALLOW_CONNECT='TRUE';
      PIN_GROUP='1';
  end_pin;
  body
      PART_NAME='Q_CAP';
      PHYS_DES_PREFIX='C';
      STANDARD='End of Design';
      LIFECYCLE='Comp-Release Qty';
      ASS_PART='';
      JEDEC_TYPE='C0402';
      ALT_SYMBOLS='(C0402-0201)';
      VALUE='0.001UF';
      RATED_VOLTAGE='50V';
      TOL='10%';
      CLASS='DISCRETE';
      DESCRIPTION='CAP CHIP 0.001U 50V(10%,X7R,0402)';
      COMPONENT_TYPE='CHIP0402';
      LEAD_LENGTH='';
      LPID='';
      DATE='20200218';
      PARENT_PART_TYPE='Q_CAP';
      PARENT_PPT='Q_CAP';
      PARENT_PPT_PART='Q_CAP_C0402-0.001UF,50V,10%,X7R,CH30106KB19';
  end_body;
end_primitive;
primitive 'Q_CAP_C0402-0.01UF,50V,10%,EMPA';
  pin
    'A':
      PIN_NUMBER='(1)';
      PINUSE='UNSPEC';
      NO_LOAD_CHECK='BOTH';
      NO_IO_CHECK='BOTH';
      ALLOW_CONNECT='TRUE';
      PIN_GROUP='1';
    'B':
      PIN_NUMBER='(2)';
      PINUSE='UNSPEC';
      NO_LOAD_CHECK='BOTH';
      NO_IO_CHECK='BOTH';
      ALLOW_CONNECT='TRUE';
      PIN_GROUP='1';
  end_pin;
  body
      PART_NAME='Q_CAP';
      PHYS_DES_PREFIX='C';
      STANDARD='';
      LIFECYCLE='';
      ASS_PART='';
      JEDEC_TYPE='C0402';
      ALT_SYMBOLS='(C0402_OCTAGONXA,C0402-0201)';
      VALUE='NA';
      RATED_VOLTAGE='50V';
      TOL='10%';
      CLASS='IO';
      DESCRIPTION='CAP CHIP 0.01U 50V(+-10%,X7R,0402)';
      COMPONENT_TYPE='CHIP0402';
      LEAD_LENGTH='';
      LPID='';
      DATE='20120326';
      PARENT_PART_TYPE='Q_CAP';
      PARENT_PPT='Q_CAP';
      PARENT_PPT_PART='Q_CAP_C0402-0.01UF,50V,10%,EMPTY,CH31006KB18';
  end_body;
end_primitive;
primitive 'Q_CAP_C0402-0.01UF,50V,10%,X7RA';
  pin
    'A':
      PIN_NUMBER='(1)';
      PINUSE='UNSPEC';
      NO_LOAD_CHECK='BOTH';
      NO_IO_CHECK='BOTH';
      ALLOW_CONNECT='TRUE';
      PIN_GROUP='1';
    'B':
      PIN_NUMBER='(2)';
      PINUSE='UNSPEC';
      NO_LOAD_CHECK='BOTH';
      NO_IO_CHECK='BOTH';
      ALLOW_CONNECT='TRUE';
      PIN_GROUP='1';
  end_pin;
  body
      PART_NAME='Q_CAP';
      PHYS_DES_PREFIX='C';
      STANDARD='';
      LIFECYCLE='';
      ASS_PART='';
      JEDEC_TYPE='C0402';
      ALT_SYMBOLS='(C0402_OCTAGONXA,C0402-0201)';
      VALUE='0.01UF';
      RATED_VOLTAGE='50V';
      TOL='10%';
      CLASS='DISCRETE';
      DESCRIPTION='CAP CHIP 0.01U 50V(+-10%,X7R,0402)';
      COMPONENT_TYPE='CHIP0402';
      LEAD_LENGTH='';
      LPID='';
      DATE='20120326';
      PARENT_PART_TYPE='Q_CAP';
      PARENT_PPT='Q_CAP';
      PARENT_PPT_PART='Q_CAP_C0402-0.01UF,50V,10%,X7R,CH31006KB18';
  end_body;
end_primitive;
primitive 'Q_CAP_C0402-0.047UF,25V,10%,X7A';
  pin
    'A':
      PIN_NUMBER='(1)';
      PINUSE='UNSPEC';
      NO_LOAD_CHECK='BOTH';
      NO_IO_CHECK='BOTH';
      ALLOW_CONNECT='TRUE';
      PIN_GROUP='1';
    'B':
      PIN_NUMBER='(2)';
      PINUSE='UNSPEC';
      NO_LOAD_CHECK='BOTH';
      NO_IO_CHECK='BOTH';
      ALLOW_CONNECT='TRUE';
      PIN_GROUP='1';
  end_pin;
  body
      PART_NAME='Q_CAP';
      PHYS_DES_PREFIX='C';
      STANDARD='';
      LIFECYCLE='';
      ASS_PART='';
      JEDEC_TYPE='C0402';
      ALT_SYMBOLS='(C0402_OCTAGONXA,C0402-0201)';
      VALUE='0.047UF';
      RATED_VOLTAGE='25V';
      TOL='10%';
      CLASS='DISCRETE';
      DESCRIPTION='CAP CHIP 0.047U 25V(+-10% X7R 0402)';
      COMPONENT_TYPE='CHIP0402';
      LEAD_LENGTH='';
      LPID='';
      DATE='20140325';
      PARENT_PART_TYPE='Q_CAP';
      PARENT_PPT='Q_CAP';
      PARENT_PPT_PART='Q_CAP_C0402-0.047UF,25V,10%,X7R,CH3474K1B04';
  end_body;
end_primitive;
primitive 'Q_CAP_C0402-0.22UF,25V,10%,X7RA';
  pin
    'A':
      PIN_NUMBER='(1)';
      PINUSE='UNSPEC';
      NO_LOAD_CHECK='BOTH';
      NO_IO_CHECK='BOTH';
      ALLOW_CONNECT='TRUE';
      PIN_GROUP='1';
    'B':
      PIN_NUMBER='(2)';
      PINUSE='UNSPEC';
      NO_LOAD_CHECK='BOTH';
      NO_IO_CHECK='BOTH';
      ALLOW_CONNECT='TRUE';
      PIN_GROUP='1';
  end_pin;
  body
      PART_NAME='Q_CAP';
      PHYS_DES_PREFIX='C';
      STANDARD='End of Design';
      LIFECYCLE='Comp-Release Qty';
      ASS_PART='';
      JEDEC_TYPE='C0402';
      ALT_SYMBOLS='(C0402_OCTAGONXA,C0402-0201)';
      VALUE='0.22UF';
      RATED_VOLTAGE='25V';
      TOL='10%';
      CLASS='DISCRETE';
      DESCRIPTION='CAP CHIP 0.22U 25V(10%,X7R,0402)';
      COMPONENT_TYPE='CHIP0402';
      LEAD_LENGTH='';
      LPID='';
      DATE='20171109';
      PARENT_PART_TYPE='Q_CAP';
      PARENT_PPT='Q_CAP';
      PARENT_PPT_PART='Q_CAP_C0402-0.22UF,25V,10%,X7R,CH4224K1B01';
  end_body;
end_primitive;
primitive 'Q_CAP_C0402-100NF,50V,10%,EMPTA';
  pin
    'A':
      PIN_NUMBER='(1)';
      PINUSE='UNSPEC';
      NO_LOAD_CHECK='BOTH';
      NO_IO_CHECK='BOTH';
      ALLOW_CONNECT='TRUE';
      PIN_GROUP='1';
    'B':
      PIN_NUMBER='(2)';
      PINUSE='UNSPEC';
      NO_LOAD_CHECK='BOTH';
      NO_IO_CHECK='BOTH';
      ALLOW_CONNECT='TRUE';
      PIN_GROUP='1';
  end_pin;
  body
      PART_NAME='Q_CAP';
      PHYS_DES_PREFIX='C';
      STANDARD='';
      LIFECYCLE='';
      ASS_PART='';
      JEDEC_TYPE='C0402';
      ALT_SYMBOLS='(C0402_OCTAGONXA,C0402-0201)';
      VALUE='NA';
      RATED_VOLTAGE='50V';
      TOL='10%';
      CLASS='IO';
      DESCRIPTION='CAP CHIP 100NF 50V(+-10%,X7R,0402)';
      COMPONENT_TYPE='CHIP0402';
      LEAD_LENGTH='';
      LPID='';
      DATE='20171109';
      PARENT_PART_TYPE='Q_CAP';
      PARENT_PPT='Q_CAP';
      PARENT_PPT_PART='Q_CAP_C0402-100NF,50V,10%,EMPTY,CH4106K1B01';
  end_body;
end_primitive;
primitive 'Q_CAP_C0402-100NF,50V,10%,X7R,A';
  pin
    'A':
      PIN_NUMBER='(1)';
      PINUSE='UNSPEC';
      NO_LOAD_CHECK='BOTH';
      NO_IO_CHECK='BOTH';
      ALLOW_CONNECT='TRUE';
      PIN_GROUP='1';
    'B':
      PIN_NUMBER='(2)';
      PINUSE='UNSPEC';
      NO_LOAD_CHECK='BOTH';
      NO_IO_CHECK='BOTH';
      ALLOW_CONNECT='TRUE';
      PIN_GROUP='1';
  end_pin;
  body
      PART_NAME='Q_CAP';
      PHYS_DES_PREFIX='C';
      STANDARD='';
      LIFECYCLE='';
      ASS_PART='';
      JEDEC_TYPE='C0402';
      ALT_SYMBOLS='(C0402_OCTAGONXA,C0402-0201)';
      VALUE='100NF';
      RATED_VOLTAGE='50V';
      TOL='10%';
      CLASS='DISCRETE';
      DESCRIPTION='CAP CHIP 100NF 50V(+-10%,X7R,0402)';
      COMPONENT_TYPE='CHIP0402';
      LEAD_LENGTH='';
      LPID='';
      DATE='20171109';
      PARENT_PART_TYPE='Q_CAP';
      PARENT_PPT='Q_CAP';
      PARENT_PPT_PART='Q_CAP_C0402-100NF,50V,10%,X7R,CH4106K1B01';
  end_body;
end_primitive;
primitive 'Q_CAP_C0402-10UF,6.3V,20%,EMPTA';
  pin
    'A':
      PIN_NUMBER='(1)';
      PINUSE='UNSPEC';
      NO_LOAD_CHECK='BOTH';
      NO_IO_CHECK='BOTH';
      ALLOW_CONNECT='TRUE';
      PIN_GROUP='1';
    'B':
      PIN_NUMBER='(2)';
      PINUSE='UNSPEC';
      NO_LOAD_CHECK='BOTH';
      NO_IO_CHECK='BOTH';
      ALLOW_CONNECT='TRUE';
      PIN_GROUP='1';
  end_pin;
  body
      PART_NAME='Q_CAP';
      PHYS_DES_PREFIX='C';
      STANDARD='';
      LIFECYCLE='';
      ASS_PART='';
      JEDEC_TYPE='C0402';
      ALT_SYMBOLS='(C0402_OCTAGONXA,C0402-0201)';
      VALUE='NA';
      RATED_VOLTAGE='6.3V';
      TOL='20%';
      CLASS='IO';
      DESCRIPTION='CAP CHIP 10UF 6.3V(+-20%,X6S,0402)';
      COMPONENT_TYPE='CHIP0402';
      LEAD_LENGTH='';
      LPID='';
      DATE='20170330';
      PARENT_PART_TYPE='Q_CAP';
      PARENT_PPT='Q_CAP';
      PARENT_PPT_PART='Q_CAP_C0402-10UF,6.3V,20%,EMPTY,CH6101MEB01';
  end_body;
end_primitive;
primitive 'Q_CAP_C0402-10UF,6.3V,20%,X6S,A';
  pin
    'A':
      PIN_NUMBER='(1)';
      PINUSE='UNSPEC';
      NO_LOAD_CHECK='BOTH';
      NO_IO_CHECK='BOTH';
      ALLOW_CONNECT='TRUE';
      PIN_GROUP='1';
    'B':
      PIN_NUMBER='(2)';
      PINUSE='UNSPEC';
      NO_LOAD_CHECK='BOTH';
      NO_IO_CHECK='BOTH';
      ALLOW_CONNECT='TRUE';
      PIN_GROUP='1';
  end_pin;
  body
      PART_NAME='Q_CAP';
      PHYS_DES_PREFIX='C';
      STANDARD='';
      LIFECYCLE='';
      ASS_PART='';
      JEDEC_TYPE='C0402';
      ALT_SYMBOLS='(C0402_OCTAGONXA,C0402-0201)';
      VALUE='10UF';
      RATED_VOLTAGE='6.3V';
      TOL='20%';
      CLASS='DISCRETE';
      DESCRIPTION='CAP CHIP 10UF 6.3V(+-20%,X6S,0402)';
      COMPONENT_TYPE='CHIP0402';
      LEAD_LENGTH='';
      LPID='';
      DATE='20170330';
      PARENT_PART_TYPE='Q_CAP';
      PARENT_PPT='Q_CAP';
      PARENT_PPT_PART='Q_CAP_C0402-10UF,6.3V,20%,X6S,CH6101MEB01';
  end_body;
end_primitive;
primitive 'Q_CAP_C0402-10UF,6.3V,20%,X6S,B';
  pin
    'A':
      PIN_NUMBER='(1)';
      PINUSE='UNSPEC';
      NO_LOAD_CHECK='BOTH';
      NO_IO_CHECK='BOTH';
      ALLOW_CONNECT='TRUE';
      PIN_GROUP='1';
    'B':
      PIN_NUMBER='(2)';
      PINUSE='UNSPEC';
      NO_LOAD_CHECK='BOTH';
      NO_IO_CHECK='BOTH';
      ALLOW_CONNECT='TRUE';
      PIN_GROUP='1';
  end_pin;
  body
      PART_NAME='Q_CAP';
      PHYS_DES_PREFIX='C';
      STANDARD='';
      LIFECYCLE='';
      ASS_PART='';
      JEDEC_TYPE='C0402';
      ALT_SYMBOLS='(C0402_OCTAGONXA,C0402-0201)';
      VALUE='10UF';
      RATED_VOLTAGE='6.3V';
      TOL='20%';
      CLASS='DISCRETE';
      DESCRIPTION='CAP CHIP 10UF 6.3V(+-20%,X6S,0402)MUR';
      COMPONENT_TYPE='CHIP0402';
      LEAD_LENGTH='';
      LPID='';
      DATE='20160111';
      PARENT_PART_TYPE='Q_CAP';
      PARENT_PPT='Q_CAP';
      PARENT_PPT_PART='Q_CAP_C0402-10UF,6.3V,20%,X6S,CH6101MEB03';
  end_body;
end_primitive;
primitive 'Q_CAP_C0402-12PF,50V,5%,EMPTY,A';
  pin
    'A':
      PIN_NUMBER='(1)';
      PINUSE='UNSPEC';
      NO_LOAD_CHECK='BOTH';
      NO_IO_CHECK='BOTH';
      ALLOW_CONNECT='TRUE';
      PIN_GROUP='1';
    'B':
      PIN_NUMBER='(2)';
      PINUSE='UNSPEC';
      NO_LOAD_CHECK='BOTH';
      NO_IO_CHECK='BOTH';
      ALLOW_CONNECT='TRUE';
      PIN_GROUP='1';
  end_pin;
  body
      PART_NAME='Q_CAP';
      PHYS_DES_PREFIX='C';
      STANDARD='';
      LIFECYCLE='';
      ASS_PART='';
      JEDEC_TYPE='C0402';
      ALT_SYMBOLS='(C0402-0201)';
      VALUE='NA';
      RATED_VOLTAGE='50V';
      TOL='5%';
      CLASS='IO';
      DESCRIPTION='CAP CHIP 12P 50V(+-5%.C0G.0402)';
      COMPONENT_TYPE='CHIP0402';
      LEAD_LENGTH='';
      LPID='';
      DATE='20130703';
      PARENT_PART_TYPE='Q_CAP';
      PARENT_PPT='Q_CAP';
      PARENT_PPT_PART='Q_CAP_C0402-12PF,50V,5%,EMPTY,CH01206JB05';
  end_body;
end_primitive;
primitive 'Q_CAP_C0402-1UF,16V,10%,X6S,CHA';
  pin
    'A':
      PIN_NUMBER='(1)';
      PINUSE='UNSPEC';
      NO_LOAD_CHECK='BOTH';
      NO_IO_CHECK='BOTH';
      ALLOW_CONNECT='TRUE';
      PIN_GROUP='1';
    'B':
      PIN_NUMBER='(2)';
      PINUSE='UNSPEC';
      NO_LOAD_CHECK='BOTH';
      NO_IO_CHECK='BOTH';
      ALLOW_CONNECT='TRUE';
      PIN_GROUP='1';
  end_pin;
  body
      PART_NAME='Q_CAP';
      PHYS_DES_PREFIX='C';
      STANDARD='';
      LIFECYCLE='';
      ASS_PART='';
      JEDEC_TYPE='C0402';
      ALT_SYMBOLS='(C0402_OCTAGONXA,C0402-0201)';
      VALUE='1UF';
      RATED_VOLTAGE='16V';
      TOL='10%';
      CLASS='DISCRETE';
      DESCRIPTION='CAP CHIP 1UF 16V(10%,X6S,0402)';
      COMPONENT_TYPE='CHIP0402';
      LEAD_LENGTH='';
      LPID='';
      DATE='20140828';
      PARENT_PART_TYPE='Q_CAP';
      PARENT_PPT='Q_CAP';
      PARENT_PPT_PART='Q_CAP_C0402-1UF,16V,10%,X6S,CH5103KEB01';
  end_body;
end_primitive;
primitive 'Q_CAP_C0402-1UF,25V,10%,EMPTY,A';
  pin
    'A':
      PIN_NUMBER='(1)';
      PINUSE='UNSPEC';
      NO_LOAD_CHECK='BOTH';
      NO_IO_CHECK='BOTH';
      ALLOW_CONNECT='TRUE';
      PIN_GROUP='1';
    'B':
      PIN_NUMBER='(2)';
      PINUSE='UNSPEC';
      NO_LOAD_CHECK='BOTH';
      NO_IO_CHECK='BOTH';
      ALLOW_CONNECT='TRUE';
      PIN_GROUP='1';
  end_pin;
  body
      PART_NAME='Q_CAP';
      PHYS_DES_PREFIX='C';
      STANDARD='';
      LIFECYCLE='';
      ASS_PART='';
      JEDEC_TYPE='C0402';
      ALT_SYMBOLS='(C0402_OCTAGONXA,C0402-0201)';
      VALUE='NA';
      RATED_VOLTAGE='25V';
      TOL='10%';
      CLASS='IO';
      DESCRIPTION='CAP CHIP 1UF 25V(+-10%,X6S,0402)';
      COMPONENT_TYPE='CHIP0402';
      LEAD_LENGTH='';
      LPID='';
      DATE='20140327';
      PARENT_PART_TYPE='Q_CAP';
      PARENT_PPT='Q_CAP';
      PARENT_PPT_PART='Q_CAP_C0402-1UF,25V,10%,EMPTY,CH5104KEB02';
  end_body;
end_primitive;
primitive 'Q_CAP_C0402-1UF,25V,10%,X6S,CHA';
  pin
    'A':
      PIN_NUMBER='(1)';
      PINUSE='UNSPEC';
      NO_LOAD_CHECK='BOTH';
      NO_IO_CHECK='BOTH';
      ALLOW_CONNECT='TRUE';
      PIN_GROUP='1';
    'B':
      PIN_NUMBER='(2)';
      PINUSE='UNSPEC';
      NO_LOAD_CHECK='BOTH';
      NO_IO_CHECK='BOTH';
      ALLOW_CONNECT='TRUE';
      PIN_GROUP='1';
  end_pin;
  body
      PART_NAME='Q_CAP';
      PHYS_DES_PREFIX='C';
      STANDARD='';
      LIFECYCLE='';
      ASS_PART='';
      JEDEC_TYPE='C0402';
      ALT_SYMBOLS='(C0402_OCTAGONXA,C0402-0201)';
      VALUE='1UF';
      RATED_VOLTAGE='25V';
      TOL='10%';
      CLASS='DISCRETE';
      DESCRIPTION='CAP CHIP 1UF 25V(+-10%,X6S,0402)';
      COMPONENT_TYPE='CHIP0402';
      LEAD_LENGTH='';
      LPID='';
      DATE='20140327';
      PARENT_PART_TYPE='Q_CAP';
      PARENT_PPT='Q_CAP';
      PARENT_PPT_PART='Q_CAP_C0402-1UF,25V,10%,X6S,CH5104KEB02';
  end_body;
end_primitive;
primitive 'Q_CAP_C0402-2.2UF,10V,10%,X6S,A';
  pin
    'A':
      PIN_NUMBER='(1)';
      PINUSE='UNSPEC';
      NO_LOAD_CHECK='BOTH';
      NO_IO_CHECK='BOTH';
      ALLOW_CONNECT='TRUE';
      PIN_GROUP='1';
    'B':
      PIN_NUMBER='(2)';
      PINUSE='UNSPEC';
      NO_LOAD_CHECK='BOTH';
      NO_IO_CHECK='BOTH';
      ALLOW_CONNECT='TRUE';
      PIN_GROUP='1';
  end_pin;
  body
      PART_NAME='Q_CAP';
      PHYS_DES_PREFIX='C';
      STANDARD='';
      LIFECYCLE='';
      ASS_PART='';
      JEDEC_TYPE='C0402';
      ALT_SYMBOLS='(C0402_OCTAGONXA,C0402-0201)';
      VALUE='2.2UF';
      RATED_VOLTAGE='10V';
      TOL='10%';
      CLASS='DISCRETE';
      DESCRIPTION='CAP CHIP 2.2UF 10V(+-10%,X6S,0402)';
      COMPONENT_TYPE='CHIP0402';
      LEAD_LENGTH='';
      LPID='';
      DATE='20150612';
      PARENT_PART_TYPE='Q_CAP';
      PARENT_PPT='Q_CAP';
      PARENT_PPT_PART='Q_CAP_C0402-2.2UF,10V,10%,X6S,CH5222KEB01';
  end_body;
end_primitive;
primitive 'Q_CAP_C0402-2.2UF,6.3V,20%,X6SA';
  pin
    'A':
      PIN_NUMBER='(1)';
      PINUSE='UNSPEC';
      NO_LOAD_CHECK='BOTH';
      NO_IO_CHECK='BOTH';
      ALLOW_CONNECT='TRUE';
      PIN_GROUP='1';
    'B':
      PIN_NUMBER='(2)';
      PINUSE='UNSPEC';
      NO_LOAD_CHECK='BOTH';
      NO_IO_CHECK='BOTH';
      ALLOW_CONNECT='TRUE';
      PIN_GROUP='1';
  end_pin;
  body
      PART_NAME='Q_CAP';
      PHYS_DES_PREFIX='C';
      STANDARD='';
      LIFECYCLE='';
      ASS_PART='';
      JEDEC_TYPE='C0402';
      ALT_SYMBOLS='(C0402_OCTAGONXA,C0402-0201)';
      VALUE='2.2UF';
      RATED_VOLTAGE='6.3V';
      TOL='20%';
      CLASS='DISCRETE';
      DESCRIPTION='CAP CHIP 2.2U 6.3V(+-20%,X6S,0402)';
      COMPONENT_TYPE='CHIP0402';
      LEAD_LENGTH='';
      LPID='';
      DATE='20170330';
      PARENT_PART_TYPE='Q_CAP';
      PARENT_PPT='Q_CAP';
      PARENT_PPT_PART='Q_CAP_C0402-2.2UF,6.3V,20%,X6S,CH5221MEB00';
  end_body;
end_primitive;
primitive 'Q_CAP_C0402-22UF,4V,20%,X6S,CHA';
  pin
    'A':
      PIN_NUMBER='(1)';
      PINUSE='UNSPEC';
      NO_LOAD_CHECK='BOTH';
      NO_IO_CHECK='BOTH';
      ALLOW_CONNECT='TRUE';
      PIN_GROUP='1';
    'B':
      PIN_NUMBER='(2)';
      PINUSE='UNSPEC';
      NO_LOAD_CHECK='BOTH';
      NO_IO_CHECK='BOTH';
      ALLOW_CONNECT='TRUE';
      PIN_GROUP='1';
  end_pin;
  body
      PART_NAME='Q_CAP';
      PHYS_DES_PREFIX='C';
      STANDARD='';
      LIFECYCLE='';
      ASS_PART='';
      JEDEC_TYPE='C0402_H32';
      ALT_SYMBOLS='(C0402_OCTAGONXA,C0402-0201_H32)';
      VALUE='22UF';
      RATED_VOLTAGE='4V';
      TOL='20%';
      CLASS='DISCRETE';
      DESCRIPTION='CAP CHIP 22UF 4V(+-20%,X6S,0402)MUR';
      COMPONENT_TYPE='CHIP0402';
      LEAD_LENGTH='';
      LPID='';
      DATE='20180313';
      PARENT_PART_TYPE='Q_CAP';
      PARENT_PPT='Q_CAP';
      PARENT_PPT_PART='Q_CAP_C0402-22UF,4V,20%,X6S,CH622KMEB01';
  end_body;
end_primitive;
primitive 'Q_CAP_C0402-33NF,25V,10%,EMPTYA';
  pin
    'A':
      PIN_NUMBER='(1)';
      PINUSE='UNSPEC';
      NO_LOAD_CHECK='BOTH';
      NO_IO_CHECK='BOTH';
      ALLOW_CONNECT='TRUE';
      PIN_GROUP='1';
    'B':
      PIN_NUMBER='(2)';
      PINUSE='UNSPEC';
      NO_LOAD_CHECK='BOTH';
      NO_IO_CHECK='BOTH';
      ALLOW_CONNECT='TRUE';
      PIN_GROUP='1';
  end_pin;
  body
      PART_NAME='Q_CAP';
      PHYS_DES_PREFIX='C';
      STANDARD='';
      LIFECYCLE='';
      ASS_PART='';
      JEDEC_TYPE='C0402';
      ALT_SYMBOLS='(C0402_OCTAGONXA,C0402-0201)';
      VALUE='NA';
      RATED_VOLTAGE='25V';
      TOL='10%';
      CLASS='IO';
      DESCRIPTION='CAP CHIP 33NF 25V(+-10%,X7R,0402)';
      COMPONENT_TYPE='CHIP0402';
      LEAD_LENGTH='';
      LPID='';
      DATE='20140507';
      PARENT_PART_TYPE='Q_CAP';
      PARENT_PPT='Q_CAP';
      PARENT_PPT_PART='Q_CAP_C0402-33NF,25V,10%,EMPTY,CH3334K1B00';
  end_body;
end_primitive;
primitive 'Q_CAP_C0402-3900PF,50V,10%,EMPA';
  pin
    'A':
      PIN_NUMBER='(1)';
      PINUSE='UNSPEC';
      NO_LOAD_CHECK='BOTH';
      NO_IO_CHECK='BOTH';
      ALLOW_CONNECT='TRUE';
      PIN_GROUP='1';
    'B':
      PIN_NUMBER='(2)';
      PINUSE='UNSPEC';
      NO_LOAD_CHECK='BOTH';
      NO_IO_CHECK='BOTH';
      ALLOW_CONNECT='TRUE';
      PIN_GROUP='1';
  end_pin;
  body
      PART_NAME='Q_CAP';
      PHYS_DES_PREFIX='C';
      STANDARD='';
      LIFECYCLE='';
      ASS_PART='';
      JEDEC_TYPE='C0402';
      ALT_SYMBOLS='(C0402-0201)';
      VALUE='NA';
      RATED_VOLTAGE='50V';
      TOL='10%';
      CLASS='IO';
      DESCRIPTION='CAP CHIP 3900P 50V(+-10%,X7R,0402)';
      COMPONENT_TYPE='CHIP0402';
      LEAD_LENGTH='';
      LPID='';
      DATE='20140325';
      PARENT_PART_TYPE='Q_CAP';
      PARENT_PPT='Q_CAP';
      PARENT_PPT_PART='Q_CAP_C0402-3900PF,50V,10%,EMPTY,CH23906KB14';
  end_body;
end_primitive;
primitive 'Q_CAP_C0402-39PF,50V,5%,EMPTY,A';
  pin
    'A':
      PIN_NUMBER='(1)';
      PINUSE='UNSPEC';
      NO_LOAD_CHECK='BOTH';
      NO_IO_CHECK='BOTH';
      ALLOW_CONNECT='TRUE';
      PIN_GROUP='1';
    'B':
      PIN_NUMBER='(2)';
      PINUSE='UNSPEC';
      NO_LOAD_CHECK='BOTH';
      NO_IO_CHECK='BOTH';
      ALLOW_CONNECT='TRUE';
      PIN_GROUP='1';
  end_pin;
  body
      PART_NAME='Q_CAP';
      PHYS_DES_PREFIX='C';
      STANDARD='';
      LIFECYCLE='';
      ASS_PART='';
      JEDEC_TYPE='C0402';
      ALT_SYMBOLS='(C0402-0201)';
      VALUE='NA';
      RATED_VOLTAGE='50V';
      TOL='5%';
      CLASS='IO';
      DESCRIPTION='CAP CHIP 39P 50V(+-5%,NPO,0402)MUR';
      COMPONENT_TYPE='CHIP0402';
      LEAD_LENGTH='';
      LPID='';
      DATE='20200218';
      PARENT_PART_TYPE='Q_CAP';
      PARENT_PPT='Q_CAP';
      PARENT_PPT_PART='Q_CAP_C0402-39PF,50V,5%,EMPTY,CH0396J0B04';
  end_body;
end_primitive;
primitive 'Q_CAP_C0402-560PF,50V,10%,X7R,A';
  pin
    'A':
      PIN_NUMBER='(1)';
      PINUSE='UNSPEC';
      NO_LOAD_CHECK='BOTH';
      NO_IO_CHECK='BOTH';
      ALLOW_CONNECT='TRUE';
      PIN_GROUP='1';
    'B':
      PIN_NUMBER='(2)';
      PINUSE='UNSPEC';
      NO_LOAD_CHECK='BOTH';
      NO_IO_CHECK='BOTH';
      ALLOW_CONNECT='TRUE';
      PIN_GROUP='1';
  end_pin;
  body
      PART_NAME='Q_CAP';
      PHYS_DES_PREFIX='C';
      STANDARD='';
      LIFECYCLE='';
      ASS_PART='';
      JEDEC_TYPE='C0402';
      ALT_SYMBOLS='(C0402_OCTAGONXA,C0402-0201)';
      VALUE='560PF';
      RATED_VOLTAGE='50V';
      TOL='10%';
      CLASS='DISCRETE';
      DESCRIPTION='CAP CHIP 560P 50V(+-10%,X7R,0402)';
      COMPONENT_TYPE='CHIP0402';
      LEAD_LENGTH='';
      LPID='';
      DATE='20130114';
      PARENT_PART_TYPE='Q_CAP';
      PARENT_PPT='Q_CAP';
      PARENT_PPT_PART='Q_CAP_C0402-560PF,50V,10%,X7R,CH1566K1B09';
  end_body;
end_primitive;
primitive 'Q_CAP_C0402-6800PF,50V,10%,X7RA';
  pin
    'A':
      PIN_NUMBER='(1)';
      PINUSE='UNSPEC';
      NO_LOAD_CHECK='BOTH';
      NO_IO_CHECK='BOTH';
      ALLOW_CONNECT='TRUE';
      PIN_GROUP='1';
    'B':
      PIN_NUMBER='(2)';
      PINUSE='UNSPEC';
      NO_LOAD_CHECK='BOTH';
      NO_IO_CHECK='BOTH';
      ALLOW_CONNECT='TRUE';
      PIN_GROUP='1';
  end_pin;
  body
      PART_NAME='Q_CAP';
      PHYS_DES_PREFIX='C';
      STANDARD='';
      LIFECYCLE='';
      ASS_PART='';
      JEDEC_TYPE='C0402';
      ALT_SYMBOLS='(C0402-0201)';
      VALUE='6800PF';
      RATED_VOLTAGE='50V';
      TOL='10%';
      CLASS='DISCRETE';
      DESCRIPTION='CAP CHIP 6800P 50V(+-10%,X7R,0402)';
      COMPONENT_TYPE='CHIP0402';
      LEAD_LENGTH='';
      LPID='';
      DATE='20120113';
      PARENT_PART_TYPE='Q_CAP';
      PARENT_PPT='Q_CAP';
      PARENT_PPT_PART='Q_CAP_C0402-6800PF,50V,10%,X7R,CH2686K1B01';
  end_body;
end_primitive;
primitive 'Q_CAP_C0402-680PF,50V,10%,X7R,A';
  pin
    'A':
      PIN_NUMBER='(1)';
      PINUSE='UNSPEC';
      NO_LOAD_CHECK='BOTH';
      NO_IO_CHECK='BOTH';
      ALLOW_CONNECT='TRUE';
      PIN_GROUP='1';
    'B':
      PIN_NUMBER='(2)';
      PINUSE='UNSPEC';
      NO_LOAD_CHECK='BOTH';
      NO_IO_CHECK='BOTH';
      ALLOW_CONNECT='TRUE';
      PIN_GROUP='1';
  end_pin;
  body
      PART_NAME='Q_CAP';
      PHYS_DES_PREFIX='C';
      STANDARD='';
      LIFECYCLE='';
      ASS_PART='';
      JEDEC_TYPE='C0402';
      ALT_SYMBOLS='(C0402-0201)';
      VALUE='680PF';
      RATED_VOLTAGE='50V';
      TOL='10%';
      CLASS='DISCRETE';
      DESCRIPTION='CAP CHIP 680P 50V(+-10%,X7R,0402)MUR';
      COMPONENT_TYPE='CHIP0402';
      LEAD_LENGTH='';
      LPID='';
      DATE='20220414';
      PARENT_PART_TYPE='Q_CAP';
      PARENT_PPT='Q_CAP';
      PARENT_PPT_PART='Q_CAP_C0402-680PF,50V,10%,X7R,CH1686K1B09';
  end_body;
end_primitive;
primitive 'Q_CAP_C0402-8.2PF,50V,0.1P,NP0A';
  pin
    'A':
      PIN_NUMBER='(1)';
      PINUSE='UNSPEC';
      NO_LOAD_CHECK='BOTH';
      NO_IO_CHECK='BOTH';
      ALLOW_CONNECT='TRUE';
      PIN_GROUP='1';
    'B':
      PIN_NUMBER='(2)';
      PINUSE='UNSPEC';
      NO_LOAD_CHECK='BOTH';
      NO_IO_CHECK='BOTH';
      ALLOW_CONNECT='TRUE';
      PIN_GROUP='1';
  end_pin;
  body
      PART_NAME='Q_CAP';
      PHYS_DES_PREFIX='C';
      STANDARD='';
      LIFECYCLE='';
      ASS_PART='';
      JEDEC_TYPE='C0402';
      ALT_SYMBOLS='(C0402-0201)';
      VALUE='8.2PF';
      RATED_VOLTAGE='50V';
      TOL='0.1P';
      CLASS='DISCRETE';
      DESCRIPTION='CAP CHIP 8.2P 50V (+-0.1P NP0 0402)';
      COMPONENT_TYPE='CHIP0402';
      LEAD_LENGTH='';
      LPID='';
      DATE='20140326';
      PARENT_PART_TYPE='Q_CAP';
      PARENT_PPT='Q_CAP';
      PARENT_PPT_PART='Q_CAP_C0402-8.2PF,50V,0.1P,NP0,CH-8216TB09';
  end_body;
end_primitive;
primitive 'Q_CAP_C0603-10UF,4V,20%,EMPTY,A';
  pin
    'A':
      PIN_NUMBER='(1)';
      PINUSE='UNSPEC';
      NO_LOAD_CHECK='BOTH';
      NO_IO_CHECK='BOTH';
      ALLOW_CONNECT='TRUE';
      PIN_GROUP='1';
    'B':
      PIN_NUMBER='(2)';
      PINUSE='UNSPEC';
      NO_LOAD_CHECK='BOTH';
      NO_IO_CHECK='BOTH';
      ALLOW_CONNECT='TRUE';
      PIN_GROUP='1';
  end_pin;
  body
      PART_NAME='Q_CAP';
      PHYS_DES_PREFIX='C';
      STANDARD='';
      LIFECYCLE='';
      ASS_PART='';
      JEDEC_TYPE='C0603';
      ALT_SYMBOLS='(SMC0603AW)';
      VALUE='NA';
      RATED_VOLTAGE='4V';
      TOL='20%';
      CLASS='IO';
      DESCRIPTION='CAP CHIP 10U 4V(+-20%,X6S,0603)AEC';
      COMPONENT_TYPE='CHIP0603';
      LEAD_LENGTH='';
      LPID='';
      DATE='20160104';
      PARENT_PART_TYPE='Q_CAP';
      PARENT_PPT='Q_CAP';
      PARENT_PPT_PART='Q_CAP_C0603-10UF,4V,20%,EMPTY,CH610KME907';
  end_body;
end_primitive;
primitive 'Q_CAP_C0603-10UF,6.3V,20%,X6S,A';
  pin
    'A':
      PIN_NUMBER='(1)';
      PINUSE='UNSPEC';
      NO_LOAD_CHECK='BOTH';
      NO_IO_CHECK='BOTH';
      ALLOW_CONNECT='TRUE';
      PIN_GROUP='1';
    'B':
      PIN_NUMBER='(2)';
      PINUSE='UNSPEC';
      NO_LOAD_CHECK='BOTH';
      NO_IO_CHECK='BOTH';
      ALLOW_CONNECT='TRUE';
      PIN_GROUP='1';
  end_pin;
  body
      PART_NAME='Q_CAP';
      PHYS_DES_PREFIX='C';
      STANDARD='End of Design';
      LIFECYCLE='Comp-Approve';
      ASS_PART='';
      JEDEC_TYPE='C0603';
      ALT_SYMBOLS='(SMC0603AW)';
      VALUE='10UF';
      RATED_VOLTAGE='6.3V';
      TOL='20%';
      CLASS='DISCRETE';
      DESCRIPTION='CAP CHIP 10U 6.3V(+-20%,X6S,0603)';
      COMPONENT_TYPE='CHIP0603';
      LEAD_LENGTH='';
      LPID='';
      DATE='20140415';
      PARENT_PART_TYPE='Q_CAP';
      PARENT_PPT='Q_CAP';
      PARENT_PPT_PART='Q_CAP_C0603-10UF,6.3V,20%,X6S,CH6101ME900';
  end_body;
end_primitive;
primitive 'Q_CAP_C0603-2.2UF,16V,10%,X6S,A';
  pin
    'A':
      PIN_NUMBER='(1)';
      PINUSE='UNSPEC';
      NO_LOAD_CHECK='BOTH';
      NO_IO_CHECK='BOTH';
      ALLOW_CONNECT='TRUE';
      PIN_GROUP='1';
    'B':
      PIN_NUMBER='(2)';
      PINUSE='UNSPEC';
      NO_LOAD_CHECK='BOTH';
      NO_IO_CHECK='BOTH';
      ALLOW_CONNECT='TRUE';
      PIN_GROUP='1';
  end_pin;
  body
      PART_NAME='Q_CAP';
      PHYS_DES_PREFIX='C';
      STANDARD='';
      LIFECYCLE='';
      ASS_PART='';
      JEDEC_TYPE='C0603';
      ALT_SYMBOLS='(SMC0603AW)';
      VALUE='2.2UF';
      RATED_VOLTAGE='16V';
      TOL='10%';
      CLASS='DISCRETE';
      DESCRIPTION='CAP CHIP 2.2U 16V(+-10%,X6S,0603)';
      COMPONENT_TYPE='CHIP0603';
      LEAD_LENGTH='';
      LPID='';
      DATE='20140327';
      PARENT_PART_TYPE='Q_CAP';
      PARENT_PPT='Q_CAP';
      PARENT_PPT_PART='Q_CAP_C0603-2.2UF,16V,10%,X6S,CH5223KE901';
  end_body;
end_primitive;
primitive 'Q_CAP_C0603-2.2UF,16V,20%,X7R,A';
  pin
    'A':
      PIN_NUMBER='(1)';
      PINUSE='UNSPEC';
      NO_LOAD_CHECK='BOTH';
      NO_IO_CHECK='BOTH';
      ALLOW_CONNECT='TRUE';
      PIN_GROUP='1';
    'B':
      PIN_NUMBER='(2)';
      PINUSE='UNSPEC';
      NO_LOAD_CHECK='BOTH';
      NO_IO_CHECK='BOTH';
      ALLOW_CONNECT='TRUE';
      PIN_GROUP='1';
  end_pin;
  body
      PART_NAME='Q_CAP';
      PHYS_DES_PREFIX='C';
      STANDARD='';
      LIFECYCLE='';
      ASS_PART='';
      JEDEC_TYPE='C0603_H40';
      ALT_SYMBOLS='(SMC0603AW)';
      VALUE='2.2UF';
      RATED_VOLTAGE='16V';
      TOL='20%';
      CLASS='DISCRETE';
      DESCRIPTION='CAP CHIP 2.2UF 16V(20%,X7R,0603)';
      COMPONENT_TYPE='CHIP0603';
      LEAD_LENGTH='';
      LPID='';
      DATE='20191216';
      PARENT_PART_TYPE='Q_CAP';
      PARENT_PPT='Q_CAP';
      PARENT_PPT_PART='Q_CAP_C0603-2.2UF,16V,20%,X7R,CH5223M1900';
  end_body;
end_primitive;
primitive 'Q_CAP_C0603-22UF,4V,20%,X6S,CHA';
  pin
    'A':
      PIN_NUMBER='(1)';
      PINUSE='UNSPEC';
      NO_LOAD_CHECK='BOTH';
      NO_IO_CHECK='BOTH';
      ALLOW_CONNECT='TRUE';
      PIN_GROUP='1';
    'B':
      PIN_NUMBER='(2)';
      PINUSE='UNSPEC';
      NO_LOAD_CHECK='BOTH';
      NO_IO_CHECK='BOTH';
      ALLOW_CONNECT='TRUE';
      PIN_GROUP='1';
  end_pin;
  body
      PART_NAME='Q_CAP';
      PHYS_DES_PREFIX='C';
      STANDARD='';
      LIFECYCLE='';
      ASS_PART='';
      JEDEC_TYPE='C0603';
      ALT_SYMBOLS='(SMC0603AW)';
      VALUE='22UF';
      RATED_VOLTAGE='4V';
      TOL='20%';
      CLASS='DISCRETE';
      DESCRIPTION='CAP CHIP 22UF 4V(+-20%,X6S,0603)';
      COMPONENT_TYPE='CHIP0603';
      LEAD_LENGTH='';
      LPID='';
      DATE='20130321';
      PARENT_PART_TYPE='Q_CAP';
      PARENT_PPT='Q_CAP';
      PARENT_PPT_PART='Q_CAP_C0603-22UF,4V,20%,X6S,CH622KME901';
  end_body;
end_primitive;
primitive 'Q_CAP_C0603-22UF,6.3V,20%,X6S,A';
  pin
    'A':
      PIN_NUMBER='(1)';
      PINUSE='UNSPEC';
      NO_LOAD_CHECK='BOTH';
      NO_IO_CHECK='BOTH';
      ALLOW_CONNECT='TRUE';
      PIN_GROUP='1';
    'B':
      PIN_NUMBER='(2)';
      PINUSE='UNSPEC';
      NO_LOAD_CHECK='BOTH';
      NO_IO_CHECK='BOTH';
      ALLOW_CONNECT='TRUE';
      PIN_GROUP='1';
  end_pin;
  body
      PART_NAME='Q_CAP';
      PHYS_DES_PREFIX='C';
      STANDARD='';
      LIFECYCLE='';
      ASS_PART='';
      JEDEC_TYPE='C0603';
      ALT_SYMBOLS='(SMC0603AW)';
      VALUE='22UF';
      RATED_VOLTAGE='6.3V';
      TOL='20%';
      CLASS='DISCRETE';
      DESCRIPTION='CAP CHIP 22U 6.3V(+-20%,X6S,0603)';
      COMPONENT_TYPE='CHIP0603';
      LEAD_LENGTH='';
      LPID='';
      DATE='20140327';
      PARENT_PART_TYPE='Q_CAP';
      PARENT_PPT='Q_CAP';
      PARENT_PPT_PART='Q_CAP_C0603-22UF,6.3V,20%,X6S,CH6221ME900';
  end_body;
end_primitive;
primitive 'Q_CAP_C0603-4.7UF,16V,10%,X6S,A';
  pin
    'A':
      PIN_NUMBER='(1)';
      PINUSE='UNSPEC';
      NO_LOAD_CHECK='BOTH';
      NO_IO_CHECK='BOTH';
      ALLOW_CONNECT='TRUE';
      PIN_GROUP='1';
    'B':
      PIN_NUMBER='(2)';
      PINUSE='UNSPEC';
      NO_LOAD_CHECK='BOTH';
      NO_IO_CHECK='BOTH';
      ALLOW_CONNECT='TRUE';
      PIN_GROUP='1';
  end_pin;
  body
      PART_NAME='Q_CAP';
      PHYS_DES_PREFIX='C';
      STANDARD='';
      LIFECYCLE='';
      ASS_PART='';
      JEDEC_TYPE='C0603_H40';
      ALT_SYMBOLS='(SMC0603AW)';
      VALUE='4.7UF';
      RATED_VOLTAGE='16V';
      TOL='10%';
      CLASS='DISCRETE';
      DESCRIPTION='CAP CHIP 4.7UF 16V(+-10%,X6S,0603)';
      COMPONENT_TYPE='CHIP0603';
      LEAD_LENGTH='';
      LPID='';
      DATE='20180627';
      PARENT_PART_TYPE='Q_CAP';
      PARENT_PPT='Q_CAP';
      PARENT_PPT_PART='Q_CAP_C0603-4.7UF,16V,10%,X6S,CH5473KE902';
  end_body;
end_primitive;
primitive 'Q_CAP_C0603-47UF,2.5V,20%,X6S,A';
  pin
    'A':
      PIN_NUMBER='(1)';
      PINUSE='UNSPEC';
      NO_LOAD_CHECK='BOTH';
      NO_IO_CHECK='BOTH';
      ALLOW_CONNECT='TRUE';
      PIN_GROUP='1';
    'B':
      PIN_NUMBER='(2)';
      PINUSE='UNSPEC';
      NO_LOAD_CHECK='BOTH';
      NO_IO_CHECK='BOTH';
      ALLOW_CONNECT='TRUE';
      PIN_GROUP='1';
  end_pin;
  body
      PART_NAME='Q_CAP';
      PHYS_DES_PREFIX='C';
      STANDARD='End of Design';
      LIFECYCLE='Comp-Approve';
      ASS_PART='';
      JEDEC_TYPE='C0603';
      ALT_SYMBOLS='(SMC0603AW)';
      VALUE='47UF';
      RATED_VOLTAGE='2.5V';
      TOL='20%';
      CLASS='DISCRETE';
      DESCRIPTION='CAP CHIP 47U 2.5V(+-20%,X6S,0603)MUR';
      COMPONENT_TYPE='CHIP0603';
      LEAD_LENGTH='';
      LPID='';
      DATE='20190605';
      PARENT_PART_TYPE='Q_CAP';
      PARENT_PPT='Q_CAP';
      PARENT_PPT_PART='Q_CAP_C0603-47UF,2.5V,20%,X6S,CH647LME900';
  end_body;
end_primitive;
primitive 'Q_CAP_C0805-10UF,16V,10%,EMPTYA';
  pin
    'A':
      PIN_NUMBER='(1)';
      PINUSE='UNSPEC';
      NO_LOAD_CHECK='BOTH';
      NO_IO_CHECK='BOTH';
      ALLOW_CONNECT='TRUE';
      PIN_GROUP='1';
    'B':
      PIN_NUMBER='(2)';
      PINUSE='UNSPEC';
      NO_LOAD_CHECK='BOTH';
      NO_IO_CHECK='BOTH';
      ALLOW_CONNECT='TRUE';
      PIN_GROUP='1';
  end_pin;
  body
      PART_NAME='Q_CAP';
      PHYS_DES_PREFIX='C';
      STANDARD='';
      LIFECYCLE='';
      ASS_PART='';
      JEDEC_TYPE='C0805_H57';
      ALT_SYMBOLS='(SMC0805AW)';
      VALUE='NA';
      RATED_VOLTAGE='16V';
      TOL='10%';
      CLASS='IO';
      DESCRIPTION='CAP CHIP 10UF 16V(+-10%,X6S,0805)';
      COMPONENT_TYPE='CHIP0805';
      LEAD_LENGTH='';
      LPID='';
      DATE='20180706';
      PARENT_PART_TYPE='Q_CAP';
      PARENT_PPT='Q_CAP';
      PARENT_PPT_PART='Q_CAP_C0805-10UF,16V,10%,EMPTY,CH6103KEA00';
  end_body;
end_primitive;
primitive 'Q_CAP_C0805-10UF,16V,10%,EMPTYB';
  pin
    'A':
      PIN_NUMBER='(1)';
      PINUSE='UNSPEC';
      NO_LOAD_CHECK='BOTH';
      NO_IO_CHECK='BOTH';
      ALLOW_CONNECT='TRUE';
      PIN_GROUP='1';
    'B':
      PIN_NUMBER='(2)';
      PINUSE='UNSPEC';
      NO_LOAD_CHECK='BOTH';
      NO_IO_CHECK='BOTH';
      ALLOW_CONNECT='TRUE';
      PIN_GROUP='1';
  end_pin;
  body
      PART_NAME='Q_CAP';
      PHYS_DES_PREFIX='C';
      STANDARD='';
      LIFECYCLE='';
      ASS_PART='';
      JEDEC_TYPE='C0805_H57';
      ALT_SYMBOLS='(SMC0805AW)';
      VALUE='NA';
      RATED_VOLTAGE='16V';
      TOL='10%';
      CLASS='IO';
      DESCRIPTION='CAP CHIP 10UF 16V(+-10%,X6S,0805)MUR';
      COMPONENT_TYPE='CHIP0805';
      LEAD_LENGTH='';
      LPID='';
      DATE='20181128';
      PARENT_PART_TYPE='Q_CAP';
      PARENT_PPT='Q_CAP';
      PARENT_PPT_PART='Q_CAP_C0805-10UF,16V,10%,EMPTY,CH6103KEA01';
  end_body;
end_primitive;
primitive 'Q_CAP_C0805-10UF,16V,10%,X6S,CA';
  pin
    'A':
      PIN_NUMBER='(1)';
      PINUSE='UNSPEC';
      NO_LOAD_CHECK='BOTH';
      NO_IO_CHECK='BOTH';
      ALLOW_CONNECT='TRUE';
      PIN_GROUP='1';
    'B':
      PIN_NUMBER='(2)';
      PINUSE='UNSPEC';
      NO_LOAD_CHECK='BOTH';
      NO_IO_CHECK='BOTH';
      ALLOW_CONNECT='TRUE';
      PIN_GROUP='1';
  end_pin;
  body
      PART_NAME='Q_CAP';
      PHYS_DES_PREFIX='C';
      STANDARD='';
      LIFECYCLE='';
      ASS_PART='';
      JEDEC_TYPE='C0805_H57';
      ALT_SYMBOLS='(SMC0805AW)';
      VALUE='10UF';
      RATED_VOLTAGE='16V';
      TOL='10%';
      CLASS='DISCRETE';
      DESCRIPTION='CAP CHIP 10UF 16V(+-10%,X6S,0805)';
      COMPONENT_TYPE='CHIP0805';
      LEAD_LENGTH='';
      LPID='';
      DATE='20180706';
      PARENT_PART_TYPE='Q_CAP';
      PARENT_PPT='Q_CAP';
      PARENT_PPT_PART='Q_CAP_C0805-10UF,16V,10%,X6S,CH6103KEA00';
  end_body;
end_primitive;
primitive 'Q_CAP_C0805-10UF,16V,10%,X6S,CB';
  pin
    'A':
      PIN_NUMBER='(1)';
      PINUSE='UNSPEC';
      NO_LOAD_CHECK='BOTH';
      NO_IO_CHECK='BOTH';
      ALLOW_CONNECT='TRUE';
      PIN_GROUP='1';
    'B':
      PIN_NUMBER='(2)';
      PINUSE='UNSPEC';
      NO_LOAD_CHECK='BOTH';
      NO_IO_CHECK='BOTH';
      ALLOW_CONNECT='TRUE';
      PIN_GROUP='1';
  end_pin;
  body
      PART_NAME='Q_CAP';
      PHYS_DES_PREFIX='C';
      STANDARD='';
      LIFECYCLE='';
      ASS_PART='';
      JEDEC_TYPE='C0805_H57';
      ALT_SYMBOLS='(SMC0805AW)';
      VALUE='10UF';
      RATED_VOLTAGE='16V';
      TOL='10%';
      CLASS='DISCRETE';
      DESCRIPTION='CAP CHIP 10UF 16V(+-10%,X6S,0805)MUR';
      COMPONENT_TYPE='CHIP0805';
      LEAD_LENGTH='';
      LPID='';
      DATE='20181128';
      PARENT_PART_TYPE='Q_CAP';
      PARENT_PPT='Q_CAP';
      PARENT_PPT_PART='Q_CAP_C0805-10UF,16V,10%,X6S,CH6103KEA01';
  end_body;
end_primitive;
primitive 'Q_CAP_C0805-10UF,16V,10%,X6S,CC';
  pin
    'A':
      PIN_NUMBER='(1)';
      PINUSE='UNSPEC';
      NO_LOAD_CHECK='BOTH';
      NO_IO_CHECK='BOTH';
      ALLOW_CONNECT='TRUE';
      PIN_GROUP='1';
    'B':
      PIN_NUMBER='(2)';
      PINUSE='UNSPEC';
      NO_LOAD_CHECK='BOTH';
      NO_IO_CHECK='BOTH';
      ALLOW_CONNECT='TRUE';
      PIN_GROUP='1';
  end_pin;
  body
      PART_NAME='Q_CAP';
      PHYS_DES_PREFIX='C';
      STANDARD='';
      LIFECYCLE='';
      ASS_PART='';
      JEDEC_TYPE='C0805_H57';
      ALT_SYMBOLS='(SMC0805AW)';
      VALUE='10UF';
      RATED_VOLTAGE='16V';
      TOL='10%';
      CLASS='DISCRETE';
      DESCRIPTION='CAP CHIP 10UF 16V(+-10%,X6S,0805)SAM';
      COMPONENT_TYPE='CHIP0805';
      LEAD_LENGTH='';
      LPID='';
      DATE='20220120';
      PARENT_PART_TYPE='Q_CAP';
      PARENT_PPT='Q_CAP';
      PARENT_PPT_PART='Q_CAP_C0805-10UF,16V,10%,X6S,CH6103KEA03';
  end_body;
end_primitive;
primitive 'Q_CAP_C0805-10UF,25V,10%,X6S,CA';
  pin
    'A':
      PIN_NUMBER='(1)';
      PINUSE='UNSPEC';
      NO_LOAD_CHECK='BOTH';
      NO_IO_CHECK='BOTH';
      ALLOW_CONNECT='TRUE';
      PIN_GROUP='1';
    'B':
      PIN_NUMBER='(2)';
      PINUSE='UNSPEC';
      NO_LOAD_CHECK='BOTH';
      NO_IO_CHECK='BOTH';
      ALLOW_CONNECT='TRUE';
      PIN_GROUP='1';
  end_pin;
  body
      PART_NAME='Q_CAP';
      PHYS_DES_PREFIX='C';
      STANDARD='';
      LIFECYCLE='';
      ASS_PART='';
      JEDEC_TYPE='C0805_H61';
      ALT_SYMBOLS='(SMC0805AW)';
      VALUE='10UF';
      RATED_VOLTAGE='25V';
      TOL='10%';
      CLASS='DISCRETE';
      DESCRIPTION='CAP CHIP 10U 25V(+-10%,X6S,0805,H1.25)';
      COMPONENT_TYPE='CHIP0805';
      LEAD_LENGTH='';
      LPID='';
      DATE='20140327';
      PARENT_PART_TYPE='Q_CAP';
      PARENT_PPT='Q_CAP';
      PARENT_PPT_PART='Q_CAP_C0805-10UF,25V,10%,X6S,CH6104KEA00';
  end_body;
end_primitive;
primitive 'Q_CAP_C0805-22UF,10V,20%,X6S,CA';
  pin
    'A':
      PIN_NUMBER='(1)';
      PINUSE='UNSPEC';
      NO_LOAD_CHECK='BOTH';
      NO_IO_CHECK='BOTH';
      ALLOW_CONNECT='TRUE';
      PIN_GROUP='1';
    'B':
      PIN_NUMBER='(2)';
      PINUSE='UNSPEC';
      NO_LOAD_CHECK='BOTH';
      NO_IO_CHECK='BOTH';
      ALLOW_CONNECT='TRUE';
      PIN_GROUP='1';
  end_pin;
  body
      PART_NAME='Q_CAP';
      PHYS_DES_PREFIX='C';
      STANDARD='';
      LIFECYCLE='';
      ASS_PART='';
      JEDEC_TYPE='C0805_H61';
      ALT_SYMBOLS='(SMC0805AW)';
      VALUE='22UF';
      RATED_VOLTAGE='10V';
      TOL='20%';
      CLASS='DISCRETE';
      DESCRIPTION='CAP CHIP 22U 10V(+-20%,X6S,0805)MUR';
      COMPONENT_TYPE='CHIP0805';
      LEAD_LENGTH='';
      LPID='';
      DATE='20150615';
      PARENT_PART_TYPE='Q_CAP';
      PARENT_PPT='Q_CAP';
      PARENT_PPT_PART='Q_CAP_C0805-22UF,10V,20%,X6S,CH6222MEA01';
  end_body;
end_primitive;
primitive 'Q_CAP_C0805-22UF,16V,20%,X6S,CA';
  pin
    'A':
      PIN_NUMBER='(1)';
      PINUSE='UNSPEC';
      NO_LOAD_CHECK='BOTH';
      NO_IO_CHECK='BOTH';
      ALLOW_CONNECT='TRUE';
      PIN_GROUP='1';
    'B':
      PIN_NUMBER='(2)';
      PINUSE='UNSPEC';
      NO_LOAD_CHECK='BOTH';
      NO_IO_CHECK='BOTH';
      ALLOW_CONNECT='TRUE';
      PIN_GROUP='1';
  end_pin;
  body
      PART_NAME='Q_CAP';
      PHYS_DES_PREFIX='C';
      STANDARD='';
      LIFECYCLE='';
      ASS_PART='';
      JEDEC_TYPE='C0805_H57';
      ALT_SYMBOLS='(SMC0805AW)';
      VALUE='22UF';
      RATED_VOLTAGE='16V';
      TOL='20%';
      CLASS='DISCRETE';
      DESCRIPTION='CAP CHIP 22UF 16V(+-20%,X6S,0805)MUR';
      COMPONENT_TYPE='CHIP0805';
      LEAD_LENGTH='';
      LPID='';
      DATE='20171127';
      PARENT_PART_TYPE='Q_CAP';
      PARENT_PPT='Q_CAP';
      PARENT_PPT_PART='Q_CAP_C0805-22UF,16V,20%,X6S,CH6223MEA01';
  end_body;
end_primitive;
primitive 'Q_CAP_C0805-22UF,16V,20%,X6S,CB';
  pin
    'A':
      PIN_NUMBER='(1)';
      PINUSE='UNSPEC';
      NO_LOAD_CHECK='BOTH';
      NO_IO_CHECK='BOTH';
      ALLOW_CONNECT='TRUE';
      PIN_GROUP='1';
    'B':
      PIN_NUMBER='(2)';
      PINUSE='UNSPEC';
      NO_LOAD_CHECK='BOTH';
      NO_IO_CHECK='BOTH';
      ALLOW_CONNECT='TRUE';
      PIN_GROUP='1';
  end_pin;
  body
      PART_NAME='Q_CAP';
      PHYS_DES_PREFIX='C';
      STANDARD='';
      LIFECYCLE='';
      ASS_PART='';
      JEDEC_TYPE='C0805_H57';
      ALT_SYMBOLS='(SMC0805AW)';
      VALUE='22UF';
      RATED_VOLTAGE='16V';
      TOL='20%';
      CLASS='DISCRETE';
      DESCRIPTION='CAP CHIP 22U 16V(+-20%,X6S,0805)';
      COMPONENT_TYPE='CHIP0805';
      LEAD_LENGTH='';
      LPID='';
      DATE='2016019';
      PARENT_PART_TYPE='Q_CAP';
      PARENT_PPT='Q_CAP';
      PARENT_PPT_PART='Q_CAP_C0805-22UF,16V,20%,X6S,CH6223MEA00';
  end_body;
end_primitive;
primitive 'Q_CAP_C0805-22UF,16V,20%,X6S,CC';
  pin
    'A':
      PIN_NUMBER='(1)';
      PINUSE='UNSPEC';
      NO_LOAD_CHECK='BOTH';
      NO_IO_CHECK='BOTH';
      ALLOW_CONNECT='TRUE';
      PIN_GROUP='1';
    'B':
      PIN_NUMBER='(2)';
      PINUSE='UNSPEC';
      NO_LOAD_CHECK='BOTH';
      NO_IO_CHECK='BOTH';
      ALLOW_CONNECT='TRUE';
      PIN_GROUP='1';
  end_pin;
  body
      PART_NAME='Q_CAP';
      PHYS_DES_PREFIX='C';
      STANDARD='';
      LIFECYCLE='';
      ASS_PART='';
      JEDEC_TYPE='C0805_H57';
      ALT_SYMBOLS='(SMC0805AW)';
      VALUE='22UF';
      RATED_VOLTAGE='16V';
      TOL='20%';
      CLASS='DISCRETE';
      DESCRIPTION='CAP CHIP 22U 16V(20%,X6S,0805)SAM';
      COMPONENT_TYPE='CHIP0805';
      LEAD_LENGTH='';
      LPID='';
      DATE='20190611';
      PARENT_PART_TYPE='Q_CAP';
      PARENT_PPT='Q_CAP';
      PARENT_PPT_PART='Q_CAP_C0805-22UF,16V,20%,X6S,CH6223MEA03';
  end_body;
end_primitive;
primitive 'Q_CAP_C0805-22UF,4V,20%,X6S,CHA';
  pin
    'A':
      PIN_NUMBER='(1)';
      PINUSE='UNSPEC';
      NO_LOAD_CHECK='BOTH';
      NO_IO_CHECK='BOTH';
      ALLOW_CONNECT='TRUE';
      PIN_GROUP='1';
    'B':
      PIN_NUMBER='(2)';
      PINUSE='UNSPEC';
      NO_LOAD_CHECK='BOTH';
      NO_IO_CHECK='BOTH';
      ALLOW_CONNECT='TRUE';
      PIN_GROUP='1';
  end_pin;
  body
      PART_NAME='Q_CAP';
      PHYS_DES_PREFIX='C';
      STANDARD='';
      LIFECYCLE='';
      ASS_PART='';
      JEDEC_TYPE='C0805_H61';
      ALT_SYMBOLS='(SMC0805AW)';
      VALUE='22UF';
      RATED_VOLTAGE='4V';
      TOL='20%';
      CLASS='DISCRETE';
      DESCRIPTION='CAP CHIP 22U 4V(+-20%,X6S,0805)MUR';
      COMPONENT_TYPE='CHIP0805';
      LEAD_LENGTH='';
      LPID='';
      DATE='20150615';
      PARENT_PART_TYPE='Q_CAP';
      PARENT_PPT='Q_CAP';
      PARENT_PPT_PART='Q_CAP_C0805-22UF,4V,20%,X6S,CH622KMEA03';
  end_body;
end_primitive;
primitive 'Q_CAP_C0805-47UF,4V,20%,X6S,CHA';
  pin
    'A':
      PIN_NUMBER='(1)';
      PINUSE='UNSPEC';
      NO_LOAD_CHECK='BOTH';
      NO_IO_CHECK='BOTH';
      ALLOW_CONNECT='TRUE';
      PIN_GROUP='1';
    'B':
      PIN_NUMBER='(2)';
      PINUSE='UNSPEC';
      NO_LOAD_CHECK='BOTH';
      NO_IO_CHECK='BOTH';
      ALLOW_CONNECT='TRUE';
      PIN_GROUP='1';
  end_pin;
  body
      PART_NAME='Q_CAP';
      PHYS_DES_PREFIX='C';
      STANDARD='';
      LIFECYCLE='';
      ASS_PART='';
      JEDEC_TYPE='C0805_H57';
      ALT_SYMBOLS='(SMC0805AW,C0805_H57_M)';
      VALUE='47UF';
      RATED_VOLTAGE='4V';
      TOL='20%';
      CLASS='DISCRETE';
      DESCRIPTION='CAP CHIP 47U 4V(+-20%,X6S,0805)MUR';
      COMPONENT_TYPE='CHIP0805';
      LEAD_LENGTH='';
      LPID='';
      DATE='20160616';
      PARENT_PART_TYPE='Q_CAP';
      PARENT_PPT='Q_CAP';
      PARENT_PPT_PART='Q_CAP_C0805-47UF,4V,20%,X6S,CH647KMEA04';
  end_body;
end_primitive;
primitive 'Q_CAP_C0805-47UF,6.3V,20%,X6S,A';
  pin
    'A':
      PIN_NUMBER='(1)';
      PINUSE='UNSPEC';
      NO_LOAD_CHECK='BOTH';
      NO_IO_CHECK='BOTH';
      ALLOW_CONNECT='TRUE';
      PIN_GROUP='1';
    'B':
      PIN_NUMBER='(2)';
      PINUSE='UNSPEC';
      NO_LOAD_CHECK='BOTH';
      NO_IO_CHECK='BOTH';
      ALLOW_CONNECT='TRUE';
      PIN_GROUP='1';
  end_pin;
  body
      PART_NAME='Q_CAP';
      PHYS_DES_PREFIX='C';
      STANDARD='';
      LIFECYCLE='';
      ASS_PART='';
      JEDEC_TYPE='C0805_H57';
      ALT_SYMBOLS='(C0805_BHS)';
      VALUE='47UF';
      RATED_VOLTAGE='6.3V';
      TOL='20%';
      CLASS='DISCRETE';
      DESCRIPTION='CAP CHIP 47U 6.3V(+-20%,X6S,0805)';
      COMPONENT_TYPE='CHIP0805';
      LEAD_LENGTH='';
      LPID='';
      DATE='20200930';
      PARENT_PART_TYPE='Q_CAP';
      PARENT_PPT='Q_CAP';
      PARENT_PPT_PART='Q_CAP_C0805-47UF,6.3V,20%,X6S,CH6471MEA02';
  end_body;
end_primitive;
primitive 'Q_CAP_DIFFBUS_C0201-DIFF BUS_0A';
  pin
    '1':
      PIN_NUMBER='(1)';
      BIDIRECTIONAL='TRUE';
      INPUT_LOAD='(-0.01,0.01)';
      OUTPUT_LOAD='(1.0,-1.0)';
      PINUSE='BI';
    '2':
      PIN_NUMBER='(2)';
      BIDIRECTIONAL='TRUE';
      INPUT_LOAD='(-0.01,0.01)';
      OUTPUT_LOAD='(1.0,-1.0)';
      PINUSE='BI';
  end_pin;
  body
      PART_NAME='Q_CAP_DIFFBUS';
      BODY_NAME='Q_CAP_DIFFBUS';
      PHYS_DES_PREFIX='C';
      CLASS='DISCRETE';
      STANDARD='';
      LIFECYCLE='';
      ASS_PART='';
      JEDEC_TYPE='C0201_DIFF-BUS';
      DESCRIPTION='CAP CHIP 0.22UF 6.3V(20%,X6S,0201)_DIFF BUS';
      MANUFTR='TDK';
      MANUF_PN='C0603X6S0J224MT-A';
      RD_CMPLS_LVL='EP(V1)';
      CMPLS_LVL='EP(V1)';
      DIP_SMD='';
      FROM_PJ='CJ2A-KEVIN';
      DATA='AC Coupling.msg';
      FP_ECN='DCN-all 0201 RCL part.doc';
      EE_CHECK_LIST='';
      PSL='';
      STATUS='';
      CREATOR='';
      CREATEDAY='20150629';
      PARENT_PART_TYPE='Q_CAP_DIFFBUS';
      PARENT_PPT='Q_CAP_DIFFBUS';
      PARENT_PPT_PART='Q_CAP_DIFFBUS_C0201-DIFF BUS_0.22UF,6.3V,20%,X6S,SP_CH4221MEE01';
  end_body;
end_primitive;
primitive 'Q_CAP_DIFFBUS_C0402-DIFF BUS_0A';
  pin
    '1':
      PIN_NUMBER='(1)';
      BIDIRECTIONAL='TRUE';
      INPUT_LOAD='(-0.01,0.01)';
      OUTPUT_LOAD='(1.0,-1.0)';
      PINUSE='BI';
    '2':
      PIN_NUMBER='(2)';
      BIDIRECTIONAL='TRUE';
      INPUT_LOAD='(-0.01,0.01)';
      OUTPUT_LOAD='(1.0,-1.0)';
      PINUSE='BI';
  end_pin;
  body
      PART_NAME='Q_CAP_DIFFBUS';
      BODY_NAME='Q_CAP_DIFFBUS';
      PHYS_DES_PREFIX='C';
      CLASS='DISCRETE';
      STANDARD='End of Design';
      LIFECYCLE='Comp-Approve';
      ASS_PART='';
      JEDEC_TYPE='C0402_DIFF-BUS';
      DESCRIPTION='CAP CHIP 0.33UF 6.3V(10%,X6S,0402)_FOR DIFF BUS';
      MANUFTR='MUR';
      MANUF_PN='GRM155C80J334K';
      RD_CMPLS_LVL='EP(V1)';
      CMPLS_LVL='EP(V1)';
      DIP_SMD='';
      FROM_PJ='S5R-ROGER';
      DATA='';
      FP_ECN='';
      EE_CHECK_LIST='';
      PSL='';
      STATUS='';
      CREATOR='';
      CREATEDAY='20180504';
      PARENT_PART_TYPE='Q_CAP_DIFFBUS';
      PARENT_PPT='Q_CAP_DIFFBUS';
      PARENT_PPT_PART='Q_CAP_DIFFBUS_C0402-DIFF BUS_0.33UF,6.3V,10%,X6S,SP_CH4331KEB01';
  end_body;
end_primitive;
primitive 'Q_CRYSTAL_SMLF-32.768KHZ,IC,BGA';
  pin
    '1':
      PIN_NUMBER='(1)';
      INPUT_LOAD='(-0.01,0.01)';
      OUTPUT_LOAD='(1.0,-1.0)';
      BIDIRECTIONAL='TRUE';
      PINUSE='BI';
    '2':
      PIN_NUMBER='(2)';
      INPUT_LOAD='(-0.01,0.01)';
      OUTPUT_LOAD='(1.0,-1.0)';
      BIDIRECTIONAL='TRUE';
      PINUSE='BI';
  end_pin;
  body
      CLASS='IC';
      PART_NAME='Q_CRYSTAL';
      PHYS_DES_PREFIX='Y';
      STANDARD='End of Design';
      LIFECYCLE='Comp-Approve';
      JEDEC_TYPE='X_2S_XTL721';
      DESCRIPTION='CRYSTAL SMD 32.768KHZ(+-20PPM,12.5PF)';
      COMPONENT_TYPE='SMTOTHER';
      LEAD_LENGTH='';
      DAY='20141103';
      PARENT_PART_TYPE='Q_CRYSTAL';
      PARENT_PPT='Q_CRYSTAL';
      PARENT_PPT_PART='Q_CRYSTAL_SMLF-32.768KHZ,IC,BG632768012';
  end_body;
end_primitive;
primitive 'Q_DIODE_SMLF-SDMK0340L-7-F,IC,A';
  pin
    '1':
      PIN_NUMBER='(1)';
      INPUT_LOAD='(-0.01,0.01)';
      OUTPUT_LOAD='(1.0,-1.0)';
      BIDIRECTIONAL='TRUE';
      PINUSE='BI';
    '2':
      PIN_NUMBER='(2)';
      INPUT_LOAD='(-0.01,0.01)';
      OUTPUT_LOAD='(1.0,-1.0)';
      BIDIRECTIONAL='TRUE';
      PINUSE='BI';
  end_pin;
  body
      CLASS='IC';
      PART_NAME='Q_DIODE';
      PHYS_DES_PREFIX='D';
      STANDARD='';
      LIFECYCLE='';
      JEDEC_TYPE='SOD323XB';
      DESCRIPTION='DIODE SMD SDMK0340L-7-F(40V,30MA)';
      COMPONENT_TYPE='SMALLSMT';
      LEAD_LENGTH='';
      LPID='';
      DAY='20101005';
      PARENT_PART_TYPE='Q_DIODE';
      PARENT_PPT='Q_DIODE';
      PARENT_PPT_PART='Q_DIODE_SMLF-SDMK0340L-7-F,IC,BC000340033';
  end_body;
end_primitive;
primitive 'Q_FUSE_SMLF-20A/125V,IC,DKK00XA';
  pin
    '1':
      PIN_NUMBER='(1)';
      INPUT_LOAD='(-0.01,0.01)';
      OUTPUT_LOAD='(1.0,-1.0)';
      BIDIRECTIONAL='TRUE';
      PINUSE='BI';
    '2':
      PIN_NUMBER='(2)';
      INPUT_LOAD='(-0.01,0.01)';
      OUTPUT_LOAD='(1.0,-1.0)';
      BIDIRECTIONAL='TRUE';
      PINUSE='BI';
  end_pin;
  body
      CLASS='IC';
      PART_NAME='Q_FUSE';
      PHYS_DES_PREFIX='FS';
      STANDARD='';
      LIFECYCLE='';
      JEDEC_TYPE='F4012';
      DESCRIPTION='FUSE SMD 20A/125V(FAST,UL/CSA)';
      COMPONENT_TYPE='CHIP';
      LEAD_LENGTH='';
      LPID='';
      DAY='20211207';
      PARENT_PART_TYPE='Q_FUSE';
      PARENT_PPT='Q_FUSE';
      PARENT_PPT_PART='Q_FUSE_SMLF-20A/125V,IC,DKK00XFU000';
  end_body;
end_primitive;
primitive 'Q_INDUCTOR4P_14-150NH,SMLF,INDA';
  pin
    '2':
      PIN_NUMBER='(2)';
      BIDIRECTIONAL='TRUE';
      INPUT_LOAD='(-0.01,0.01)';
      OUTPUT_LOAD='(1.0,-1.0)';
      PINUSE='BI';
    '3':
      PIN_NUMBER='(3)';
      BIDIRECTIONAL='TRUE';
      INPUT_LOAD='(-0.01,0.01)';
      OUTPUT_LOAD='(1.0,-1.0)';
      PINUSE='BI';
    '4':
      PIN_NUMBER='(4)';
      BIDIRECTIONAL='TRUE';
      INPUT_LOAD='(-0.01,0.01)';
      OUTPUT_LOAD='(1.0,-1.0)';
      PINUSE='BI';
    '1':
      PIN_NUMBER='(1)';
      BIDIRECTIONAL='TRUE';
      INPUT_LOAD='(-0.01,0.01)';
      OUTPUT_LOAD='(1.0,-1.0)';
      PINUSE='BI';
  end_pin;
  body
      PART_NAME='Q_INDUCTOR4P_14';
      BODY_NAME='Q_INDUCTOR4P_14';
      PHYS_DES_PREFIX='L';
      CLASS='DISCRETE';
      STANDARD='End of Design';
      LIFECYCLE='Comp-Approve';
      JEDEC_TYPE='L_TLM117513Q-151QL_11X7-5XA';
      CURRENT='82A';
      DESCRIPTION='IND SMD 150NH 15% 82A(PGL6303.151HLT)';
      MANUFTR='PLE';
      MANUF_PN='PGL6303.151HLT';
      RD_CMPLS_LVL='EP(V1)';
      CMPLS_LVL='';
      DIP_SMD='';
      FROM_PJ='S6X-KIMI';
      DATA='PLE_PGL6303.151HLT.pdf';
      FP_ECN='';
      EE_CHECK_LIST='';
      STATUS='';
      PREFERENCE='';
      NOT_INSERT='';
      DAY='20201026';
      PARENT_PART_TYPE='Q_INDUCTOR4P_14';
      PARENT_PPT='Q_INDUCTOR4P_14';
      PARENT_PPT_PART='Q_INDUCTOR4P_14-150NH,SMLF,IND,CV+15^0TZ04';
  end_body;
end_primitive;
primitive 'Q_INDUCTOR_SMLF-0.68UH,IND,CV+A';
  pin
    '2':
      PIN_NUMBER='(2)';
      BIDIRECTIONAL='TRUE';
      INPUT_LOAD='(-0.01,0.01)';
      OUTPUT_LOAD='(1.0,-1.0)';
      PINUSE='BI';
    '1':
      PIN_NUMBER='(1)';
      BIDIRECTIONAL='TRUE';
      INPUT_LOAD='(-0.01,0.01)';
      OUTPUT_LOAD='(1.0,-1.0)';
      PINUSE='BI';
  end_pin;
  body
      PART_NAME='Q_INDUCTOR';
      BODY_NAME='Q_INDUCTOR';
      PHYS_DES_PREFIX='L';
      CLASS='DISCRETE';
      STANDARD='';
      LIFECYCLE='';
      JEDEC_TYPE='L_PCMC063T';
      VALUE='0.68UH';
      DESCRIPTION='IND SMD 0.68U +-20%,15.5A PCMC063T-R68MN';
      COMPONENT_TYPE='CHIP';
      LEAD_LENGTH='';
      LPID='';
      DAY='20110221';
      PARENT_PART_TYPE='Q_INDUCTOR';
      PARENT_PPT='Q_INDUCTOR';
      PARENT_PPT_PART='Q_INDUCTOR_SMLF-0.68UH,IND,CV+68F5MZ05';
  end_body;
end_primitive;
primitive 'Q_INDUCTOR_SMLF-1.5UH/53A,IND,A';
  pin
    '2':
      PIN_NUMBER='(2)';
      BIDIRECTIONAL='TRUE';
      INPUT_LOAD='(-0.01,0.01)';
      OUTPUT_LOAD='(1.0,-1.0)';
      PINUSE='BI';
    '1':
      PIN_NUMBER='(1)';
      BIDIRECTIONAL='TRUE';
      INPUT_LOAD='(-0.01,0.01)';
      OUTPUT_LOAD='(1.0,-1.0)';
      PINUSE='BI';
  end_pin;
  body
      PART_NAME='Q_INDUCTOR';
      BODY_NAME='Q_INDUCTOR';
      PHYS_DES_PREFIX='L';
      CLASS='DISCRETE';
      STANDARD='';
      LIFECYCLE='';
      JEDEC_TYPE='L_EM-15AM17VG1-QS_14-3X12-9';
      VALUE='1.5UH/53A';
      DESCRIPTION='IND SMD 1.5UH 20% 53A(EM-15AM17VG1-QS)';
      COMPONENT_TYPE='CHIP';
      LEAD_LENGTH='';
      LPID='';
      DAY='20201030';
      PARENT_PART_TYPE='Q_INDUCTOR';
      PARENT_PPT='Q_INDUCTOR';
      PARENT_PPT_PART='Q_INDUCTOR_SMLF-1.5UH/53A,IND,CV-15^0MZ02';
  end_body;
end_primitive;
primitive 'Q_INDUCTOR_SMLF-100NH/16A,IND,A';
  pin
    '2':
      PIN_NUMBER='(2)';
      BIDIRECTIONAL='TRUE';
      INPUT_LOAD='(-0.01,0.01)';
      OUTPUT_LOAD='(1.0,-1.0)';
      PINUSE='BI';
    '1':
      PIN_NUMBER='(1)';
      BIDIRECTIONAL='TRUE';
      INPUT_LOAD='(-0.01,0.01)';
      OUTPUT_LOAD='(1.0,-1.0)';
      PINUSE='BI';
  end_pin;
  body
      PART_NAME='Q_INDUCTOR';
      BODY_NAME='Q_INDUCTOR';
      PHYS_DES_PREFIX='L';
      CLASS='DISCRETE';
      STANDARD='';
      LIFECYCLE='';
      JEDEC_TYPE='L_HCBS4545_4-5X4-5';
      VALUE='100NH/16A';
      DESCRIPTION='IND SMD 100NH 20% 16A(HCBS4545-101)';
      COMPONENT_TYPE='CHIP';
      LEAD_LENGTH='';
      LPID='';
      DAY='20150715';
      PARENT_PART_TYPE='Q_INDUCTOR';
      PARENT_PPT='Q_INDUCTOR';
      PARENT_PPT_PART='Q_INDUCTOR_SMLF-100NH/16A,IND,CV+10G0MZ04';
  end_body;
end_primitive;
primitive 'Q_INDUCTOR_SMLF-120NH/69A,IND,A';
  pin
    '2':
      PIN_NUMBER='(2)';
      BIDIRECTIONAL='TRUE';
      INPUT_LOAD='(-0.01,0.01)';
      OUTPUT_LOAD='(1.0,-1.0)';
      PINUSE='BI';
    '1':
      PIN_NUMBER='(1)';
      BIDIRECTIONAL='TRUE';
      INPUT_LOAD='(-0.01,0.01)';
      OUTPUT_LOAD='(1.0,-1.0)';
      PINUSE='BI';
  end_pin;
  body
      PART_NAME='Q_INDUCTOR';
      BODY_NAME='Q_INDUCTOR';
      PHYS_DES_PREFIX='L';
      CLASS='DISCRETE';
      STANDARD='';
      LIFECYCLE='';
      JEDEC_TYPE='L_VLBU6565100T-R12L-1_6-5X6-5';
      VALUE='120NH/69A';
      DESCRIPTION='IND SMD 120NH 15% 69A(PGL6312.121AHLT)';
      COMPONENT_TYPE='CHIP';
      LEAD_LENGTH='';
      LPID='';
      DAY='20201109';
      PARENT_PART_TYPE='Q_INDUCTOR';
      PARENT_PPT='Q_INDUCTOR';
      PARENT_PPT_PART='Q_INDUCTOR_SMLF-120NH/69A,IND,CV+12^0EZ03';
  end_body;
end_primitive;
primitive 'Q_INDUCTOR_SMLF-130NH/106A,INDA';
  pin
    '2':
      PIN_NUMBER='(2)';
      BIDIRECTIONAL='TRUE';
      INPUT_LOAD='(-0.01,0.01)';
      OUTPUT_LOAD='(1.0,-1.0)';
      PINUSE='BI';
    '1':
      PIN_NUMBER='(1)';
      BIDIRECTIONAL='TRUE';
      INPUT_LOAD='(-0.01,0.01)';
      OUTPUT_LOAD='(1.0,-1.0)';
      PINUSE='BI';
  end_pin;
  body
      PART_NAME='Q_INDUCTOR';
      BODY_NAME='Q_INDUCTOR';
      PHYS_DES_PREFIX='L';
      CLASS='DISCRETE';
      STANDARD='End of Design';
      LIFECYCLE='Comp-Approve';
      JEDEC_TYPE='L_HCME107512-131_10X7-5';
      VALUE='130NH/106A';
      DESCRIPTION='IND SMD 130NH 10% 106A(PG2323.131HLT)';
      COMPONENT_TYPE='CHIP';
      LEAD_LENGTH='';
      LPID='';
      DAY='20200608';
      PARENT_PART_TYPE='Q_INDUCTOR';
      PARENT_PPT='Q_INDUCTOR';
      PARENT_PPT_PART='Q_INDUCTOR_SMLF-130NH/106A,IND,CV+13^0KZ11';
  end_body;
end_primitive;
primitive 'Q_INDUCTOR_SMLF-2.2UH,IND,CV-2A';
  pin
    '2':
      PIN_NUMBER='(2)';
      BIDIRECTIONAL='TRUE';
      INPUT_LOAD='(-0.01,0.01)';
      OUTPUT_LOAD='(1.0,-1.0)';
      PINUSE='BI';
    '1':
      PIN_NUMBER='(1)';
      BIDIRECTIONAL='TRUE';
      INPUT_LOAD='(-0.01,0.01)';
      OUTPUT_LOAD='(1.0,-1.0)';
      PINUSE='BI';
  end_pin;
  body
      PART_NAME='Q_INDUCTOR';
      BODY_NAME='Q_INDUCTOR';
      PHYS_DES_PREFIX='L';
      CLASS='DISCRETE';
      STANDARD='';
      LIFECYCLE='';
      JEDEC_TYPE='L_PCMC063T';
      VALUE='2.2UH';
      DESCRIPTION='IND SMD 2.2UH +-20% 8A(PCMC063T-2R2MN)';
      COMPONENT_TYPE='CHIP';
      LEAD_LENGTH='';
      LPID='';
      DAY='20110221';
      PARENT_PART_TYPE='Q_INDUCTOR';
      PARENT_PPT='Q_INDUCTOR';
      PARENT_PPT_PART='Q_INDUCTOR_SMLF-2.2UH,IND,CV-2280MZ15';
  end_body;
end_primitive;
primitive 'Q_INDUCTOR_SMLF-300NH/33A,IND,A';
  pin
    '2':
      PIN_NUMBER='(2)';
      BIDIRECTIONAL='TRUE';
      INPUT_LOAD='(-0.01,0.01)';
      OUTPUT_LOAD='(1.0,-1.0)';
      PINUSE='BI';
    '1':
      PIN_NUMBER='(1)';
      BIDIRECTIONAL='TRUE';
      INPUT_LOAD='(-0.01,0.01)';
      OUTPUT_LOAD='(1.0,-1.0)';
      PINUSE='BI';
  end_pin;
  body
      PART_NAME='Q_INDUCTOR';
      BODY_NAME='Q_INDUCTOR';
      PHYS_DES_PREFIX='L';
      CLASS='DISCRETE';
      STANDARD='';
      LIFECYCLE='';
      JEDEC_TYPE='L_AF13A-120K_9-6X6-4';
      VALUE='300NH/33A';
      DESCRIPTION='IND SMD 300NH 10% 33A(PG1712.301AHLT)';
      COMPONENT_TYPE='CHIP';
      LEAD_LENGTH='';
      LPID='';
      DAY='20200703';
      PARENT_PART_TYPE='Q_INDUCTOR';
      PARENT_PPT='Q_INDUCTOR';
      PARENT_PPT_PART='Q_INDUCTOR_SMLF-300NH/33A,IND,CV+30Y0KZ05';
  end_body;
end_primitive;
primitive 'Q_INDUCTOR_SMLF-4.7UH,IND,CV-4A';
  pin
    '2':
      PIN_NUMBER='(2)';
      BIDIRECTIONAL='TRUE';
      INPUT_LOAD='(-0.01,0.01)';
      OUTPUT_LOAD='(1.0,-1.0)';
      PINUSE='BI';
    '1':
      PIN_NUMBER='(1)';
      BIDIRECTIONAL='TRUE';
      INPUT_LOAD='(-0.01,0.01)';
      OUTPUT_LOAD='(1.0,-1.0)';
      PINUSE='BI';
  end_pin;
  body
      PART_NAME='Q_INDUCTOR';
      BODY_NAME='Q_INDUCTOR';
      PHYS_DES_PREFIX='L';
      CLASS='DISCRETE';
      STANDARD='';
      LIFECYCLE='';
      JEDEC_TYPE='L_PCMB104EXB';
      VALUE='4.7UH';
      DESCRIPTION='IND SMD 4.7UH +-20% 10A(PCMB104E-4R7MS)';
      COMPONENT_TYPE='CHIP';
      LEAD_LENGTH='';
      LPID='';
      DAY='20110221';
      PARENT_PART_TYPE='Q_INDUCTOR';
      PARENT_PPT='Q_INDUCTOR';
      PARENT_PPT_PART='Q_INDUCTOR_SMLF-4.7UH,IND,CV-47A0MZ10';
  end_body;
end_primitive;
primitive 'Q_INDUCTOR_SMLF-4.7UH,IND,CV-4B';
  pin
    '2':
      PIN_NUMBER='(2)';
      BIDIRECTIONAL='TRUE';
      INPUT_LOAD='(-0.01,0.01)';
      OUTPUT_LOAD='(1.0,-1.0)';
      PINUSE='BI';
    '1':
      PIN_NUMBER='(1)';
      BIDIRECTIONAL='TRUE';
      INPUT_LOAD='(-0.01,0.01)';
      OUTPUT_LOAD='(1.0,-1.0)';
      PINUSE='BI';
  end_pin;
  body
      PART_NAME='Q_INDUCTOR';
      BODY_NAME='Q_INDUCTOR';
      PHYS_DES_PREFIX='L';
      CLASS='DISCRETE';
      STANDARD='';
      LIFECYCLE='';
      JEDEC_TYPE='L_PCMC063T';
      VALUE='4.7UH';
      DESCRIPTION='IND SMD 4.7U20%5.5A(PCMC063T-4R7MN)';
      COMPONENT_TYPE='CHIP';
      LEAD_LENGTH='';
      LPID='';
      DAY='20110221';
      PARENT_PART_TYPE='Q_INDUCTOR';
      PARENT_PPT='Q_INDUCTOR';
      PARENT_PPT_PART='Q_INDUCTOR_SMLF-4.7UH,IND,CV-4755MZ12';
  end_body;
end_primitive;
primitive 'Q_INDUCTOR_SMLF-50NH/148A,IND,A';
  pin
    '2':
      PIN_NUMBER='(2)';
      BIDIRECTIONAL='TRUE';
      INPUT_LOAD='(-0.01,0.01)';
      OUTPUT_LOAD='(1.0,-1.0)';
      PINUSE='BI';
    '1':
      PIN_NUMBER='(1)';
      BIDIRECTIONAL='TRUE';
      INPUT_LOAD='(-0.01,0.01)';
      OUTPUT_LOAD='(1.0,-1.0)';
      PINUSE='BI';
  end_pin;
  body
      PART_NAME='Q_INDUCTOR';
      BODY_NAME='Q_INDUCTOR';
      PHYS_DES_PREFIX='L';
      CLASS='DISCRETE';
      STANDARD='End of Design';
      LIFECYCLE='Comp-Approve';
      JEDEC_TYPE='L_HCBS1080-500QL_10X8-3';
      VALUE='50NH/148A';
      DESCRIPTION='IND SMD 50NH 15% 148A(PGL6189.500HLT)';
      COMPONENT_TYPE='CHIP';
      LEAD_LENGTH='';
      LPID='';
      DAY='20200620';
      PARENT_PART_TYPE='Q_INDUCTOR';
      PARENT_PPT='Q_INDUCTOR';
      PARENT_PPT_PART='Q_INDUCTOR_SMLF-50NH/148A,IND,CVA50^0EZ01';
  end_body;
end_primitive;
primitive 'Q_INDUCTOR_SMLF-BLM15PX121SN1DA';
  pin
    '2':
      PIN_NUMBER='(2)';
      BIDIRECTIONAL='TRUE';
      INPUT_LOAD='(-0.01,0.01)';
      OUTPUT_LOAD='(1.0,-1.0)';
      PINUSE='BI';
    '1':
      PIN_NUMBER='(1)';
      BIDIRECTIONAL='TRUE';
      INPUT_LOAD='(-0.01,0.01)';
      OUTPUT_LOAD='(1.0,-1.0)';
      PINUSE='BI';
  end_pin;
  body
      PART_NAME='Q_INDUCTOR';
      BODY_NAME='Q_INDUCTOR';
      PHYS_DES_PREFIX='L';
      CLASS='IO';
      STANDARD='';
      LIFECYCLE='';
      JEDEC_TYPE='L0402';
      VALUE='NA';
      DESCRIPTION='EMI FILTER BLM15PX121SN1D(120,2A)';
      COMPONENT_TYPE='CHIP';
      LEAD_LENGTH='';
      LPID='';
      DAY='20160425';
      PARENT_PART_TYPE='Q_INDUCTOR';
      PARENT_PPT='Q_INDUCTOR';
      PARENT_PPT_PART='Q_INDUCTOR_SMLF-BLM15PX121SN1D/2A,EMPTY,CX5PX121001';
  end_body;
end_primitive;
primitive 'Q_INDUCTOR_SMLF-BLM15PX121SN1DB';
  pin
    '2':
      PIN_NUMBER='(2)';
      BIDIRECTIONAL='TRUE';
      INPUT_LOAD='(-0.01,0.01)';
      OUTPUT_LOAD='(1.0,-1.0)';
      PINUSE='BI';
    '1':
      PIN_NUMBER='(1)';
      BIDIRECTIONAL='TRUE';
      INPUT_LOAD='(-0.01,0.01)';
      OUTPUT_LOAD='(1.0,-1.0)';
      PINUSE='BI';
  end_pin;
  body
      PART_NAME='Q_INDUCTOR';
      BODY_NAME='Q_INDUCTOR';
      PHYS_DES_PREFIX='L';
      CLASS='DISCRETE';
      STANDARD='';
      LIFECYCLE='';
      JEDEC_TYPE='L0402';
      VALUE='BLM15PX121SN1D/2A';
      DESCRIPTION='EMI FILTER BLM15PX121SN1D(120,2A)';
      COMPONENT_TYPE='CHIP';
      LEAD_LENGTH='';
      LPID='';
      DAY='20160425';
      PARENT_PART_TYPE='Q_INDUCTOR';
      PARENT_PPT='Q_INDUCTOR';
      PARENT_PPT_PART='Q_INDUCTOR_SMLF-BLM15PX121SN1D/2A,IND,CX5PX121001';
  end_body;
end_primitive;
primitive 'Q_INDUCTOR_SMLF-BLM18PG121SN1DA';
  pin
    '2':
      PIN_NUMBER='(2)';
      BIDIRECTIONAL='TRUE';
      INPUT_LOAD='(-0.01,0.01)';
      OUTPUT_LOAD='(1.0,-1.0)';
      PINUSE='BI';
    '1':
      PIN_NUMBER='(1)';
      BIDIRECTIONAL='TRUE';
      INPUT_LOAD='(-0.01,0.01)';
      OUTPUT_LOAD='(1.0,-1.0)';
      PINUSE='BI';
  end_pin;
  body
      PART_NAME='Q_INDUCTOR';
      BODY_NAME='Q_INDUCTOR';
      PHYS_DES_PREFIX='L';
      CLASS='IO';
      STANDARD='';
      LIFECYCLE='';
      JEDEC_TYPE='L0603';
      VALUE='NA';
      DESCRIPTION='EMI FILTER BLM18PG121SN(120,2000MA)';
      COMPONENT_TYPE='CHIP';
      LEAD_LENGTH='';
      LPID='';
      DAY='20140812';
      PARENT_PART_TYPE='Q_INDUCTOR';
      PARENT_PPT='Q_INDUCTOR';
      PARENT_PPT_PART='Q_INDUCTOR_SMLF-BLM18PG121SN1D/2000MA,EMPTY,CX8PG121009';
  end_body;
end_primitive;
primitive 'Q_INDUCTOR_SMLF-BLM18PG300SN1DA';
  pin
    '2':
      PIN_NUMBER='(2)';
      BIDIRECTIONAL='TRUE';
      INPUT_LOAD='(-0.01,0.01)';
      OUTPUT_LOAD='(1.0,-1.0)';
      PINUSE='BI';
    '1':
      PIN_NUMBER='(1)';
      BIDIRECTIONAL='TRUE';
      INPUT_LOAD='(-0.01,0.01)';
      OUTPUT_LOAD='(1.0,-1.0)';
      PINUSE='BI';
  end_pin;
  body
      PART_NAME='Q_INDUCTOR';
      BODY_NAME='Q_INDUCTOR';
      PHYS_DES_PREFIX='L';
      CLASS='IO';
      STANDARD='';
      LIFECYCLE='';
      JEDEC_TYPE='L0603';
      VALUE='NA';
      DESCRIPTION='EMI FILTER SBK160808T-100Y-N(10,500MA)';
      COMPONENT_TYPE='CHIP';
      LEAD_LENGTH='';
      LPID='';
      DAY='';
      PARENT_PART_TYPE='Q_INDUCTOR';
      PARENT_PPT='Q_INDUCTOR';
      PARENT_PPT_PART='Q_INDUCTOR_SMLF-BLM18PG300SN1D ,EMPTY,TMP_QCX8PG300001';
  end_body;
end_primitive;
primitive 'Q_INDUCTOR_SMLF-BLM18PG300SN1DB';
  pin
    '2':
      PIN_NUMBER='(2)';
      BIDIRECTIONAL='TRUE';
      INPUT_LOAD='(-0.01,0.01)';
      OUTPUT_LOAD='(1.0,-1.0)';
      PINUSE='BI';
    '1':
      PIN_NUMBER='(1)';
      BIDIRECTIONAL='TRUE';
      INPUT_LOAD='(-0.01,0.01)';
      OUTPUT_LOAD='(1.0,-1.0)';
      PINUSE='BI';
  end_pin;
  body
      PART_NAME='Q_INDUCTOR';
      BODY_NAME='Q_INDUCTOR';
      PHYS_DES_PREFIX='L';
      CLASS='DISCRETE';
      STANDARD='';
      LIFECYCLE='';
      JEDEC_TYPE='L0603';
      VALUE='BLM18PG300SN1D ';
      DESCRIPTION='EMI FILTER SBK160808T-100Y-N(10,500MA)';
      COMPONENT_TYPE='CHIP';
      LEAD_LENGTH='';
      LPID='';
      DAY='';
      PARENT_PART_TYPE='Q_INDUCTOR';
      PARENT_PPT='Q_INDUCTOR';
      PARENT_PPT_PART='Q_INDUCTOR_SMLF-BLM18PG300SN1D ,IND,TMP_QCX8PG300001';
  end_body;
end_primitive;
primitive 'Q_INDUCTOR_SMLF-BLM18SG331TN1DA';
  pin
    '2':
      PIN_NUMBER='(2)';
      BIDIRECTIONAL='TRUE';
      INPUT_LOAD='(-0.01,0.01)';
      OUTPUT_LOAD='(1.0,-1.0)';
      PINUSE='BI';
    '1':
      PIN_NUMBER='(1)';
      BIDIRECTIONAL='TRUE';
      INPUT_LOAD='(-0.01,0.01)';
      OUTPUT_LOAD='(1.0,-1.0)';
      PINUSE='BI';
  end_pin;
  body
      PART_NAME='Q_INDUCTOR';
      BODY_NAME='Q_INDUCTOR';
      PHYS_DES_PREFIX='L';
      CLASS='DISCRETE';
      STANDARD='End of Design';
      LIFECYCLE='Comp-Approve';
      JEDEC_TYPE='L0603';
      VALUE='BLM18SG331TN1D/1.5A';
      DESCRIPTION='EMI FILTER BLM18SG331TN1D(330,1.5A)';
      COMPONENT_TYPE='CHIP';
      LEAD_LENGTH='';
      LPID='';
      DAY='20130520';
      PARENT_PART_TYPE='Q_INDUCTOR';
      PARENT_PPT='Q_INDUCTOR';
      PARENT_PPT_PART='Q_INDUCTOR_SMLF-BLM18SG331TN1D/1.5A,IND,CX8SG331000';
  end_body;
end_primitive;
primitive 'Q_INDUCTOR_SMLF-BLM18SN220TN1DA';
  pin
    '2':
      PIN_NUMBER='(2)';
      BIDIRECTIONAL='TRUE';
      INPUT_LOAD='(-0.01,0.01)';
      OUTPUT_LOAD='(1.0,-1.0)';
      PINUSE='BI';
    '1':
      PIN_NUMBER='(1)';
      BIDIRECTIONAL='TRUE';
      INPUT_LOAD='(-0.01,0.01)';
      OUTPUT_LOAD='(1.0,-1.0)';
      PINUSE='BI';
  end_pin;
  body
      PART_NAME='Q_INDUCTOR';
      BODY_NAME='Q_INDUCTOR';
      PHYS_DES_PREFIX='L';
      CLASS='DISCRETE';
      STANDARD='End of Design';
      LIFECYCLE='Comp-Approve';
      JEDEC_TYPE='L0603';
      VALUE='BLM18SN220TN1D/8000MA';
      DESCRIPTION='EMI FILTER BLM18SN220TN1D(22,8000MA)';
      COMPONENT_TYPE='CHIP';
      LEAD_LENGTH='';
      LPID='';
      DAY='20160104';
      PARENT_PART_TYPE='Q_INDUCTOR';
      PARENT_PPT='Q_INDUCTOR';
      PARENT_PPT_PART='Q_INDUCTOR_SMLF-BLM18SN220TN1D/8000MA,IND,CX220TN1001';
  end_body;
end_primitive;
primitive 'Q_INDUCTOR_SMLF-FCM2012KF-601TA';
  pin
    '2':
      PIN_NUMBER='(2)';
      BIDIRECTIONAL='TRUE';
      INPUT_LOAD='(-0.01,0.01)';
      OUTPUT_LOAD='(1.0,-1.0)';
      PINUSE='BI';
    '1':
      PIN_NUMBER='(1)';
      BIDIRECTIONAL='TRUE';
      INPUT_LOAD='(-0.01,0.01)';
      OUTPUT_LOAD='(1.0,-1.0)';
      PINUSE='BI';
  end_pin;
  body
      PART_NAME='Q_INDUCTOR';
      BODY_NAME='Q_INDUCTOR';
      PHYS_DES_PREFIX='L';
      CLASS='DISCRETE';
      STANDARD='';
      LIFECYCLE='';
      JEDEC_TYPE='L0805';
      VALUE='FCM2012KF-601T/0.5A';
      DESCRIPTION='EMI FILTER FCM2012KF-601T05(600,0.5A)';
      COMPONENT_TYPE='CHIP';
      LEAD_LENGTH='';
      LPID='';
      DAY='20131206';
      PARENT_PART_TYPE='Q_INDUCTOR';
      PARENT_PPT='Q_INDUCTOR';
      PARENT_PPT_PART='Q_INDUCTOR_SMLF-FCM2012KF-601T/0.5A,IND,CX601T05003';
  end_body;
end_primitive;
primitive 'Q_LED_SMLF-LED_BLUE,LTST-C281TA';
  pin
    'A':
      PIN_NUMBER='(A)';
      INPUT_LOAD='(-0.01,0.01)';
      OUTPUT_LOAD='(1.0,-1.0)';
      BIDIRECTIONAL='TRUE';
      PINUSE='BI';
    'C':
      PIN_NUMBER='(C)';
      INPUT_LOAD='(-0.01,0.01)';
      OUTPUT_LOAD='(1.0,-1.0)';
      BIDIRECTIONAL='TRUE';
      PINUSE='BI';
  end_pin;
  body
      CLASS='IC';
      PART_NAME='Q_LED';
      PHYS_DES_PREFIX='D';
      STANDARD='';
      LIFECYCLE='';
      JEDEC_TYPE='LED2S_0402';
      DESCRIPTION='LED SMD(2P) BLUE(LTST-C281TBKT-5A)';
      COMPONENT_TYPE='';
      LEAD_LENGTH='';
      LPID='';
      DAY='20121120';
      PARENT_PART_TYPE='Q_LED';
      PARENT_PPT='Q_LED';
      PARENT_PPT_PART='Q_LED_SMLF-LED_BLUE,LTST-C281TBKT-5A,IC,BEBL0172Z00';
  end_body;
end_primitive;
primitive 'Q_LED_SMLF-LED_YELLOW,LTST-C19A';
  pin
    'A':
      PIN_NUMBER='(A)';
      INPUT_LOAD='(-0.01,0.01)';
      OUTPUT_LOAD='(1.0,-1.0)';
      BIDIRECTIONAL='TRUE';
      PINUSE='BI';
    'C':
      PIN_NUMBER='(C)';
      INPUT_LOAD='(-0.01,0.01)';
      OUTPUT_LOAD='(1.0,-1.0)';
      BIDIRECTIONAL='TRUE';
      PINUSE='BI';
  end_pin;
  body
      CLASS='IC';
      PART_NAME='Q_LED';
      PHYS_DES_PREFIX='D';
      STANDARD='';
      LIFECYCLE='';
      JEDEC_TYPE='LED_1921XA';
      DESCRIPTION='LED SMD(2P)YELLOW(LTST-C190KSKT-P)';
      COMPONENT_TYPE='';
      LEAD_LENGTH='';
      LPID='';
      DAY='20200214';
      PARENT_PART_TYPE='Q_LED';
      PARENT_PPT='Q_LED';
      PARENT_PPT_PART='Q_LED_SMLF-LED_YELLOW,LTST-C190KSKT-P,IC,BEYL0159Z00';
  end_body;
end_primitive;
primitive 'Q_OSC4P_SMLF-25MHZ,OSC,BF62500A';
  pin
    'OE':
      PIN_NUMBER='(1)';
      INPUT_LOAD='(-0.01,0.01)';
      PINUSE='IN';
    'OUT':
      PIN_NUMBER='(3)';
      OUTPUT_LOAD='(1.0,-1.0)';
      PINUSE='OUT';
    'GND':
      PIN_NUMBER='(2)';
      PINUSE='POWER';
    'VDD':
      PIN_NUMBER='(4)';
      PINUSE='POWER';
  end_pin;
  body
      CLASS='IC';
      PART_NAME='Q_OSC4P';
      PHYS_DES_PREFIX='OSC';
      STANDARD='';
      LIFECYCLE='';
      JEDEC_TYPE='OSC4_FJ2500009';
      DESCRIPTION='OSC SMD 25MHZ(+-25PPM,3.3V)FJ2500009';
      COMPONENT_TYPE='SMTOTHER';
      LPID='';
      CREATEDAY='';
      PARENT_PART_TYPE='Q_OSC4P';
      PARENT_PPT='Q_OSC4P';
      PARENT_PPT_PART='Q_OSC4P_SMLF-25MHZ,OSC,BF625000014';
  end_body;
end_primitive;
primitive 'Q_OSC4P_SMLF-50MHZ,OSC,BF65000A';
  pin
    'OE':
      PIN_NUMBER='(1)';
      INPUT_LOAD='(-0.01,0.01)';
      PINUSE='IN';
    'OUT':
      PIN_NUMBER='(3)';
      OUTPUT_LOAD='(1.0,-1.0)';
      PINUSE='OUT';
    'GND':
      PIN_NUMBER='(2)';
      PINUSE='POWER';
    'VDD':
      PIN_NUMBER='(4)';
      PINUSE='POWER';
  end_pin;
  body
      CLASS='IC';
      PART_NAME='Q_OSC4P';
      PHYS_DES_PREFIX='OSC';
      STANDARD='';
      LIFECYCLE='';
      JEDEC_TYPE='OSC4_XP';
      DESCRIPTION='OSC SMD 50MHZ(25PPM,15PF,3.3V)FK5000023';
      COMPONENT_TYPE='SMTOTHER';
      LPID='';
      CREATEDAY='20130129';
      PARENT_PART_TYPE='Q_OSC4P';
      PARENT_PPT='Q_OSC4P';
      PARENT_PPT_PART='Q_OSC4P_SMLF-50MHZ,OSC,BF650000032';
  end_body;
end_primitive;
primitive 'Q_RES_0402LF-0,5%,1/16W,CHIP,CA';
  pin
    'A':
      PIN_GROUP='1';
      PIN_NUMBER='(1)';
      PIN_TYPE='UNSPEC';
      PINUSE='UNSPEC';
    'B':
      PIN_GROUP='1';
      PIN_NUMBER='(2)';
      PIN_TYPE='UNSPEC';
      PINUSE='UNSPEC';
  end_pin;
  body
      PART_NAME='Q_RES';
      PHYS_DES_PREFIX='R';
      STANDARD='End of Design';
      LIFECYCLE='Comp-Approve';
      JEDEC_TYPE='R0402';
      ALT_SYMBOLS='(R0402-0201)';
      VALUE='0';
      TOL='5%';
      WATTAGE='1/16W';
      CLASS='DISCRETE';
      DESCRIPTION='RES CHIP 0 1/16W +-5%(0402)EF';
      COMPONENT_TYPE='CHIPR0402';
      LEAD_LENGTH='';
      DFM_EXCLUSION='';
      DAY='20180208';
      PARENT_PART_TYPE='Q_RES';
      PARENT_PPT='Q_RES';
      PARENT_PPT_PART='Q_RES_0402LF-0,5%,1/16W,CHIP,CS00002JB13';
  end_body;
end_primitive;
primitive 'Q_RES_0402LF-0,5%,1/16W,EMPTY,A';
  pin
    'A':
      PIN_GROUP='1';
      PIN_NUMBER='(1)';
      PIN_TYPE='UNSPEC';
      PINUSE='UNSPEC';
    'B':
      PIN_GROUP='1';
      PIN_NUMBER='(2)';
      PIN_TYPE='UNSPEC';
      PINUSE='UNSPEC';
  end_pin;
  body
      PART_NAME='Q_RES';
      PHYS_DES_PREFIX='R';
      STANDARD='End of Design';
      LIFECYCLE='Comp-Approve';
      JEDEC_TYPE='R0402';
      ALT_SYMBOLS='(R0402-0201)';
      VALUE='0';
      TOL='5%';
      WATTAGE='1/16W';
      CLASS='IO';
      DESCRIPTION='RES CHIP 0 1/16W +-5%(0402)EF';
      COMPONENT_TYPE='CHIPR0402';
      LEAD_LENGTH='';
      DFM_EXCLUSION='';
      DAY='20180208';
      PARENT_PART_TYPE='Q_RES';
      PARENT_PPT='Q_RES';
      PARENT_PPT_PART='Q_RES_0402LF-0,5%,1/16W,EMPTY,CS00002JB13';
  end_body;
end_primitive;
primitive 'Q_RES_0402LF-1,1%,1/16W,CHIP,CA';
  pin
    'A':
      PIN_GROUP='1';
      PIN_NUMBER='(1)';
      PIN_TYPE='UNSPEC';
      PINUSE='UNSPEC';
    'B':
      PIN_GROUP='1';
      PIN_NUMBER='(2)';
      PIN_TYPE='UNSPEC';
      PINUSE='UNSPEC';
  end_pin;
  body
      PART_NAME='Q_RES';
      PHYS_DES_PREFIX='R';
      STANDARD='End of Design';
      LIFECYCLE='Comp-Approve';
      JEDEC_TYPE='R0402';
      ALT_SYMBOLS='(R0402-0201)';
      VALUE='1';
      TOL='1%';
      WATTAGE='1/16W';
      CLASS='DISCRETE';
      DESCRIPTION='RES CHIP 1 1/16W +-1%(0402)EF';
      COMPONENT_TYPE='CHIPR0402';
      LEAD_LENGTH='';
      DFM_EXCLUSION='';
      DAY='20180221';
      PARENT_PART_TYPE='Q_RES';
      PARENT_PPT='Q_RES';
      PARENT_PPT_PART='Q_RES_0402LF-1,1%,1/16W,CHIP,CS-1002FB04';
  end_body;
end_primitive;
primitive 'Q_RES_0402LF-1,1%,1/16W,EMPTY,A';
  pin
    'A':
      PIN_GROUP='1';
      PIN_NUMBER='(1)';
      PIN_TYPE='UNSPEC';
      PINUSE='UNSPEC';
    'B':
      PIN_GROUP='1';
      PIN_NUMBER='(2)';
      PIN_TYPE='UNSPEC';
      PINUSE='UNSPEC';
  end_pin;
  body
      PART_NAME='Q_RES';
      PHYS_DES_PREFIX='R';
      STANDARD='End of Design';
      LIFECYCLE='Comp-Approve';
      JEDEC_TYPE='R0402';
      ALT_SYMBOLS='(R0402-0201)';
      VALUE='1';
      TOL='1%';
      WATTAGE='1/16W';
      CLASS='IO';
      DESCRIPTION='RES CHIP 1 1/16W +-1%(0402)EF';
      COMPONENT_TYPE='CHIPR0402';
      LEAD_LENGTH='';
      DFM_EXCLUSION='';
      DAY='20180221';
      PARENT_PART_TYPE='Q_RES';
      PARENT_PPT='Q_RES';
      PARENT_PPT_PART='Q_RES_0402LF-1,1%,1/16W,EMPTY,CS-1002FB04';
  end_body;
end_primitive;
primitive 'Q_RES_0402LF-1.21K,1%,1/16W,CHA';
  pin
    'A':
      PIN_GROUP='1';
      PIN_NUMBER='(1)';
      PIN_TYPE='UNSPEC';
      PINUSE='UNSPEC';
    'B':
      PIN_GROUP='1';
      PIN_NUMBER='(2)';
      PIN_TYPE='UNSPEC';
      PINUSE='UNSPEC';
  end_pin;
  body
      PART_NAME='Q_RES';
      PHYS_DES_PREFIX='R';
      STANDARD='End of Design';
      LIFECYCLE='Comp-Approve';
      JEDEC_TYPE='R0402';
      ALT_SYMBOLS='(R0402-0201)';
      VALUE='1.21K';
      TOL='1%';
      WATTAGE='1/16W';
      CLASS='DISCRETE';
      DESCRIPTION='RES CHIP 1.21K 1/16W +-1%(0402)EF';
      COMPONENT_TYPE='CHIPR0402';
      LEAD_LENGTH='';
      DFM_EXCLUSION='';
      DAY='20180221';
      PARENT_PART_TYPE='Q_RES';
      PARENT_PPT='Q_RES';
      PARENT_PPT_PART='Q_RES_0402LF-1.21K,1%,1/16W,CHIP,CS21212FB05';
  end_body;
end_primitive;
primitive 'Q_RES_0402LF-1.33K,1%,1/16W,EMA';
  pin
    'A':
      PIN_GROUP='1';
      PIN_NUMBER='(1)';
      PIN_TYPE='UNSPEC';
      PINUSE='UNSPEC';
    'B':
      PIN_GROUP='1';
      PIN_NUMBER='(2)';
      PIN_TYPE='UNSPEC';
      PINUSE='UNSPEC';
  end_pin;
  body
      PART_NAME='Q_RES';
      PHYS_DES_PREFIX='R';
      STANDARD='';
      LIFECYCLE='';
      JEDEC_TYPE='R0402';
      ALT_SYMBOLS='(R0402-0201)';
      VALUE='1.33K';
      TOL='1%';
      WATTAGE='1/16W';
      CLASS='IO';
      DESCRIPTION='RES CHIP 1.33K 1/16W +-1%(0402)EF';
      COMPONENT_TYPE='CHIPR0402';
      LEAD_LENGTH='';
      DFM_EXCLUSION='';
      DAY='20190717';
      PARENT_PART_TYPE='Q_RES';
      PARENT_PPT='Q_RES';
      PARENT_PPT_PART='Q_RES_0402LF-1.33K,1%,1/16W,EMPTY,CS21332FB05';
  end_body;
end_primitive;
primitive 'Q_RES_0402LF-1.5K,1%,1/16W,CHIA';
  pin
    'A':
      PIN_GROUP='1';
      PIN_NUMBER='(1)';
      PIN_TYPE='UNSPEC';
      PINUSE='UNSPEC';
    'B':
      PIN_GROUP='1';
      PIN_NUMBER='(2)';
      PIN_TYPE='UNSPEC';
      PINUSE='UNSPEC';
  end_pin;
  body
      PART_NAME='Q_RES';
      PHYS_DES_PREFIX='R';
      STANDARD='End of Design';
      LIFECYCLE='Comp-Approve';
      JEDEC_TYPE='R0402';
      ALT_SYMBOLS='(R0402-0201)';
      VALUE='1.5K';
      TOL='1%';
      WATTAGE='1/16W';
      CLASS='DISCRETE';
      DESCRIPTION='RES CHIP 1.5K 1/16W +-1%(0402)EF';
      COMPONENT_TYPE='CHIPR0402';
      LEAD_LENGTH='';
      DFM_EXCLUSION='';
      DAY='20180208';
      PARENT_PART_TYPE='Q_RES';
      PARENT_PPT='Q_RES';
      PARENT_PPT_PART='Q_RES_0402LF-1.5K,1%,1/16W,CHIP,CS21502FB07';
  end_body;
end_primitive;
primitive 'Q_RES_0402LF-1.5K,1%,1/16W,EMPA';
  pin
    'A':
      PIN_GROUP='1';
      PIN_NUMBER='(1)';
      PIN_TYPE='UNSPEC';
      PINUSE='UNSPEC';
    'B':
      PIN_GROUP='1';
      PIN_NUMBER='(2)';
      PIN_TYPE='UNSPEC';
      PINUSE='UNSPEC';
  end_pin;
  body
      PART_NAME='Q_RES';
      PHYS_DES_PREFIX='R';
      STANDARD='End of Design';
      LIFECYCLE='Comp-Approve';
      JEDEC_TYPE='R0402';
      ALT_SYMBOLS='(R0402-0201)';
      VALUE='1.5K';
      TOL='1%';
      WATTAGE='1/16W';
      CLASS='IO';
      DESCRIPTION='RES CHIP 1.5K 1/16W +-1%(0402)EF';
      COMPONENT_TYPE='CHIPR0402';
      LEAD_LENGTH='';
      DFM_EXCLUSION='';
      DAY='20180208';
      PARENT_PART_TYPE='Q_RES';
      PARENT_PPT='Q_RES';
      PARENT_PPT_PART='Q_RES_0402LF-1.5K,1%,1/16W,EMPTY,CS21502FB07';
  end_body;
end_primitive;
primitive 'Q_RES_0402LF-10,1%,1/16W,CHIP,A';
  pin
    'A':
      PIN_GROUP='1';
      PIN_NUMBER='(1)';
      PIN_TYPE='UNSPEC';
      PINUSE='UNSPEC';
    'B':
      PIN_GROUP='1';
      PIN_NUMBER='(2)';
      PIN_TYPE='UNSPEC';
      PINUSE='UNSPEC';
  end_pin;
  body
      PART_NAME='Q_RES';
      PHYS_DES_PREFIX='R';
      STANDARD='End of Design';
      LIFECYCLE='Comp-Approve';
      JEDEC_TYPE='R0402';
      ALT_SYMBOLS='(R0402-0201)';
      VALUE='10';
      TOL='1%';
      WATTAGE='1/16W';
      CLASS='DISCRETE';
      DESCRIPTION='RES CHIP 10 1/16W +-1%(0402)EF';
      COMPONENT_TYPE='CHIPR0402';
      LEAD_LENGTH='';
      DFM_EXCLUSION='';
      DAY='20180208';
      PARENT_PART_TYPE='Q_RES';
      PARENT_PPT='Q_RES';
      PARENT_PPT_PART='Q_RES_0402LF-10,1%,1/16W,CHIP,CS01002FB07';
  end_body;
end_primitive;
primitive 'Q_RES_0402LF-10,1%,1/16W,EMPTYA';
  pin
    'A':
      PIN_GROUP='1';
      PIN_NUMBER='(1)';
      PIN_TYPE='UNSPEC';
      PINUSE='UNSPEC';
    'B':
      PIN_GROUP='1';
      PIN_NUMBER='(2)';
      PIN_TYPE='UNSPEC';
      PINUSE='UNSPEC';
  end_pin;
  body
      PART_NAME='Q_RES';
      PHYS_DES_PREFIX='R';
      STANDARD='End of Design';
      LIFECYCLE='Comp-Approve';
      JEDEC_TYPE='R0402';
      ALT_SYMBOLS='(R0402-0201)';
      VALUE='10';
      TOL='1%';
      WATTAGE='1/16W';
      CLASS='IO';
      DESCRIPTION='RES CHIP 10 1/16W +-1%(0402)EF';
      COMPONENT_TYPE='CHIPR0402';
      LEAD_LENGTH='';
      DFM_EXCLUSION='';
      DAY='20180208';
      PARENT_PART_TYPE='Q_RES';
      PARENT_PPT='Q_RES';
      PARENT_PPT_PART='Q_RES_0402LF-10,1%,1/16W,EMPTY,CS01002FB07';
  end_body;
end_primitive;
primitive 'Q_RES_0402LF-10.5K,1%,1/16W,EMA';
  pin
    'A':
      PIN_GROUP='1';
      PIN_NUMBER='(1)';
      PIN_TYPE='UNSPEC';
      PINUSE='UNSPEC';
    'B':
      PIN_GROUP='1';
      PIN_NUMBER='(2)';
      PIN_TYPE='UNSPEC';
      PINUSE='UNSPEC';
  end_pin;
  body
      PART_NAME='Q_RES';
      PHYS_DES_PREFIX='R';
      STANDARD='';
      LIFECYCLE='';
      JEDEC_TYPE='R0402';
      ALT_SYMBOLS='(R0402-0201)';
      VALUE='10.5K';
      TOL='1%';
      WATTAGE='1/16W';
      CLASS='IO';
      DESCRIPTION='RES CHIP 10.5K 1/16W +-1%(0402)EF';
      COMPONENT_TYPE='CHIPR0402';
      LEAD_LENGTH='';
      DFM_EXCLUSION='';
      DAY='20220426';
      PARENT_PART_TYPE='Q_RES';
      PARENT_PPT='Q_RES';
      PARENT_PPT_PART='Q_RES_0402LF-10.5K,1%,1/16W,EMPTY,CS31052FB03';
  end_body;
end_primitive;
primitive 'Q_RES_0402LF-100,1%,1/16W,CHIPA';
  pin
    'A':
      PIN_GROUP='1';
      PIN_NUMBER='(1)';
      PIN_TYPE='UNSPEC';
      PINUSE='UNSPEC';
    'B':
      PIN_GROUP='1';
      PIN_NUMBER='(2)';
      PIN_TYPE='UNSPEC';
      PINUSE='UNSPEC';
  end_pin;
  body
      PART_NAME='Q_RES';
      PHYS_DES_PREFIX='R';
      STANDARD='End of Design';
      LIFECYCLE='Comp-Approve';
      JEDEC_TYPE='R0402';
      ALT_SYMBOLS='(R0402-0201)';
      VALUE='100';
      TOL='1%';
      WATTAGE='1/16W';
      CLASS='DISCRETE';
      DESCRIPTION='RES CHIP 100 1/16W +-1%(0402)EF';
      COMPONENT_TYPE='CHIPR0402';
      LEAD_LENGTH='';
      DFM_EXCLUSION='';
      DAY='20180208';
      PARENT_PART_TYPE='Q_RES';
      PARENT_PPT='Q_RES';
      PARENT_PPT_PART='Q_RES_0402LF-100,1%,1/16W,CHIP,CS11002FB07';
  end_body;
end_primitive;
primitive 'Q_RES_0402LF-100,1%,1/16W,EMPTA';
  pin
    'A':
      PIN_GROUP='1';
      PIN_NUMBER='(1)';
      PIN_TYPE='UNSPEC';
      PINUSE='UNSPEC';
    'B':
      PIN_GROUP='1';
      PIN_NUMBER='(2)';
      PIN_TYPE='UNSPEC';
      PINUSE='UNSPEC';
  end_pin;
  body
      PART_NAME='Q_RES';
      PHYS_DES_PREFIX='R';
      STANDARD='End of Design';
      LIFECYCLE='Comp-Approve';
      JEDEC_TYPE='R0402';
      ALT_SYMBOLS='(R0402-0201)';
      VALUE='100';
      TOL='1%';
      WATTAGE='1/16W';
      CLASS='IO';
      DESCRIPTION='RES CHIP 100 1/16W +-1%(0402)EF';
      COMPONENT_TYPE='CHIPR0402';
      LEAD_LENGTH='';
      DFM_EXCLUSION='';
      DAY='20180208';
      PARENT_PART_TYPE='Q_RES';
      PARENT_PPT='Q_RES';
      PARENT_PPT_PART='Q_RES_0402LF-100,1%,1/16W,EMPTY,CS11002FB07';
  end_body;
end_primitive;
primitive 'Q_RES_0402LF-100K,1%,1/16W,CHIA';
  pin
    'A':
      PIN_GROUP='1';
      PIN_NUMBER='(1)';
      PIN_TYPE='UNSPEC';
      PINUSE='UNSPEC';
    'B':
      PIN_GROUP='1';
      PIN_NUMBER='(2)';
      PIN_TYPE='UNSPEC';
      PINUSE='UNSPEC';
  end_pin;
  body
      PART_NAME='Q_RES';
      PHYS_DES_PREFIX='R';
      STANDARD='End of Design';
      LIFECYCLE='Comp-Approve';
      JEDEC_TYPE='R0402';
      ALT_SYMBOLS='(R0402-0201)';
      VALUE='100K';
      TOL='1%';
      WATTAGE='1/16W';
      CLASS='DISCRETE';
      DESCRIPTION='RES CHIP 100K 1/16W +-1%(0402)EF';
      COMPONENT_TYPE='CHIPR0402';
      LEAD_LENGTH='';
      DFM_EXCLUSION='';
      DAY='20180208';
      PARENT_PART_TYPE='Q_RES';
      PARENT_PPT='Q_RES';
      PARENT_PPT_PART='Q_RES_0402LF-100K,1%,1/16W,CHIP,CS41002FB09';
  end_body;
end_primitive;
primitive 'Q_RES_0402LF-100K,1%,1/16W,EMPA';
  pin
    'A':
      PIN_GROUP='1';
      PIN_NUMBER='(1)';
      PIN_TYPE='UNSPEC';
      PINUSE='UNSPEC';
    'B':
      PIN_GROUP='1';
      PIN_NUMBER='(2)';
      PIN_TYPE='UNSPEC';
      PINUSE='UNSPEC';
  end_pin;
  body
      PART_NAME='Q_RES';
      PHYS_DES_PREFIX='R';
      STANDARD='End of Design';
      LIFECYCLE='Comp-Approve';
      JEDEC_TYPE='R0402';
      ALT_SYMBOLS='(R0402-0201)';
      VALUE='100K';
      TOL='1%';
      WATTAGE='1/16W';
      CLASS='IO';
      DESCRIPTION='RES CHIP 100K 1/16W +-1%(0402)EF';
      COMPONENT_TYPE='CHIPR0402';
      LEAD_LENGTH='';
      DFM_EXCLUSION='';
      DAY='20180208';
      PARENT_PART_TYPE='Q_RES';
      PARENT_PPT='Q_RES';
      PARENT_PPT_PART='Q_RES_0402LF-100K,1%,1/16W,EMPTY,CS41002FB09';
  end_body;
end_primitive;
primitive 'Q_RES_0402LF-10K,0.1%,1/16W,CHA';
  pin
    'A':
      PIN_GROUP='1';
      PIN_NUMBER='(1)';
      PIN_TYPE='UNSPEC';
      PINUSE='UNSPEC';
    'B':
      PIN_GROUP='1';
      PIN_NUMBER='(2)';
      PIN_TYPE='UNSPEC';
      PINUSE='UNSPEC';
  end_pin;
  body
      PART_NAME='Q_RES';
      PHYS_DES_PREFIX='R';
      STANDARD='End of Design';
      LIFECYCLE='Comp-Approve';
      JEDEC_TYPE='R0402';
      ALT_SYMBOLS='(R0402-0201)';
      VALUE='10K';
      TOL='0.1%';
      WATTAGE='1/16W';
      CLASS='DISCRETE';
      DESCRIPTION='RES CHIP 10K 1/16W +-0.1%(0402)EF';
      COMPONENT_TYPE='CHIP0402';
      LEAD_LENGTH='';
      DFM_EXCLUSION='';
      DAY='20180212';
      PARENT_PART_TYPE='Q_RES';
      PARENT_PPT='Q_RES';
      PARENT_PPT_PART='Q_RES_0402LF-10K,0.1%,1/16W,CHIP,CS31002BB06';
  end_body;
end_primitive;
primitive 'Q_RES_0402LF-10K,1%,1/16W,CHIPA';
  pin
    'A':
      PIN_GROUP='1';
      PIN_NUMBER='(1)';
      PIN_TYPE='UNSPEC';
      PINUSE='UNSPEC';
    'B':
      PIN_GROUP='1';
      PIN_NUMBER='(2)';
      PIN_TYPE='UNSPEC';
      PINUSE='UNSPEC';
  end_pin;
  body
      PART_NAME='Q_RES';
      PHYS_DES_PREFIX='R';
      STANDARD='End of Design';
      LIFECYCLE='Comp-Approve';
      JEDEC_TYPE='R0402';
      ALT_SYMBOLS='(R0402-0201)';
      VALUE='10K';
      TOL='1%';
      WATTAGE='1/16W';
      CLASS='DISCRETE';
      DESCRIPTION='RES CHIP 10K 1/16W +-1%(0402)EF';
      COMPONENT_TYPE='CHIPR0402';
      LEAD_LENGTH='';
      DFM_EXCLUSION='';
      DAY='20180208';
      PARENT_PART_TYPE='Q_RES';
      PARENT_PPT='Q_RES';
      PARENT_PPT_PART='Q_RES_0402LF-10K,1%,1/16W,CHIP,CS31002FB08';
  end_body;
end_primitive;
primitive 'Q_RES_0402LF-10K,1%,1/16W,EMPTA';
  pin
    'A':
      PIN_GROUP='1';
      PIN_NUMBER='(1)';
      PIN_TYPE='UNSPEC';
      PINUSE='UNSPEC';
    'B':
      PIN_GROUP='1';
      PIN_NUMBER='(2)';
      PIN_TYPE='UNSPEC';
      PINUSE='UNSPEC';
  end_pin;
  body
      PART_NAME='Q_RES';
      PHYS_DES_PREFIX='R';
      STANDARD='End of Design';
      LIFECYCLE='Comp-Approve';
      JEDEC_TYPE='R0402';
      ALT_SYMBOLS='(R0402-0201)';
      VALUE='10K';
      TOL='1%';
      WATTAGE='1/16W';
      CLASS='IO';
      DESCRIPTION='RES CHIP 10K 1/16W +-1%(0402)EF';
      COMPONENT_TYPE='CHIPR0402';
      LEAD_LENGTH='';
      DFM_EXCLUSION='';
      DAY='20180208';
      PARENT_PART_TYPE='Q_RES';
      PARENT_PPT='Q_RES';
      PARENT_PPT_PART='Q_RES_0402LF-10K,1%,1/16W,EMPTY,CS31002FB08';
  end_body;
end_primitive;
primitive 'Q_RES_0402LF-10M,1%,1/16W,CHIPA';
  pin
    'A':
      PIN_GROUP='1';
      PIN_NUMBER='(1)';
      PIN_TYPE='UNSPEC';
      PINUSE='UNSPEC';
    'B':
      PIN_GROUP='1';
      PIN_NUMBER='(2)';
      PIN_TYPE='UNSPEC';
      PINUSE='UNSPEC';
  end_pin;
  body
      PART_NAME='Q_RES';
      PHYS_DES_PREFIX='R';
      STANDARD='';
      LIFECYCLE='';
      JEDEC_TYPE='R0402';
      ALT_SYMBOLS='(R0402-0201)';
      VALUE='10M';
      TOL='1%';
      WATTAGE='1/16W';
      CLASS='DISCRETE';
      DESCRIPTION='RES CHIP 10M 1/16W +-1%(0402)EF';
      COMPONENT_TYPE='CHIPR0402';
      LEAD_LENGTH='';
      DFM_EXCLUSION='';
      DAY='20190906';
      PARENT_PART_TYPE='Q_RES';
      PARENT_PPT='Q_RES';
      PARENT_PPT_PART='Q_RES_0402LF-10M,1%,1/16W,CHIP,CS61002FB02';
  end_body;
end_primitive;
primitive 'Q_RES_0402LF-10M,1%,1/16W,EMPTA';
  pin
    'A':
      PIN_GROUP='1';
      PIN_NUMBER='(1)';
      PIN_TYPE='UNSPEC';
      PINUSE='UNSPEC';
    'B':
      PIN_GROUP='1';
      PIN_NUMBER='(2)';
      PIN_TYPE='UNSPEC';
      PINUSE='UNSPEC';
  end_pin;
  body
      PART_NAME='Q_RES';
      PHYS_DES_PREFIX='R';
      STANDARD='';
      LIFECYCLE='';
      JEDEC_TYPE='R0402';
      ALT_SYMBOLS='(R0402-0201)';
      VALUE='10M';
      TOL='1%';
      WATTAGE='1/16W';
      CLASS='IO';
      DESCRIPTION='RES CHIP 10M 1/16W +-1%(0402)EF';
      COMPONENT_TYPE='CHIPR0402';
      LEAD_LENGTH='';
      DFM_EXCLUSION='';
      DAY='20190906';
      PARENT_PART_TYPE='Q_RES';
      PARENT_PPT='Q_RES';
      PARENT_PPT_PART='Q_RES_0402LF-10M,1%,1/16W,EMPTY,CS61002FB02';
  end_body;
end_primitive;
primitive 'Q_RES_0402LF-11.3K,0.1%,1/16W,A';
  pin
    'A':
      PIN_GROUP='1';
      PIN_NUMBER='(1)';
      PIN_TYPE='UNSPEC';
      PINUSE='UNSPEC';
    'B':
      PIN_GROUP='1';
      PIN_NUMBER='(2)';
      PIN_TYPE='UNSPEC';
      PINUSE='UNSPEC';
  end_pin;
  body
      PART_NAME='Q_RES';
      PHYS_DES_PREFIX='R';
      STANDARD='';
      LIFECYCLE='';
      JEDEC_TYPE='R0402';
      ALT_SYMBOLS='(R0402-0201)';
      VALUE='11.3K';
      TOL='0.1%';
      WATTAGE='1/16W';
      CLASS='DISCRETE';
      DESCRIPTION='RES CHIP 11.3K 1/16W +-0.1%(0402)EF';
      COMPONENT_TYPE='CHIPR0402';
      LEAD_LENGTH='';
      DFM_EXCLUSION='';
      DAY='20220316';
      PARENT_PART_TYPE='Q_RES';
      PARENT_PPT='Q_RES';
      PARENT_PPT_PART='Q_RES_0402LF-11.3K,0.1%,1/16W,CHIP,CS31132BB02';
  end_body;
end_primitive;
primitive 'Q_RES_0402LF-11.8K,0.1%,1/16W,A';
  pin
    'A':
      PIN_GROUP='1';
      PIN_NUMBER='(1)';
      PIN_TYPE='UNSPEC';
      PINUSE='UNSPEC';
    'B':
      PIN_GROUP='1';
      PIN_NUMBER='(2)';
      PIN_TYPE='UNSPEC';
      PINUSE='UNSPEC';
  end_pin;
  body
      PART_NAME='Q_RES';
      PHYS_DES_PREFIX='R';
      STANDARD='';
      LIFECYCLE='';
      JEDEC_TYPE='R0402';
      ALT_SYMBOLS='(R0402-0201)';
      VALUE='11.8K';
      TOL='0.1%';
      WATTAGE='1/16W';
      CLASS='DISCRETE';
      DESCRIPTION='RES CHIP 11.8K 1/16W +-0.1%(0402)EF';
      COMPONENT_TYPE='CHIPR0402';
      LEAD_LENGTH='';
      DFM_EXCLUSION='';
      DAY='20210719';
      PARENT_PART_TYPE='Q_RES';
      PARENT_PPT='Q_RES';
      PARENT_PPT_PART='Q_RES_0402LF-11.8K,0.1%,1/16W,CHIP,CS31182BB06';
  end_body;
end_primitive;
primitive 'Q_RES_0402LF-113,1%,1/16W,CHIPA';
  pin
    'A':
      PIN_GROUP='1';
      PIN_NUMBER='(1)';
      PIN_TYPE='UNSPEC';
      PINUSE='UNSPEC';
    'B':
      PIN_GROUP='1';
      PIN_NUMBER='(2)';
      PIN_TYPE='UNSPEC';
      PINUSE='UNSPEC';
  end_pin;
  body
      PART_NAME='Q_RES';
      PHYS_DES_PREFIX='R';
      STANDARD='End of Design';
      LIFECYCLE='Comp-Approve';
      JEDEC_TYPE='R0402';
      ALT_SYMBOLS='(R0402-0201)';
      VALUE='113';
      TOL='1%';
      WATTAGE='1/16W';
      CLASS='DISCRETE';
      DESCRIPTION='RES CHIP 113 1/16W +-1%(0402)EF';
      COMPONENT_TYPE='CHIPR0402';
      LEAD_LENGTH='';
      DFM_EXCLUSION='';
      DAY='20180221';
      PARENT_PART_TYPE='Q_RES';
      PARENT_PPT='Q_RES';
      PARENT_PPT_PART='Q_RES_0402LF-113,1%,1/16W,CHIP,CS11132FB02';
  end_body;
end_primitive;
primitive 'Q_RES_0402LF-12.4K,0.1%,1/16W,A';
  pin
    'A':
      PIN_GROUP='1';
      PIN_NUMBER='(1)';
      PIN_TYPE='UNSPEC';
      PINUSE='UNSPEC';
    'B':
      PIN_GROUP='1';
      PIN_NUMBER='(2)';
      PIN_TYPE='UNSPEC';
      PINUSE='UNSPEC';
  end_pin;
  body
      PART_NAME='Q_RES';
      PHYS_DES_PREFIX='R';
      STANDARD='';
      LIFECYCLE='';
      JEDEC_TYPE='R0402';
      ALT_SYMBOLS='(R0402-0201)';
      VALUE='12.4K';
      TOL='0.1%';
      WATTAGE='1/16W';
      CLASS='DISCRETE';
      DESCRIPTION='RES CHIP 12.4K 1/16W +-0.1%( 0402)EF';
      COMPONENT_TYPE='CHIPR0402';
      LEAD_LENGTH='';
      DFM_EXCLUSION='';
      DAY='20210719';
      PARENT_PART_TYPE='Q_RES';
      PARENT_PPT='Q_RES';
      PARENT_PPT_PART='Q_RES_0402LF-12.4K,0.1%,1/16W,CHIP,CS31242BB10';
  end_body;
end_primitive;
primitive 'Q_RES_0402LF-120,1%,1/16W,CHIPA';
  pin
    'A':
      PIN_GROUP='1';
      PIN_NUMBER='(1)';
      PIN_TYPE='UNSPEC';
      PINUSE='UNSPEC';
    'B':
      PIN_GROUP='1';
      PIN_NUMBER='(2)';
      PIN_TYPE='UNSPEC';
      PINUSE='UNSPEC';
  end_pin;
  body
      PART_NAME='Q_RES';
      PHYS_DES_PREFIX='R';
      STANDARD='End of Design';
      LIFECYCLE='Comp-Approve';
      JEDEC_TYPE='R0402';
      ALT_SYMBOLS='(R0402-0201)';
      VALUE='120';
      TOL='1%';
      WATTAGE='1/16W';
      CLASS='DISCRETE';
      DESCRIPTION='RES CHIP 120 1/16W +-1%(0402)EF';
      COMPONENT_TYPE='CHIPR0402';
      LEAD_LENGTH='';
      DFM_EXCLUSION='';
      DAY='20180116';
      PARENT_PART_TYPE='Q_RES';
      PARENT_PPT='Q_RES';
      PARENT_PPT_PART='Q_RES_0402LF-120,1%,1/16W,CHIP,CS11202FB02';
  end_body;
end_primitive;
primitive 'Q_RES_0402LF-120K,1%,1/16W,CHIA';
  pin
    'A':
      PIN_GROUP='1';
      PIN_NUMBER='(1)';
      PIN_TYPE='UNSPEC';
      PINUSE='UNSPEC';
    'B':
      PIN_GROUP='1';
      PIN_NUMBER='(2)';
      PIN_TYPE='UNSPEC';
      PINUSE='UNSPEC';
  end_pin;
  body
      PART_NAME='Q_RES';
      PHYS_DES_PREFIX='R';
      STANDARD='';
      LIFECYCLE='';
      JEDEC_TYPE='R0402';
      ALT_SYMBOLS='(R0402-0201)';
      VALUE='120K';
      TOL='1%';
      WATTAGE='1/16W';
      CLASS='DISCRETE';
      DESCRIPTION='RES CHIP 120K 1/16W +-1%(0402)EF';
      COMPONENT_TYPE='CHIPR0402';
      LEAD_LENGTH='';
      DFM_EXCLUSION='';
      DAY='20200225';
      PARENT_PART_TYPE='Q_RES';
      PARENT_PPT='Q_RES';
      PARENT_PPT_PART='Q_RES_0402LF-120K,1%,1/16W,CHIP,CS41202FB05';
  end_body;
end_primitive;
primitive 'Q_RES_0402LF-127K,1%,1/16W,CHIA';
  pin
    'A':
      PIN_GROUP='1';
      PIN_NUMBER='(1)';
      PIN_TYPE='UNSPEC';
      PINUSE='UNSPEC';
    'B':
      PIN_GROUP='1';
      PIN_NUMBER='(2)';
      PIN_TYPE='UNSPEC';
      PINUSE='UNSPEC';
  end_pin;
  body
      PART_NAME='Q_RES';
      PHYS_DES_PREFIX='R';
      STANDARD='';
      LIFECYCLE='';
      JEDEC_TYPE='R0402';
      ALT_SYMBOLS='(R0402-0201)';
      VALUE='127K';
      TOL='1%';
      WATTAGE='1/16W';
      CLASS='DISCRETE';
      DESCRIPTION='RES CHIP 127K 1/16W +-1%(0402)EF';
      COMPONENT_TYPE='CHIPR0402';
      LEAD_LENGTH='';
      DFM_EXCLUSION='';
      DAY='20210715';
      PARENT_PART_TYPE='Q_RES';
      PARENT_PPT='Q_RES';
      PARENT_PPT_PART='Q_RES_0402LF-127K,1%,1/16W,CHIP,CS41272FB07';
  end_body;
end_primitive;
primitive 'Q_RES_0402LF-12K,1%,1/16W,EMPTA';
  pin
    'A':
      PIN_GROUP='1';
      PIN_NUMBER='(1)';
      PIN_TYPE='UNSPEC';
      PINUSE='UNSPEC';
    'B':
      PIN_GROUP='1';
      PIN_NUMBER='(2)';
      PIN_TYPE='UNSPEC';
      PINUSE='UNSPEC';
  end_pin;
  body
      PART_NAME='Q_RES';
      PHYS_DES_PREFIX='R';
      STANDARD='End of Design';
      LIFECYCLE='Comp-Approve';
      JEDEC_TYPE='R0402';
      ALT_SYMBOLS='(R0402-0201)';
      VALUE='12K';
      TOL='1%';
      WATTAGE='1/16W';
      CLASS='IO';
      DESCRIPTION='RES CHIP 12K 1/16W +-1%(0402)EF';
      COMPONENT_TYPE='CHIPR0402';
      LEAD_LENGTH='';
      DFM_EXCLUSION='';
      DAY='20180221';
      PARENT_PART_TYPE='Q_RES';
      PARENT_PPT='Q_RES';
      PARENT_PPT_PART='Q_RES_0402LF-12K,1%,1/16W,EMPTY,CS31202FB04';
  end_body;
end_primitive;
primitive 'Q_RES_0402LF-130,1%,1/16W,CHIPA';
  pin
    'A':
      PIN_GROUP='1';
      PIN_NUMBER='(1)';
      PIN_TYPE='UNSPEC';
      PINUSE='UNSPEC';
    'B':
      PIN_GROUP='1';
      PIN_NUMBER='(2)';
      PIN_TYPE='UNSPEC';
      PINUSE='UNSPEC';
  end_pin;
  body
      PART_NAME='Q_RES';
      PHYS_DES_PREFIX='R';
      STANDARD='End of Design';
      LIFECYCLE='Comp-Approve';
      JEDEC_TYPE='R0402';
      ALT_SYMBOLS='(R0402-0201)';
      VALUE='130';
      TOL='1%';
      WATTAGE='1/16W';
      CLASS='DISCRETE';
      DESCRIPTION='RES CHIP 130 1/16W +-1%(0402)EF';
      COMPONENT_TYPE='CHIPR0402';
      LEAD_LENGTH='';
      DFM_EXCLUSION='';
      DAY='20180221';
      PARENT_PART_TYPE='Q_RES';
      PARENT_PPT='Q_RES';
      PARENT_PPT_PART='Q_RES_0402LF-130,1%,1/16W,CHIP,CS11302FB03';
  end_body;
end_primitive;
primitive 'Q_RES_0402LF-14.3K,1%,1/16W,CHA';
  pin
    'A':
      PIN_GROUP='1';
      PIN_NUMBER='(1)';
      PIN_TYPE='UNSPEC';
      PINUSE='UNSPEC';
    'B':
      PIN_GROUP='1';
      PIN_NUMBER='(2)';
      PIN_TYPE='UNSPEC';
      PINUSE='UNSPEC';
  end_pin;
  body
      PART_NAME='Q_RES';
      PHYS_DES_PREFIX='R';
      STANDARD='End of Design';
      LIFECYCLE='Comp-Approve';
      JEDEC_TYPE='R0402';
      ALT_SYMBOLS='(R0402-0201)';
      VALUE='14.3K';
      TOL='1%';
      WATTAGE='1/16W';
      CLASS='DISCRETE';
      DESCRIPTION='RES CHIP 14.3K 1/16W +-1%(0402)EF';
      COMPONENT_TYPE='CHIPR0402';
      LEAD_LENGTH='';
      DFM_EXCLUSION='';
      DAY='20180221';
      PARENT_PART_TYPE='Q_RES';
      PARENT_PPT='Q_RES';
      PARENT_PPT_PART='Q_RES_0402LF-14.3K,1%,1/16W,CHIP,CS31432FB02';
  end_body;
end_primitive;
primitive 'Q_RES_0402LF-15.4K,1%,1/16W,CHA';
  pin
    'A':
      PIN_GROUP='1';
      PIN_NUMBER='(1)';
      PIN_TYPE='UNSPEC';
      PINUSE='UNSPEC';
    'B':
      PIN_GROUP='1';
      PIN_NUMBER='(2)';
      PIN_TYPE='UNSPEC';
      PINUSE='UNSPEC';
  end_pin;
  body
      PART_NAME='Q_RES';
      PHYS_DES_PREFIX='R';
      STANDARD='';
      LIFECYCLE='';
      JEDEC_TYPE='R0402';
      ALT_SYMBOLS='(R0402-0201)';
      VALUE='15.4K';
      TOL='1%';
      WATTAGE='1/16W';
      CLASS='DISCRETE';
      DESCRIPTION='RES CHIP 15.4K 1/16W +-1%(0402)EF';
      COMPONENT_TYPE='CHIPR0402';
      LEAD_LENGTH='';
      DFM_EXCLUSION='';
      DAY='20210715';
      PARENT_PART_TYPE='Q_RES';
      PARENT_PPT='Q_RES';
      PARENT_PPT_PART='Q_RES_0402LF-15.4K,1%,1/16W,CHIP,CS31542FB02';
  end_body;
end_primitive;
primitive 'Q_RES_0402LF-150,1%,1/16W,CHIPA';
  pin
    'A':
      PIN_GROUP='1';
      PIN_NUMBER='(1)';
      PIN_TYPE='UNSPEC';
      PINUSE='UNSPEC';
    'B':
      PIN_GROUP='1';
      PIN_NUMBER='(2)';
      PIN_TYPE='UNSPEC';
      PINUSE='UNSPEC';
  end_pin;
  body
      PART_NAME='Q_RES';
      PHYS_DES_PREFIX='R';
      STANDARD='End of Design';
      LIFECYCLE='Comp-Approve';
      JEDEC_TYPE='R0402';
      ALT_SYMBOLS='(R0402-0201)';
      VALUE='150';
      TOL='1%';
      WATTAGE='1/16W';
      CLASS='DISCRETE';
      DESCRIPTION='RES CHIP 150 1/16W +-1%(0402)EF';
      COMPONENT_TYPE='CHIPR0402';
      LEAD_LENGTH='';
      DFM_EXCLUSION='';
      DAY='20180208';
      PARENT_PART_TYPE='Q_RES';
      PARENT_PPT='Q_RES';
      PARENT_PPT_PART='Q_RES_0402LF-150,1%,1/16W,CHIP,CS11502FB07';
  end_body;
end_primitive;
primitive 'Q_RES_0402LF-150K,1%,1/16W,CHIA';
  pin
    'A':
      PIN_GROUP='1';
      PIN_NUMBER='(1)';
      PIN_TYPE='UNSPEC';
      PINUSE='UNSPEC';
    'B':
      PIN_GROUP='1';
      PIN_NUMBER='(2)';
      PIN_TYPE='UNSPEC';
      PINUSE='UNSPEC';
  end_pin;
  body
      PART_NAME='Q_RES';
      PHYS_DES_PREFIX='R';
      STANDARD='End of Design';
      LIFECYCLE='Comp-Approve';
      JEDEC_TYPE='R0402';
      ALT_SYMBOLS='(R0402-0201)';
      VALUE='150K';
      TOL='1%';
      WATTAGE='1/16W';
      CLASS='DISCRETE';
      DESCRIPTION='RES CHIP 150K 1/16W +-1%(0402)EF';
      COMPONENT_TYPE='CHIPR0402';
      LEAD_LENGTH='';
      DFM_EXCLUSION='';
      DAY='20180221';
      PARENT_PART_TYPE='Q_RES';
      PARENT_PPT='Q_RES';
      PARENT_PPT_PART='Q_RES_0402LF-150K,1%,1/16W,CHIP,CS41502FB04';
  end_body;
end_primitive;
primitive 'Q_RES_0402LF-15K,0.1%,1/16W,CHA';
  pin
    'A':
      PIN_GROUP='1';
      PIN_NUMBER='(1)';
      PIN_TYPE='UNSPEC';
      PINUSE='UNSPEC';
    'B':
      PIN_GROUP='1';
      PIN_NUMBER='(2)';
      PIN_TYPE='UNSPEC';
      PINUSE='UNSPEC';
  end_pin;
  body
      PART_NAME='Q_RES';
      PHYS_DES_PREFIX='R';
      STANDARD='End of Design';
      LIFECYCLE='Comp-Approve';
      JEDEC_TYPE='R0402';
      ALT_SYMBOLS='(R0402-0201)';
      VALUE='15K';
      TOL='0.1%';
      WATTAGE='1/16W';
      CLASS='DISCRETE';
      DESCRIPTION='RES CHIP 15K  1/16W +-0.1%(0402)EF';
      COMPONENT_TYPE='CHIPR0402';
      LEAD_LENGTH='';
      DFM_EXCLUSION='';
      DAY='20180221';
      PARENT_PART_TYPE='Q_RES';
      PARENT_PPT='Q_RES';
      PARENT_PPT_PART='Q_RES_0402LF-15K,0.1%,1/16W,CHIP,CS31502BB03';
  end_body;
end_primitive;
primitive 'Q_RES_0402LF-15K,1%,1/16W,CHIPA';
  pin
    'A':
      PIN_GROUP='1';
      PIN_NUMBER='(1)';
      PIN_TYPE='UNSPEC';
      PINUSE='UNSPEC';
    'B':
      PIN_GROUP='1';
      PIN_NUMBER='(2)';
      PIN_TYPE='UNSPEC';
      PINUSE='UNSPEC';
  end_pin;
  body
      PART_NAME='Q_RES';
      PHYS_DES_PREFIX='R';
      STANDARD='End of Design';
      LIFECYCLE='Comp-Approve';
      JEDEC_TYPE='R0402';
      ALT_SYMBOLS='(R0402-0201)';
      VALUE='15K';
      TOL='1%';
      WATTAGE='1/16W';
      CLASS='DISCRETE';
      DESCRIPTION='RES CHIP 15K 1/16W +-1%(0402)EF';
      COMPONENT_TYPE='CHIPR0402';
      LEAD_LENGTH='';
      DFM_EXCLUSION='';
      DAY='20191227';
      PARENT_PART_TYPE='Q_RES';
      PARENT_PPT='Q_RES';
      PARENT_PPT_PART='Q_RES_0402LF-15K,1%,1/16W,CHIP,CS31502FB05';
  end_body;
end_primitive;
primitive 'Q_RES_0402LF-15K,1%,1/16W,EMPTA';
  pin
    'A':
      PIN_GROUP='1';
      PIN_NUMBER='(1)';
      PIN_TYPE='UNSPEC';
      PINUSE='UNSPEC';
    'B':
      PIN_GROUP='1';
      PIN_NUMBER='(2)';
      PIN_TYPE='UNSPEC';
      PINUSE='UNSPEC';
  end_pin;
  body
      PART_NAME='Q_RES';
      PHYS_DES_PREFIX='R';
      STANDARD='End of Design';
      LIFECYCLE='Comp-Approve';
      JEDEC_TYPE='R0402';
      ALT_SYMBOLS='(R0402-0201)';
      VALUE='15K';
      TOL='1%';
      WATTAGE='1/16W';
      CLASS='IO';
      DESCRIPTION='RES CHIP 15K 1/16W +-1%(0402)EF';
      COMPONENT_TYPE='CHIPR0402';
      LEAD_LENGTH='';
      DFM_EXCLUSION='';
      DAY='20191227';
      PARENT_PART_TYPE='Q_RES';
      PARENT_PPT='Q_RES';
      PARENT_PPT_PART='Q_RES_0402LF-15K,1%,1/16W,EMPTY,CS31502FB05';
  end_body;
end_primitive;
primitive 'Q_RES_0402LF-16.9K,1%,1/16W,CHA';
  pin
    'A':
      PIN_GROUP='1';
      PIN_NUMBER='(1)';
      PIN_TYPE='UNSPEC';
      PINUSE='UNSPEC';
    'B':
      PIN_GROUP='1';
      PIN_NUMBER='(2)';
      PIN_TYPE='UNSPEC';
      PINUSE='UNSPEC';
  end_pin;
  body
      PART_NAME='Q_RES';
      PHYS_DES_PREFIX='R';
      STANDARD='End of Design';
      LIFECYCLE='Comp-Approve';
      JEDEC_TYPE='R0402';
      ALT_SYMBOLS='(R0402-0201)';
      VALUE='16.9K';
      TOL='1%';
      WATTAGE='1/16W';
      CLASS='DISCRETE';
      DESCRIPTION='RES CHIP 16.9K 1/16W +-1%(0402)EF';
      COMPONENT_TYPE='CHIPR0402';
      LEAD_LENGTH='';
      DFM_EXCLUSION='';
      DAY='20200615';
      PARENT_PART_TYPE='Q_RES';
      PARENT_PPT='Q_RES';
      PARENT_PPT_PART='Q_RES_0402LF-16.9K,1%,1/16W,CHIP,CS31692FB03';
  end_body;
end_primitive;
primitive 'Q_RES_0402LF-160K,1%,1/16W,EMPA';
  pin
    'A':
      PIN_GROUP='1';
      PIN_NUMBER='(1)';
      PIN_TYPE='UNSPEC';
      PINUSE='UNSPEC';
    'B':
      PIN_GROUP='1';
      PIN_NUMBER='(2)';
      PIN_TYPE='UNSPEC';
      PINUSE='UNSPEC';
  end_pin;
  body
      PART_NAME='Q_RES';
      PHYS_DES_PREFIX='R';
      STANDARD='';
      LIFECYCLE='';
      JEDEC_TYPE='R0402';
      ALT_SYMBOLS='(R0402-0201)';
      VALUE='160K';
      TOL='1%';
      WATTAGE='1/16W';
      CLASS='IO';
      DESCRIPTION='RES CHIP 160K 1/16W+-1%(0402)EF';
      COMPONENT_TYPE='CHIPR0402';
      LEAD_LENGTH='';
      DFM_EXCLUSION='';
      DAY='20191113';
      PARENT_PART_TYPE='Q_RES';
      PARENT_PPT='Q_RES';
      PARENT_PPT_PART='Q_RES_0402LF-160K,1%,1/16W,EMPTY,CS41602FB05';
  end_body;
end_primitive;
primitive 'Q_RES_0402LF-17.4K,1%,1/16W,CHA';
  pin
    'A':
      PIN_GROUP='1';
      PIN_NUMBER='(1)';
      PIN_TYPE='UNSPEC';
      PINUSE='UNSPEC';
    'B':
      PIN_GROUP='1';
      PIN_NUMBER='(2)';
      PIN_TYPE='UNSPEC';
      PINUSE='UNSPEC';
  end_pin;
  body
      PART_NAME='Q_RES';
      PHYS_DES_PREFIX='R';
      STANDARD='End of Design';
      LIFECYCLE='Comp-Approve';
      JEDEC_TYPE='R0402';
      ALT_SYMBOLS='(R0402-0201)';
      VALUE='17.4K';
      TOL='1%';
      WATTAGE='1/16W';
      CLASS='DISCRETE';
      DESCRIPTION='RES CHIP 17.4K 1/16W +-1%(0402)EF';
      COMPONENT_TYPE='CHIPR0402';
      LEAD_LENGTH='';
      DFM_EXCLUSION='';
      DAY='20190826';
      PARENT_PART_TYPE='Q_RES';
      PARENT_PPT='Q_RES';
      PARENT_PPT_PART='Q_RES_0402LF-17.4K,1%,1/16W,CHIP,CS31742FB04';
  end_body;
end_primitive;
primitive 'Q_RES_0402LF-17.8K,1%,1/16W,EMA';
  pin
    'A':
      PIN_GROUP='1';
      PIN_NUMBER='(1)';
      PIN_TYPE='UNSPEC';
      PINUSE='UNSPEC';
    'B':
      PIN_GROUP='1';
      PIN_NUMBER='(2)';
      PIN_TYPE='UNSPEC';
      PINUSE='UNSPEC';
  end_pin;
  body
      PART_NAME='Q_RES';
      PHYS_DES_PREFIX='R';
      STANDARD='End of Design';
      LIFECYCLE='Comp-Approve';
      JEDEC_TYPE='R0402';
      ALT_SYMBOLS='(R0402-0201)';
      VALUE='17.8K';
      TOL='1%';
      WATTAGE='1/16W';
      CLASS='IO';
      DESCRIPTION='RES CHIP 17.8K 1/16W +- 1% (0402)EF';
      COMPONENT_TYPE='CHIPR0402';
      LEAD_LENGTH='';
      DFM_EXCLUSION='';
      DAY='20190730';
      PARENT_PART_TYPE='Q_RES';
      PARENT_PPT='Q_RES';
      PARENT_PPT_PART='Q_RES_0402LF-17.8K,1%,1/16W,EMPTY,CS31782FB04';
  end_body;
end_primitive;
primitive 'Q_RES_0402LF-18K,1%,1/16W,CHIPA';
  pin
    'A':
      PIN_GROUP='1';
      PIN_NUMBER='(1)';
      PIN_TYPE='UNSPEC';
      PINUSE='UNSPEC';
    'B':
      PIN_GROUP='1';
      PIN_NUMBER='(2)';
      PIN_TYPE='UNSPEC';
      PINUSE='UNSPEC';
  end_pin;
  body
      PART_NAME='Q_RES';
      PHYS_DES_PREFIX='R';
      STANDARD='';
      LIFECYCLE='';
      JEDEC_TYPE='R0402';
      ALT_SYMBOLS='(R0402-0201)';
      VALUE='18K';
      TOL='1%';
      WATTAGE='1/16W';
      CLASS='DISCRETE';
      DESCRIPTION='RES CHIP 18K 1/16W +-1%(0402)EF';
      COMPONENT_TYPE='CHIPR0402';
      LEAD_LENGTH='';
      DFM_EXCLUSION='';
      DAY='20210719';
      PARENT_PART_TYPE='Q_RES';
      PARENT_PPT='Q_RES';
      PARENT_PPT_PART='Q_RES_0402LF-18K,1%,1/16W,CHIP,CS31802FB04';
  end_body;
end_primitive;
primitive 'Q_RES_0402LF-196K,1%,1/16W,CHIA';
  pin
    'A':
      PIN_GROUP='1';
      PIN_NUMBER='(1)';
      PIN_TYPE='UNSPEC';
      PINUSE='UNSPEC';
    'B':
      PIN_GROUP='1';
      PIN_NUMBER='(2)';
      PIN_TYPE='UNSPEC';
      PINUSE='UNSPEC';
  end_pin;
  body
      PART_NAME='Q_RES';
      PHYS_DES_PREFIX='R';
      STANDARD='End of Design';
      LIFECYCLE='Comp-Approve';
      JEDEC_TYPE='R0402';
      ALT_SYMBOLS='(R0402-0201)';
      VALUE='196K';
      TOL='1%';
      WATTAGE='1/16W';
      CLASS='DISCRETE';
      DESCRIPTION='RES CHIP 196K 1/16W +-1%(0402)EF';
      COMPONENT_TYPE='CHIPR0402';
      LEAD_LENGTH='';
      DFM_EXCLUSION='';
      DAY='20210715';
      PARENT_PART_TYPE='Q_RES';
      PARENT_PPT='Q_RES';
      PARENT_PPT_PART='Q_RES_0402LF-196K,1%,1/16W,CHIP,CS41962FB03';
  end_body;
end_primitive;
primitive 'Q_RES_0402LF-1K,1%,1/16W,CHIP,A';
  pin
    'A':
      PIN_GROUP='1';
      PIN_NUMBER='(1)';
      PIN_TYPE='UNSPEC';
      PINUSE='UNSPEC';
    'B':
      PIN_GROUP='1';
      PIN_NUMBER='(2)';
      PIN_TYPE='UNSPEC';
      PINUSE='UNSPEC';
  end_pin;
  body
      PART_NAME='Q_RES';
      PHYS_DES_PREFIX='R';
      STANDARD='End of Design';
      LIFECYCLE='Comp-Approve';
      JEDEC_TYPE='R0402';
      ALT_SYMBOLS='(R0402-0201)';
      VALUE='1K';
      TOL='1%';
      WATTAGE='1/16W';
      CLASS='DISCRETE';
      DESCRIPTION='RES CHIP 1K 1/16W +-1%(0402)EF';
      COMPONENT_TYPE='CHIPR0402';
      LEAD_LENGTH='';
      DFM_EXCLUSION='';
      DAY='20180208';
      PARENT_PART_TYPE='Q_RES';
      PARENT_PPT='Q_RES';
      PARENT_PPT_PART='Q_RES_0402LF-1K,1%,1/16W,CHIP,CS21002FB06';
  end_body;
end_primitive;
primitive 'Q_RES_0402LF-1K,1%,1/16W,EMPTYA';
  pin
    'A':
      PIN_GROUP='1';
      PIN_NUMBER='(1)';
      PIN_TYPE='UNSPEC';
      PINUSE='UNSPEC';
    'B':
      PIN_GROUP='1';
      PIN_NUMBER='(2)';
      PIN_TYPE='UNSPEC';
      PINUSE='UNSPEC';
  end_pin;
  body
      PART_NAME='Q_RES';
      PHYS_DES_PREFIX='R';
      STANDARD='End of Design';
      LIFECYCLE='Comp-Approve';
      JEDEC_TYPE='R0402';
      ALT_SYMBOLS='(R0402-0201)';
      VALUE='1K';
      TOL='1%';
      WATTAGE='1/16W';
      CLASS='IO';
      DESCRIPTION='RES CHIP 1K 1/16W +-1%(0402)EF';
      COMPONENT_TYPE='CHIPR0402';
      LEAD_LENGTH='';
      DFM_EXCLUSION='';
      DAY='20180208';
      PARENT_PART_TYPE='Q_RES';
      PARENT_PPT='Q_RES';
      PARENT_PPT_PART='Q_RES_0402LF-1K,1%,1/16W,EMPTY,CS21002FB06';
  end_body;
end_primitive;
primitive 'Q_RES_0402LF-1M,1%,1/16W,CHIP,A';
  pin
    'A':
      PIN_GROUP='1';
      PIN_NUMBER='(1)';
      PIN_TYPE='UNSPEC';
      PINUSE='UNSPEC';
    'B':
      PIN_GROUP='1';
      PIN_NUMBER='(2)';
      PIN_TYPE='UNSPEC';
      PINUSE='UNSPEC';
  end_pin;
  body
      PART_NAME='Q_RES';
      PHYS_DES_PREFIX='R';
      STANDARD='End of Design';
      LIFECYCLE='Comp-Approve';
      JEDEC_TYPE='R0402';
      ALT_SYMBOLS='(R0402-0201)';
      VALUE='1M';
      TOL='1%';
      WATTAGE='1/16W';
      CLASS='DISCRETE';
      DESCRIPTION='RES CHIP 1M 1/16W +-1%(0402)EF';
      COMPONENT_TYPE='CHIPR0402';
      LEAD_LENGTH='';
      DFM_EXCLUSION='';
      DAY='20180221';
      PARENT_PART_TYPE='Q_RES';
      PARENT_PPT='Q_RES';
      PARENT_PPT_PART='Q_RES_0402LF-1M,1%,1/16W,CHIP,CS51002FB05';
  end_body;
end_primitive;
primitive 'Q_RES_0402LF-1M,1%,1/16W,EMPTYA';
  pin
    'A':
      PIN_GROUP='1';
      PIN_NUMBER='(1)';
      PIN_TYPE='UNSPEC';
      PINUSE='UNSPEC';
    'B':
      PIN_GROUP='1';
      PIN_NUMBER='(2)';
      PIN_TYPE='UNSPEC';
      PINUSE='UNSPEC';
  end_pin;
  body
      PART_NAME='Q_RES';
      PHYS_DES_PREFIX='R';
      STANDARD='End of Design';
      LIFECYCLE='Comp-Approve';
      JEDEC_TYPE='R0402';
      ALT_SYMBOLS='(R0402-0201)';
      VALUE='1M';
      TOL='1%';
      WATTAGE='1/16W';
      CLASS='IO';
      DESCRIPTION='RES CHIP 1M 1/16W +-1%(0402)EF';
      COMPONENT_TYPE='CHIPR0402';
      LEAD_LENGTH='';
      DFM_EXCLUSION='';
      DAY='20180221';
      PARENT_PART_TYPE='Q_RES';
      PARENT_PPT='Q_RES';
      PARENT_PPT_PART='Q_RES_0402LF-1M,1%,1/16W,EMPTY,CS51002FB05';
  end_body;
end_primitive;
primitive 'Q_RES_0402LF-2.2,1%,1/16W,CHIPA';
  pin
    'A':
      PIN_GROUP='1';
      PIN_NUMBER='(1)';
      PIN_TYPE='UNSPEC';
      PINUSE='UNSPEC';
    'B':
      PIN_GROUP='1';
      PIN_NUMBER='(2)';
      PIN_TYPE='UNSPEC';
      PINUSE='UNSPEC';
  end_pin;
  body
      PART_NAME='Q_RES';
      PHYS_DES_PREFIX='R';
      STANDARD='End of Design';
      LIFECYCLE='Comp-Approve';
      JEDEC_TYPE='R0402';
      ALT_SYMBOLS='(R0402-0201)';
      VALUE='2.2';
      TOL='1%';
      WATTAGE='1/16W';
      CLASS='DISCRETE';
      DESCRIPTION='RES CHIP 2.2 1/16W +-1%(0402)EF';
      COMPONENT_TYPE='CHIP0402';
      LEAD_LENGTH='';
      DFM_EXCLUSION='';
      DAY='20180212';
      PARENT_PART_TYPE='Q_RES';
      PARENT_PPT='Q_RES';
      PARENT_PPT_PART='Q_RES_0402LF-2.2,1%,1/16W,CHIP,CS-2202FB01';
  end_body;
end_primitive;
primitive 'Q_RES_0402LF-2.21K,1%,1/16W,EMA';
  pin
    'A':
      PIN_GROUP='1';
      PIN_NUMBER='(1)';
      PIN_TYPE='UNSPEC';
      PINUSE='UNSPEC';
    'B':
      PIN_GROUP='1';
      PIN_NUMBER='(2)';
      PIN_TYPE='UNSPEC';
      PINUSE='UNSPEC';
  end_pin;
  body
      PART_NAME='Q_RES';
      PHYS_DES_PREFIX='R';
      STANDARD='End of Design';
      LIFECYCLE='Comp-Approve';
      JEDEC_TYPE='R0402';
      ALT_SYMBOLS='(R0402-0201)';
      VALUE='2.21K';
      TOL='1%';
      WATTAGE='1/16W';
      CLASS='IO';
      DESCRIPTION='RES CHIP 2.21K 1/16W +-1%(0402)EF';
      COMPONENT_TYPE='CHIPR0402';
      LEAD_LENGTH='';
      DFM_EXCLUSION='';
      DAY='20180221';
      PARENT_PART_TYPE='Q_RES';
      PARENT_PPT='Q_RES';
      PARENT_PPT_PART='Q_RES_0402LF-2.21K,1%,1/16W,EMPTY,CS22212FB06';
  end_body;
end_primitive;
primitive 'Q_RES_0402LF-2.2K,5%,1/16W,CHIA';
  pin
    'A':
      PIN_GROUP='1';
      PIN_NUMBER='(1)';
      PIN_TYPE='UNSPEC';
      PINUSE='UNSPEC';
    'B':
      PIN_GROUP='1';
      PIN_NUMBER='(2)';
      PIN_TYPE='UNSPEC';
      PINUSE='UNSPEC';
  end_pin;
  body
      PART_NAME='Q_RES';
      PHYS_DES_PREFIX='R';
      STANDARD='End of Design';
      LIFECYCLE='Comp-Approve';
      JEDEC_TYPE='R0402';
      ALT_SYMBOLS='(R0402-0201)';
      VALUE='2.2K';
      TOL='5%';
      WATTAGE='1/16W';
      CLASS='DISCRETE';
      DESCRIPTION='RES CHIP 2.2K 1/16W +-5%(0402)EF';
      COMPONENT_TYPE='CHIP0402';
      LEAD_LENGTH='';
      DFM_EXCLUSION='';
      DAY='20180212';
      PARENT_PART_TYPE='Q_RES';
      PARENT_PPT='Q_RES';
      PARENT_PPT_PART='Q_RES_0402LF-2.2K,5%,1/16W,CHIP,CS22202JB07';
  end_body;
end_primitive;
primitive 'Q_RES_0402LF-2.2K,5%,1/16W,EMPA';
  pin
    'A':
      PIN_GROUP='1';
      PIN_NUMBER='(1)';
      PIN_TYPE='UNSPEC';
      PINUSE='UNSPEC';
    'B':
      PIN_GROUP='1';
      PIN_NUMBER='(2)';
      PIN_TYPE='UNSPEC';
      PINUSE='UNSPEC';
  end_pin;
  body
      PART_NAME='Q_RES';
      PHYS_DES_PREFIX='R';
      STANDARD='End of Design';
      LIFECYCLE='Comp-Approve';
      JEDEC_TYPE='R0402';
      ALT_SYMBOLS='(R0402-0201)';
      VALUE='2.2K';
      TOL='5%';
      WATTAGE='1/16W';
      CLASS='IO';
      DESCRIPTION='RES CHIP 2.2K 1/16W +-5%(0402)EF';
      COMPONENT_TYPE='CHIP0402';
      LEAD_LENGTH='';
      DFM_EXCLUSION='';
      DAY='20180212';
      PARENT_PART_TYPE='Q_RES';
      PARENT_PPT='Q_RES';
      PARENT_PPT_PART='Q_RES_0402LF-2.2K,5%,1/16W,EMPTY,CS22202JB07';
  end_body;
end_primitive;
primitive 'Q_RES_0402LF-2.49K,1%,1/16W,CHA';
  pin
    'A':
      PIN_GROUP='1';
      PIN_NUMBER='(1)';
      PIN_TYPE='UNSPEC';
      PINUSE='UNSPEC';
    'B':
      PIN_GROUP='1';
      PIN_NUMBER='(2)';
      PIN_TYPE='UNSPEC';
      PINUSE='UNSPEC';
  end_pin;
  body
      PART_NAME='Q_RES';
      PHYS_DES_PREFIX='R';
      STANDARD='End of Design';
      LIFECYCLE='Comp-Approve';
      JEDEC_TYPE='R0402';
      ALT_SYMBOLS='(R0402-0201)';
      VALUE='2.49K';
      TOL='1%';
      WATTAGE='1/16W';
      CLASS='DISCRETE';
      DESCRIPTION='RES CHIP 2.49K 1/16W +-1%(0402)EF';
      COMPONENT_TYPE='CHIPR0402';
      LEAD_LENGTH='';
      DFM_EXCLUSION='';
      DAY='20180221';
      PARENT_PART_TYPE='Q_RES';
      PARENT_PPT='Q_RES';
      PARENT_PPT_PART='Q_RES_0402LF-2.49K,1%,1/16W,CHIP,CS22492FB05';
  end_body;
end_primitive;
primitive 'Q_RES_0402LF-2.67K,1%,1/16W,EMA';
  pin
    'A':
      PIN_GROUP='1';
      PIN_NUMBER='(1)';
      PIN_TYPE='UNSPEC';
      PINUSE='UNSPEC';
    'B':
      PIN_GROUP='1';
      PIN_NUMBER='(2)';
      PIN_TYPE='UNSPEC';
      PINUSE='UNSPEC';
  end_pin;
  body
      PART_NAME='Q_RES';
      PHYS_DES_PREFIX='R';
      STANDARD='End of Design';
      LIFECYCLE='Comp-Approve';
      JEDEC_TYPE='R0402';
      ALT_SYMBOLS='(R0402-0201)';
      VALUE='2.67K';
      TOL='1%';
      WATTAGE='1/16W';
      CLASS='IO';
      DESCRIPTION='RES CHIP 2.67K 1/16W +-1%(0402)EF';
      COMPONENT_TYPE='CHIPR0402';
      LEAD_LENGTH='';
      DFM_EXCLUSION='';
      DAY='20190905';
      PARENT_PART_TYPE='Q_RES';
      PARENT_PPT='Q_RES';
      PARENT_PPT_PART='Q_RES_0402LF-2.67K,1%,1/16W,EMPTY,CS22672FB03';
  end_body;
end_primitive;
primitive 'Q_RES_0402LF-2.8K,1%,1/16W,EMPA';
  pin
    'A':
      PIN_GROUP='1';
      PIN_NUMBER='(1)';
      PIN_TYPE='UNSPEC';
      PINUSE='UNSPEC';
    'B':
      PIN_GROUP='1';
      PIN_NUMBER='(2)';
      PIN_TYPE='UNSPEC';
      PINUSE='UNSPEC';
  end_pin;
  body
      PART_NAME='Q_RES';
      PHYS_DES_PREFIX='R';
      STANDARD='End of Design';
      LIFECYCLE='Comp-Approve';
      JEDEC_TYPE='R0402';
      ALT_SYMBOLS='(R0402-0201)';
      VALUE='2.8K';
      TOL='1%';
      WATTAGE='1/16W';
      CLASS='IO';
      DESCRIPTION='RES CHIP 2.8K 1/16W +-1%(0402)EF';
      COMPONENT_TYPE='CHIPR0402';
      LEAD_LENGTH='';
      DFM_EXCLUSION='';
      DAY='20211222';
      PARENT_PART_TYPE='Q_RES';
      PARENT_PPT='Q_RES';
      PARENT_PPT_PART='Q_RES_0402LF-2.8K,1%,1/16W,EMPTY,CS22802FB04';
  end_body;
end_primitive;
primitive 'Q_RES_0402LF-200,1%,1/16W,CHIPA';
  pin
    'A':
      PIN_GROUP='1';
      PIN_NUMBER='(1)';
      PIN_TYPE='UNSPEC';
      PINUSE='UNSPEC';
    'B':
      PIN_GROUP='1';
      PIN_NUMBER='(2)';
      PIN_TYPE='UNSPEC';
      PINUSE='UNSPEC';
  end_pin;
  body
      PART_NAME='Q_RES';
      PHYS_DES_PREFIX='R';
      STANDARD='End of Design';
      LIFECYCLE='Comp-Approve';
      JEDEC_TYPE='R0402';
      ALT_SYMBOLS='(R0402-0201)';
      VALUE='200';
      TOL='1%';
      WATTAGE='1/16W';
      CLASS='DISCRETE';
      DESCRIPTION='RES CHIP 200 1/16W +-1%(0402)EF';
      COMPONENT_TYPE='CHIPR0402';
      LEAD_LENGTH='';
      DFM_EXCLUSION='';
      DAY='20180208';
      PARENT_PART_TYPE='Q_RES';
      PARENT_PPT='Q_RES';
      PARENT_PPT_PART='Q_RES_0402LF-200,1%,1/16W,CHIP,CS12002FB06';
  end_body;
end_primitive;
primitive 'Q_RES_0402LF-200,1%,1/16W,EMPTA';
  pin
    'A':
      PIN_GROUP='1';
      PIN_NUMBER='(1)';
      PIN_TYPE='UNSPEC';
      PINUSE='UNSPEC';
    'B':
      PIN_GROUP='1';
      PIN_NUMBER='(2)';
      PIN_TYPE='UNSPEC';
      PINUSE='UNSPEC';
  end_pin;
  body
      PART_NAME='Q_RES';
      PHYS_DES_PREFIX='R';
      STANDARD='End of Design';
      LIFECYCLE='Comp-Approve';
      JEDEC_TYPE='R0402';
      ALT_SYMBOLS='(R0402-0201)';
      VALUE='200';
      TOL='1%';
      WATTAGE='1/16W';
      CLASS='IO';
      DESCRIPTION='RES CHIP 200 1/16W +-1%(0402)EF';
      COMPONENT_TYPE='CHIPR0402';
      LEAD_LENGTH='';
      DFM_EXCLUSION='';
      DAY='20180208';
      PARENT_PART_TYPE='Q_RES';
      PARENT_PPT='Q_RES';
      PARENT_PPT_PART='Q_RES_0402LF-200,1%,1/16W,EMPTY,CS12002FB06';
  end_body;
end_primitive;
primitive 'Q_RES_0402LF-200K,1%,1/16W,CHIA';
  pin
    'A':
      PIN_GROUP='1';
      PIN_NUMBER='(1)';
      PIN_TYPE='UNSPEC';
      PINUSE='UNSPEC';
    'B':
      PIN_GROUP='1';
      PIN_NUMBER='(2)';
      PIN_TYPE='UNSPEC';
      PINUSE='UNSPEC';
  end_pin;
  body
      PART_NAME='Q_RES';
      PHYS_DES_PREFIX='R';
      STANDARD='End of Design';
      LIFECYCLE='Comp-Approve';
      JEDEC_TYPE='R0402';
      ALT_SYMBOLS='(R0402-0201)';
      VALUE='200K';
      TOL='1%';
      WATTAGE='1/16W';
      CLASS='DISCRETE';
      DESCRIPTION='RES CHIP 200K 1/16W +-1%(0402)EF';
      COMPONENT_TYPE='CHIPR0402';
      LEAD_LENGTH='';
      DFM_EXCLUSION='';
      DAY='20180208';
      PARENT_PART_TYPE='Q_RES';
      PARENT_PPT='Q_RES';
      PARENT_PPT_PART='Q_RES_0402LF-200K,1%,1/16W,CHIP,CS42002FB05';
  end_body;
end_primitive;
primitive 'Q_RES_0402LF-200K,1%,1/16W,EMPA';
  pin
    'A':
      PIN_GROUP='1';
      PIN_NUMBER='(1)';
      PIN_TYPE='UNSPEC';
      PINUSE='UNSPEC';
    'B':
      PIN_GROUP='1';
      PIN_NUMBER='(2)';
      PIN_TYPE='UNSPEC';
      PINUSE='UNSPEC';
  end_pin;
  body
      PART_NAME='Q_RES';
      PHYS_DES_PREFIX='R';
      STANDARD='End of Design';
      LIFECYCLE='Comp-Approve';
      JEDEC_TYPE='R0402';
      ALT_SYMBOLS='(R0402-0201)';
      VALUE='200K';
      TOL='1%';
      WATTAGE='1/16W';
      CLASS='IO';
      DESCRIPTION='RES CHIP 200K 1/16W +-1%(0402)EF';
      COMPONENT_TYPE='CHIPR0402';
      LEAD_LENGTH='';
      DFM_EXCLUSION='';
      DAY='20180208';
      PARENT_PART_TYPE='Q_RES';
      PARENT_PPT='Q_RES';
      PARENT_PPT_PART='Q_RES_0402LF-200K,1%,1/16W,EMPTY,CS42002FB05';
  end_body;
end_primitive;
primitive 'Q_RES_0402LF-20K,1%,1/16W,CHIPA';
  pin
    'A':
      PIN_GROUP='1';
      PIN_NUMBER='(1)';
      PIN_TYPE='UNSPEC';
      PINUSE='UNSPEC';
    'B':
      PIN_GROUP='1';
      PIN_NUMBER='(2)';
      PIN_TYPE='UNSPEC';
      PINUSE='UNSPEC';
  end_pin;
  body
      PART_NAME='Q_RES';
      PHYS_DES_PREFIX='R';
      STANDARD='End of Design';
      LIFECYCLE='Comp-Approve';
      JEDEC_TYPE='R0402';
      ALT_SYMBOLS='(R0402-0201)';
      VALUE='20K';
      TOL='1%';
      WATTAGE='1/16W';
      CLASS='DISCRETE';
      DESCRIPTION='RES CHIP 20K 1/16W +-1%(0402)EF';
      COMPONENT_TYPE='CHIPR0402';
      LEAD_LENGTH='';
      DFM_EXCLUSION='';
      DAY='20180208';
      PARENT_PART_TYPE='Q_RES';
      PARENT_PPT='Q_RES';
      PARENT_PPT_PART='Q_RES_0402LF-20K,1%,1/16W,CHIP,CS32002FB06';
  end_body;
end_primitive;
primitive 'Q_RES_0402LF-20K,1%,1/16W,EMPTA';
  pin
    'A':
      PIN_GROUP='1';
      PIN_NUMBER='(1)';
      PIN_TYPE='UNSPEC';
      PINUSE='UNSPEC';
    'B':
      PIN_GROUP='1';
      PIN_NUMBER='(2)';
      PIN_TYPE='UNSPEC';
      PINUSE='UNSPEC';
  end_pin;
  body
      PART_NAME='Q_RES';
      PHYS_DES_PREFIX='R';
      STANDARD='End of Design';
      LIFECYCLE='Comp-Approve';
      JEDEC_TYPE='R0402';
      ALT_SYMBOLS='(R0402-0201)';
      VALUE='20K';
      TOL='1%';
      WATTAGE='1/16W';
      CLASS='IO';
      DESCRIPTION='RES CHIP 20K 1/16W +-1%(0402)EF';
      COMPONENT_TYPE='CHIPR0402';
      LEAD_LENGTH='';
      DFM_EXCLUSION='';
      DAY='20180208';
      PARENT_PART_TYPE='Q_RES';
      PARENT_PPT='Q_RES';
      PARENT_PPT_PART='Q_RES_0402LF-20K,1%,1/16W,EMPTY,CS32002FB06';
  end_body;
end_primitive;
primitive 'Q_RES_0402LF-21.5K,1%,1/16W,CHA';
  pin
    'A':
      PIN_GROUP='1';
      PIN_NUMBER='(1)';
      PIN_TYPE='UNSPEC';
      PINUSE='UNSPEC';
    'B':
      PIN_GROUP='1';
      PIN_NUMBER='(2)';
      PIN_TYPE='UNSPEC';
      PINUSE='UNSPEC';
  end_pin;
  body
      PART_NAME='Q_RES';
      PHYS_DES_PREFIX='R';
      STANDARD='';
      LIFECYCLE='';
      JEDEC_TYPE='R0402';
      ALT_SYMBOLS='(R0402-0201)';
      VALUE='21.5K';
      TOL='1%';
      WATTAGE='1/16W';
      CLASS='DISCRETE';
      DESCRIPTION='RES CHIP 21.5K 1/16W +-1%(0402)EF';
      COMPONENT_TYPE='CHIPR0402';
      LEAD_LENGTH='';
      DFM_EXCLUSION='';
      DAY='20200302';
      PARENT_PART_TYPE='Q_RES';
      PARENT_PPT='Q_RES';
      PARENT_PPT_PART='Q_RES_0402LF-21.5K,1%,1/16W,CHIP,CS32152FB04';
  end_body;
end_primitive;
primitive 'Q_RES_0402LF-22,1%,1/16W,CHIP,A';
  pin
    'A':
      PIN_GROUP='1';
      PIN_NUMBER='(1)';
      PIN_TYPE='UNSPEC';
      PINUSE='UNSPEC';
    'B':
      PIN_GROUP='1';
      PIN_NUMBER='(2)';
      PIN_TYPE='UNSPEC';
      PINUSE='UNSPEC';
  end_pin;
  body
      PART_NAME='Q_RES';
      PHYS_DES_PREFIX='R';
      STANDARD='End of Design';
      LIFECYCLE='Comp-Approve';
      JEDEC_TYPE='R0402';
      ALT_SYMBOLS='(R0402-0201)';
      VALUE='22';
      TOL='1%';
      WATTAGE='1/16W';
      CLASS='DISCRETE';
      DESCRIPTION='RES CHIP 22 1/16W +-1%(0402)EF';
      COMPONENT_TYPE='CHIP0402';
      LEAD_LENGTH='';
      DFM_EXCLUSION='';
      DAY='20180212';
      PARENT_PART_TYPE='Q_RES';
      PARENT_PPT='Q_RES';
      PARENT_PPT_PART='Q_RES_0402LF-22,1%,1/16W,CHIP,CS02202FB02';
  end_body;
end_primitive;
primitive 'Q_RES_0402LF-22,1%,1/16W,EMPTYA';
  pin
    'A':
      PIN_GROUP='1';
      PIN_NUMBER='(1)';
      PIN_TYPE='UNSPEC';
      PINUSE='UNSPEC';
    'B':
      PIN_GROUP='1';
      PIN_NUMBER='(2)';
      PIN_TYPE='UNSPEC';
      PINUSE='UNSPEC';
  end_pin;
  body
      PART_NAME='Q_RES';
      PHYS_DES_PREFIX='R';
      STANDARD='End of Design';
      LIFECYCLE='Comp-Approve';
      JEDEC_TYPE='R0402';
      ALT_SYMBOLS='(R0402-0201)';
      VALUE='22';
      TOL='1%';
      WATTAGE='1/16W';
      CLASS='IO';
      DESCRIPTION='RES CHIP 22 1/16W +-1%(0402)EF';
      COMPONENT_TYPE='CHIP0402';
      LEAD_LENGTH='';
      DFM_EXCLUSION='';
      DAY='20180212';
      PARENT_PART_TYPE='Q_RES';
      PARENT_PPT='Q_RES';
      PARENT_PPT_PART='Q_RES_0402LF-22,1%,1/16W,EMPTY,CS02202FB02';
  end_body;
end_primitive;
primitive 'Q_RES_0402LF-22,5%,1/16W,CHIP,A';
  pin
    'A':
      PIN_GROUP='1';
      PIN_NUMBER='(1)';
      PIN_TYPE='UNSPEC';
      PINUSE='UNSPEC';
    'B':
      PIN_GROUP='1';
      PIN_NUMBER='(2)';
      PIN_TYPE='UNSPEC';
      PINUSE='UNSPEC';
  end_pin;
  body
      PART_NAME='Q_RES';
      PHYS_DES_PREFIX='R';
      STANDARD='End of Design';
      LIFECYCLE='Comp-Approve';
      JEDEC_TYPE='R0402';
      ALT_SYMBOLS='(R0402-0201)';
      VALUE='22';
      TOL='5%';
      WATTAGE='1/16W';
      CLASS='DISCRETE';
      DESCRIPTION='RES CHIP 22 1/16W +-5%(0402)EF';
      COMPONENT_TYPE='CHIP0402';
      LEAD_LENGTH='';
      DFM_EXCLUSION='';
      DAY='20180212';
      PARENT_PART_TYPE='Q_RES';
      PARENT_PPT='Q_RES';
      PARENT_PPT_PART='Q_RES_0402LF-22,5%,1/16W,CHIP,CS02202JB09';
  end_body;
end_primitive;
primitive 'Q_RES_0402LF-22.6K,1%,1/16W,CHA';
  pin
    'A':
      PIN_GROUP='1';
      PIN_NUMBER='(1)';
      PIN_TYPE='UNSPEC';
      PINUSE='UNSPEC';
    'B':
      PIN_GROUP='1';
      PIN_NUMBER='(2)';
      PIN_TYPE='UNSPEC';
      PINUSE='UNSPEC';
  end_pin;
  body
      PART_NAME='Q_RES';
      PHYS_DES_PREFIX='R';
      STANDARD='End of Design';
      LIFECYCLE='Comp-Approve';
      JEDEC_TYPE='R0402';
      ALT_SYMBOLS='(R0402-0201)';
      VALUE='22.6K';
      TOL='1%';
      WATTAGE='1/16W';
      CLASS='DISCRETE';
      DESCRIPTION='RES CHIP 22.6K 1/16W +-1%(0402)EF';
      COMPONENT_TYPE='CHIPR0402';
      LEAD_LENGTH='';
      DFM_EXCLUSION='';
      DAY='20190718';
      PARENT_PART_TYPE='Q_RES';
      PARENT_PPT='Q_RES';
      PARENT_PPT_PART='Q_RES_0402LF-22.6K,1%,1/16W,CHIP,CS32262FB02';
  end_body;
end_primitive;
primitive 'Q_RES_0402LF-23.2K,1%,1/16W,CHA';
  pin
    'A':
      PIN_GROUP='1';
      PIN_NUMBER='(1)';
      PIN_TYPE='UNSPEC';
      PINUSE='UNSPEC';
    'B':
      PIN_GROUP='1';
      PIN_NUMBER='(2)';
      PIN_TYPE='UNSPEC';
      PINUSE='UNSPEC';
  end_pin;
  body
      PART_NAME='Q_RES';
      PHYS_DES_PREFIX='R';
      STANDARD='End of Design';
      LIFECYCLE='Comp-Approve';
      JEDEC_TYPE='R0402';
      ALT_SYMBOLS='(R0402-0201)';
      VALUE='23.2K';
      TOL='1%';
      WATTAGE='1/16W';
      CLASS='DISCRETE';
      DESCRIPTION='RES CHIP 23.2K 1/16W +-1%(0402)EF';
      COMPONENT_TYPE='CHIPR0402';
      LEAD_LENGTH='';
      DFM_EXCLUSION='';
      DAY='20210720';
      PARENT_PART_TYPE='Q_RES';
      PARENT_PPT='Q_RES';
      PARENT_PPT_PART='Q_RES_0402LF-23.2K,1%,1/16W,CHIP,CS32322FB03';
  end_body;
end_primitive;
primitive 'Q_RES_0402LF-24.3K,1%,1/16W,CHA';
  pin
    'A':
      PIN_GROUP='1';
      PIN_NUMBER='(1)';
      PIN_TYPE='UNSPEC';
      PINUSE='UNSPEC';
    'B':
      PIN_GROUP='1';
      PIN_NUMBER='(2)';
      PIN_TYPE='UNSPEC';
      PINUSE='UNSPEC';
  end_pin;
  body
      PART_NAME='Q_RES';
      PHYS_DES_PREFIX='R';
      STANDARD='';
      LIFECYCLE='';
      JEDEC_TYPE='R0402';
      ALT_SYMBOLS='(R0402-0201)';
      VALUE='24.3K';
      TOL='1%';
      WATTAGE='1/16W';
      CLASS='DISCRETE';
      DESCRIPTION='RES CHIP 24.3K 1/16W +-1%(0402)EF';
      COMPONENT_TYPE='CHIPR0402';
      LEAD_LENGTH='';
      DFM_EXCLUSION='';
      DAY='20190717';
      PARENT_PART_TYPE='Q_RES';
      PARENT_PPT='Q_RES';
      PARENT_PPT_PART='Q_RES_0402LF-24.3K,1%,1/16W,CHIP,CS32432FB03';
  end_body;
end_primitive;
primitive 'Q_RES_0402LF-240,1%,1/16W,CHIPA';
  pin
    'A':
      PIN_GROUP='1';
      PIN_NUMBER='(1)';
      PIN_TYPE='UNSPEC';
      PINUSE='UNSPEC';
    'B':
      PIN_GROUP='1';
      PIN_NUMBER='(2)';
      PIN_TYPE='UNSPEC';
      PINUSE='UNSPEC';
  end_pin;
  body
      PART_NAME='Q_RES';
      PHYS_DES_PREFIX='R';
      STANDARD='End of Design';
      LIFECYCLE='Comp-Approve';
      JEDEC_TYPE='R0402';
      ALT_SYMBOLS='(R0402-0201)';
      VALUE='240';
      TOL='1%';
      WATTAGE='1/16W';
      CLASS='DISCRETE';
      DESCRIPTION='RES CHIP 240 1/16W +-1%(0402)EF';
      COMPONENT_TYPE='CHIPR0402';
      LEAD_LENGTH='';
      DFM_EXCLUSION='';
      DAY='20180221';
      PARENT_PART_TYPE='Q_RES';
      PARENT_PPT='Q_RES';
      PARENT_PPT_PART='Q_RES_0402LF-240,1%,1/16W,CHIP,CS12402FB01';
  end_body;
end_primitive;
primitive 'Q_RES_0402LF-240,1%,1/16W,EMPTA';
  pin
    'A':
      PIN_GROUP='1';
      PIN_NUMBER='(1)';
      PIN_TYPE='UNSPEC';
      PINUSE='UNSPEC';
    'B':
      PIN_GROUP='1';
      PIN_NUMBER='(2)';
      PIN_TYPE='UNSPEC';
      PINUSE='UNSPEC';
  end_pin;
  body
      PART_NAME='Q_RES';
      PHYS_DES_PREFIX='R';
      STANDARD='End of Design';
      LIFECYCLE='Comp-Approve';
      JEDEC_TYPE='R0402';
      ALT_SYMBOLS='(R0402-0201)';
      VALUE='240';
      TOL='1%';
      WATTAGE='1/16W';
      CLASS='IO';
      DESCRIPTION='RES CHIP 240 1/16W +-1%(0402)EF';
      COMPONENT_TYPE='CHIPR0402';
      LEAD_LENGTH='';
      DFM_EXCLUSION='';
      DAY='20180221';
      PARENT_PART_TYPE='Q_RES';
      PARENT_PPT='Q_RES';
      PARENT_PPT_PART='Q_RES_0402LF-240,1%,1/16W,EMPTY,CS12402FB01';
  end_body;
end_primitive;
primitive 'Q_RES_0402LF-249,1%,1/16W,CHIPA';
  pin
    'A':
      PIN_GROUP='1';
      PIN_NUMBER='(1)';
      PIN_TYPE='UNSPEC';
      PINUSE='UNSPEC';
    'B':
      PIN_GROUP='1';
      PIN_NUMBER='(2)';
      PIN_TYPE='UNSPEC';
      PINUSE='UNSPEC';
  end_pin;
  body
      PART_NAME='Q_RES';
      PHYS_DES_PREFIX='R';
      STANDARD='End of Design';
      LIFECYCLE='Comp-Approve';
      JEDEC_TYPE='R0402';
      ALT_SYMBOLS='(R0402-0201)';
      VALUE='249';
      TOL='1%';
      WATTAGE='1/16W';
      CLASS='DISCRETE';
      DESCRIPTION='RES CHIP 249 1/16W +-1%(0402)EF';
      COMPONENT_TYPE='CHIPR0402';
      LEAD_LENGTH='';
      DFM_EXCLUSION='';
      DAY='20190904';
      PARENT_PART_TYPE='Q_RES';
      PARENT_PPT='Q_RES';
      PARENT_PPT_PART='Q_RES_0402LF-249,1%,1/16W,CHIP,CS12492FB02';
  end_body;
end_primitive;
primitive 'Q_RES_0402LF-25.5K,1%,1/16W,CHA';
  pin
    'A':
      PIN_GROUP='1';
      PIN_NUMBER='(1)';
      PIN_TYPE='UNSPEC';
      PINUSE='UNSPEC';
    'B':
      PIN_GROUP='1';
      PIN_NUMBER='(2)';
      PIN_TYPE='UNSPEC';
      PINUSE='UNSPEC';
  end_pin;
  body
      PART_NAME='Q_RES';
      PHYS_DES_PREFIX='R';
      STANDARD='End of Design';
      LIFECYCLE='Comp-Approve';
      JEDEC_TYPE='R0402';
      ALT_SYMBOLS='(R0402-0201)';
      VALUE='25.5K';
      TOL='1%';
      WATTAGE='1/16W';
      CLASS='DISCRETE';
      DESCRIPTION='RES CHIP 25.5K 1/16W +-1%(0402)EF';
      COMPONENT_TYPE='CHIPR0402';
      LEAD_LENGTH='';
      DFM_EXCLUSION='';
      DAY='20180221';
      PARENT_PART_TYPE='Q_RES';
      PARENT_PPT='Q_RES';
      PARENT_PPT_PART='Q_RES_0402LF-25.5K,1%,1/16W,CHIP,CS32552FB06';
  end_body;
end_primitive;
primitive 'Q_RES_0402LF-26.1K,0.1%,1/16W,A';
  pin
    'A':
      PIN_GROUP='1';
      PIN_NUMBER='(1)';
      PIN_TYPE='UNSPEC';
      PINUSE='UNSPEC';
    'B':
      PIN_GROUP='1';
      PIN_NUMBER='(2)';
      PIN_TYPE='UNSPEC';
      PINUSE='UNSPEC';
  end_pin;
  body
      PART_NAME='Q_RES';
      PHYS_DES_PREFIX='R';
      STANDARD='';
      LIFECYCLE='';
      JEDEC_TYPE='R0402';
      ALT_SYMBOLS='(R0402-0201)';
      VALUE='26.1K';
      TOL='0.1%';
      WATTAGE='1/16W';
      CLASS='IO';
      DESCRIPTION='RES CHIP 26.1K 1/16W +-0.1%(0402)EF';
      COMPONENT_TYPE='CHIPR0402';
      LEAD_LENGTH='';
      DFM_EXCLUSION='';
      DAY='20210720';
      PARENT_PART_TYPE='Q_RES';
      PARENT_PPT='Q_RES';
      PARENT_PPT_PART='Q_RES_0402LF-26.1K,0.1%,1/16W,EMPTY,CS32612BB02';
  end_body;
end_primitive;
primitive 'Q_RES_0402LF-26.7K,1%,1/16W,CHA';
  pin
    'A':
      PIN_GROUP='1';
      PIN_NUMBER='(1)';
      PIN_TYPE='UNSPEC';
      PINUSE='UNSPEC';
    'B':
      PIN_GROUP='1';
      PIN_NUMBER='(2)';
      PIN_TYPE='UNSPEC';
      PINUSE='UNSPEC';
  end_pin;
  body
      PART_NAME='Q_RES';
      PHYS_DES_PREFIX='R';
      STANDARD='End of Design';
      LIFECYCLE='Comp-Approve';
      JEDEC_TYPE='R0402';
      ALT_SYMBOLS='(R0402-0201)';
      VALUE='26.7K';
      TOL='1%';
      WATTAGE='1/16W';
      CLASS='DISCRETE';
      DESCRIPTION='RES CHIP 26.7K 1/16W +-1%(0402)EF';
      COMPONENT_TYPE='CHIPR0402';
      LEAD_LENGTH='';
      DFM_EXCLUSION='';
      DAY='20190906';
      PARENT_PART_TYPE='Q_RES';
      PARENT_PPT='Q_RES';
      PARENT_PPT_PART='Q_RES_0402LF-26.7K,1%,1/16W,CHIP,CS32672FB03';
  end_body;
end_primitive;
primitive 'Q_RES_0402LF-27.4,1%,1/16W,CHIA';
  pin
    'A':
      PIN_GROUP='1';
      PIN_NUMBER='(1)';
      PIN_TYPE='UNSPEC';
      PINUSE='UNSPEC';
    'B':
      PIN_GROUP='1';
      PIN_NUMBER='(2)';
      PIN_TYPE='UNSPEC';
      PINUSE='UNSPEC';
  end_pin;
  body
      PART_NAME='Q_RES';
      PHYS_DES_PREFIX='R';
      STANDARD='End of Design';
      LIFECYCLE='Comp-Release Qty';
      JEDEC_TYPE='R0402';
      ALT_SYMBOLS='(R0402-0201)';
      VALUE='27.4';
      TOL='1%';
      WATTAGE='1/16W';
      CLASS='DISCRETE';
      DESCRIPTION='RES CHIP 27.4 1/16W +-1%(0402)EF';
      COMPONENT_TYPE='CHIPR0402';
      LEAD_LENGTH='';
      DFM_EXCLUSION='';
      DAY='20180221';
      PARENT_PART_TYPE='Q_RES';
      PARENT_PPT='Q_RES';
      PARENT_PPT_PART='Q_RES_0402LF-27.4,1%,1/16W,CHIP,CS02742FB03';
  end_body;
end_primitive;
primitive 'Q_RES_0402LF-28K,1%,1/16W,EMPTA';
  pin
    'A':
      PIN_GROUP='1';
      PIN_NUMBER='(1)';
      PIN_TYPE='UNSPEC';
      PINUSE='UNSPEC';
    'B':
      PIN_GROUP='1';
      PIN_NUMBER='(2)';
      PIN_TYPE='UNSPEC';
      PINUSE='UNSPEC';
  end_pin;
  body
      PART_NAME='Q_RES';
      PHYS_DES_PREFIX='R';
      STANDARD='End of Design';
      LIFECYCLE='Comp-Approve';
      JEDEC_TYPE='R0402';
      ALT_SYMBOLS='(R0402-0201)';
      VALUE='28K';
      TOL='1%';
      WATTAGE='1/16W';
      CLASS='IO';
      DESCRIPTION='RES CHIP 28K 1/16W +-1%(0402)EF';
      COMPONENT_TYPE='CHIP0402';
      LEAD_LENGTH='';
      DFM_EXCLUSION='';
      DAY='20180212';
      PARENT_PART_TYPE='Q_RES';
      PARENT_PPT='Q_RES';
      PARENT_PPT_PART='Q_RES_0402LF-28K,1%,1/16W,EMPTY,CS32802FB05';
  end_body;
end_primitive;
primitive 'Q_RES_0402LF-2K,0.1%,1/16W,CHIA';
  pin
    'A':
      PIN_GROUP='1';
      PIN_NUMBER='(1)';
      PIN_TYPE='UNSPEC';
      PINUSE='UNSPEC';
    'B':
      PIN_GROUP='1';
      PIN_NUMBER='(2)';
      PIN_TYPE='UNSPEC';
      PINUSE='UNSPEC';
  end_pin;
  body
      PART_NAME='Q_RES';
      PHYS_DES_PREFIX='R';
      STANDARD='';
      LIFECYCLE='';
      JEDEC_TYPE='R0402';
      ALT_SYMBOLS='(R0402-0201)';
      VALUE='2K';
      TOL='0.1%';
      WATTAGE='1/16W';
      CLASS='DISCRETE';
      DESCRIPTION='RES CHIP 2K 1/16W +-0.1%(0402)EF';
      COMPONENT_TYPE='CHIPR0402';
      LEAD_LENGTH='';
      DFM_EXCLUSION='';
      DAY='20211207';
      PARENT_PART_TYPE='Q_RES';
      PARENT_PPT='Q_RES';
      PARENT_PPT_PART='Q_RES_0402LF-2K,0.1%,1/16W,CHIP,CS22002BB07';
  end_body;
end_primitive;
primitive 'Q_RES_0402LF-2K,1%,1/16W,CHIP,A';
  pin
    'A':
      PIN_GROUP='1';
      PIN_NUMBER='(1)';
      PIN_TYPE='UNSPEC';
      PINUSE='UNSPEC';
    'B':
      PIN_GROUP='1';
      PIN_NUMBER='(2)';
      PIN_TYPE='UNSPEC';
      PINUSE='UNSPEC';
  end_pin;
  body
      PART_NAME='Q_RES';
      PHYS_DES_PREFIX='R';
      STANDARD='End of Design';
      LIFECYCLE='Comp-Approve';
      JEDEC_TYPE='R0402';
      ALT_SYMBOLS='(R0402-0201)';
      VALUE='2K';
      TOL='1%';
      WATTAGE='1/16W';
      CLASS='DISCRETE';
      DESCRIPTION='RES CHIP 2K 1/16W +-1%(0402)EF';
      COMPONENT_TYPE='CHIPR0402';
      LEAD_LENGTH='';
      DFM_EXCLUSION='';
      DAY='20180221';
      PARENT_PART_TYPE='Q_RES';
      PARENT_PPT='Q_RES';
      PARENT_PPT_PART='Q_RES_0402LF-2K,1%,1/16W,CHIP,CS22002FB07';
  end_body;
end_primitive;
primitive 'Q_RES_0402LF-2K,1%,1/16W,EMPTYA';
  pin
    'A':
      PIN_GROUP='1';
      PIN_NUMBER='(1)';
      PIN_TYPE='UNSPEC';
      PINUSE='UNSPEC';
    'B':
      PIN_GROUP='1';
      PIN_NUMBER='(2)';
      PIN_TYPE='UNSPEC';
      PINUSE='UNSPEC';
  end_pin;
  body
      PART_NAME='Q_RES';
      PHYS_DES_PREFIX='R';
      STANDARD='End of Design';
      LIFECYCLE='Comp-Approve';
      JEDEC_TYPE='R0402';
      ALT_SYMBOLS='(R0402-0201)';
      VALUE='2K';
      TOL='1%';
      WATTAGE='1/16W';
      CLASS='IO';
      DESCRIPTION='RES CHIP 2K 1/16W +-1%(0402)EF';
      COMPONENT_TYPE='CHIPR0402';
      LEAD_LENGTH='';
      DFM_EXCLUSION='';
      DAY='20180221';
      PARENT_PART_TYPE='Q_RES';
      PARENT_PPT='Q_RES';
      PARENT_PPT_PART='Q_RES_0402LF-2K,1%,1/16W,EMPTY,CS22002FB07';
  end_body;
end_primitive;
primitive 'Q_RES_0402LF-3.3,1%,1/16W,CHIPA';
  pin
    'A':
      PIN_GROUP='1';
      PIN_NUMBER='(1)';
      PIN_TYPE='UNSPEC';
      PINUSE='UNSPEC';
    'B':
      PIN_GROUP='1';
      PIN_NUMBER='(2)';
      PIN_TYPE='UNSPEC';
      PINUSE='UNSPEC';
  end_pin;
  body
      PART_NAME='Q_RES';
      PHYS_DES_PREFIX='R';
      STANDARD='End of Design';
      LIFECYCLE='Comp-Approve';
      JEDEC_TYPE='R0402';
      ALT_SYMBOLS='(R0402-0201)';
      VALUE='3.3';
      TOL='1%';
      WATTAGE='1/16W';
      CLASS='DISCRETE';
      DESCRIPTION='RES CHIP 3.3 1/16W +-1%(0402)EF';
      COMPONENT_TYPE='CHIPR0402';
      LEAD_LENGTH='';
      DFM_EXCLUSION='';
      DAY='20210715';
      PARENT_PART_TYPE='Q_RES';
      PARENT_PPT='Q_RES';
      PARENT_PPT_PART='Q_RES_0402LF-3.3,1%,1/16W,CHIP,CS-3302FB01';
  end_body;
end_primitive;
primitive 'Q_RES_0402LF-3.57K,1%,1/16W,CHA';
  pin
    'A':
      PIN_GROUP='1';
      PIN_NUMBER='(1)';
      PIN_TYPE='UNSPEC';
      PINUSE='UNSPEC';
    'B':
      PIN_GROUP='1';
      PIN_NUMBER='(2)';
      PIN_TYPE='UNSPEC';
      PINUSE='UNSPEC';
  end_pin;
  body
      PART_NAME='Q_RES';
      PHYS_DES_PREFIX='R';
      STANDARD='End of Design';
      LIFECYCLE='Comp-Approve';
      JEDEC_TYPE='R0402';
      ALT_SYMBOLS='(R0402-0201)';
      VALUE='3.57K';
      TOL='1%';
      WATTAGE='1/16W';
      CLASS='DISCRETE';
      DESCRIPTION='RES CHIP 3.57K 1/16W +-1%(0402)EF';
      COMPONENT_TYPE='CHIPR0402';
      LEAD_LENGTH='';
      DFM_EXCLUSION='';
      DAY='20190829';
      PARENT_PART_TYPE='Q_RES';
      PARENT_PPT='Q_RES';
      PARENT_PPT_PART='Q_RES_0402LF-3.57K,1%,1/16W,CHIP,CS23572FB05';
  end_body;
end_primitive;
primitive 'Q_RES_0402LF-3.9K,5%,1/16W,EMPA';
  pin
    'A':
      PIN_GROUP='1';
      PIN_NUMBER='(1)';
      PIN_TYPE='UNSPEC';
      PINUSE='UNSPEC';
    'B':
      PIN_GROUP='1';
      PIN_NUMBER='(2)';
      PIN_TYPE='UNSPEC';
      PINUSE='UNSPEC';
  end_pin;
  body
      PART_NAME='Q_RES';
      PHYS_DES_PREFIX='R';
      STANDARD='End of Design';
      LIFECYCLE='Comp-Approve';
      JEDEC_TYPE='R0402';
      ALT_SYMBOLS='(R0402-0201)';
      VALUE='3.9K';
      TOL='5%';
      WATTAGE='1/16W';
      CLASS='IO';
      DESCRIPTION='RES CHIP 3.9K 1/16W +-5%(0402)EF';
      COMPONENT_TYPE='CHIPR0402';
      LEAD_LENGTH='';
      DFM_EXCLUSION='';
      DAY='20210715';
      PARENT_PART_TYPE='Q_RES';
      PARENT_PPT='Q_RES';
      PARENT_PPT_PART='Q_RES_0402LF-3.9K,5%,1/16W,EMPTY,CS23902JB04';
  end_body;
end_primitive;
primitive 'Q_RES_0402LF-30.1K,1%,1/16W,CHA';
  pin
    'A':
      PIN_GROUP='1';
      PIN_NUMBER='(1)';
      PIN_TYPE='UNSPEC';
      PINUSE='UNSPEC';
    'B':
      PIN_GROUP='1';
      PIN_NUMBER='(2)';
      PIN_TYPE='UNSPEC';
      PINUSE='UNSPEC';
  end_pin;
  body
      PART_NAME='Q_RES';
      PHYS_DES_PREFIX='R';
      STANDARD='End of Design';
      LIFECYCLE='Comp-Approve';
      JEDEC_TYPE='R0402';
      ALT_SYMBOLS='(R0402-0201)';
      VALUE='30.1K';
      TOL='1%';
      WATTAGE='1/16W';
      CLASS='DISCRETE';
      DESCRIPTION='RES CHIP 30.1K 1/16W +-1%(0402)EF';
      COMPONENT_TYPE='CHIPR0402';
      LEAD_LENGTH='';
      DFM_EXCLUSION='';
      DAY='20210715';
      PARENT_PART_TYPE='Q_RES';
      PARENT_PPT='Q_RES';
      PARENT_PPT_PART='Q_RES_0402LF-30.1K,1%,1/16W,CHIP,CS33012FB03';
  end_body;
end_primitive;
primitive 'Q_RES_0402LF-30.1K,1%,1/16W,EMA';
  pin
    'A':
      PIN_GROUP='1';
      PIN_NUMBER='(1)';
      PIN_TYPE='UNSPEC';
      PINUSE='UNSPEC';
    'B':
      PIN_GROUP='1';
      PIN_NUMBER='(2)';
      PIN_TYPE='UNSPEC';
      PINUSE='UNSPEC';
  end_pin;
  body
      PART_NAME='Q_RES';
      PHYS_DES_PREFIX='R';
      STANDARD='End of Design';
      LIFECYCLE='Comp-Approve';
      JEDEC_TYPE='R0402';
      ALT_SYMBOLS='(R0402-0201)';
      VALUE='30.1K';
      TOL='1%';
      WATTAGE='1/16W';
      CLASS='IO';
      DESCRIPTION='RES CHIP 30.1K 1/16W +-1%(0402)EF';
      COMPONENT_TYPE='CHIPR0402';
      LEAD_LENGTH='';
      DFM_EXCLUSION='';
      DAY='20210715';
      PARENT_PART_TYPE='Q_RES';
      PARENT_PPT='Q_RES';
      PARENT_PPT_PART='Q_RES_0402LF-30.1K,1%,1/16W,EMPTY,CS33012FB03';
  end_body;
end_primitive;
primitive 'Q_RES_0402LF-301,1%,1/16W,CHIPA';
  pin
    'A':
      PIN_GROUP='1';
      PIN_NUMBER='(1)';
      PIN_TYPE='UNSPEC';
      PINUSE='UNSPEC';
    'B':
      PIN_GROUP='1';
      PIN_NUMBER='(2)';
      PIN_TYPE='UNSPEC';
      PINUSE='UNSPEC';
  end_pin;
  body
      PART_NAME='Q_RES';
      PHYS_DES_PREFIX='R';
      STANDARD='End of Design';
      LIFECYCLE='Comp-Approve';
      JEDEC_TYPE='R0402';
      ALT_SYMBOLS='(R0402-0201)';
      VALUE='301';
      TOL='1%';
      WATTAGE='1/16W';
      CLASS='DISCRETE';
      DESCRIPTION='RES CHIP 301 1/16W +-1%(0402)EF';
      COMPONENT_TYPE='CHIPR0402';
      LEAD_LENGTH='';
      DFM_EXCLUSION='';
      DAY='20190904';
      PARENT_PART_TYPE='Q_RES';
      PARENT_PPT='Q_RES';
      PARENT_PPT_PART='Q_RES_0402LF-301,1%,1/16W,CHIP,CS13012FB02';
  end_body;
end_primitive;
primitive 'Q_RES_0402LF-31.6K,1%,1/16W,CHA';
  pin
    'A':
      PIN_GROUP='1';
      PIN_NUMBER='(1)';
      PIN_TYPE='UNSPEC';
      PINUSE='UNSPEC';
    'B':
      PIN_GROUP='1';
      PIN_NUMBER='(2)';
      PIN_TYPE='UNSPEC';
      PINUSE='UNSPEC';
  end_pin;
  body
      PART_NAME='Q_RES';
      PHYS_DES_PREFIX='R';
      STANDARD='End of Design';
      LIFECYCLE='Comp-Approve';
      JEDEC_TYPE='R0402';
      ALT_SYMBOLS='(R0402-0201)';
      VALUE='31.6K';
      TOL='1%';
      WATTAGE='1/16W';
      CLASS='DISCRETE';
      DESCRIPTION='RES CHIP 31.6K 1/16W +-1%(0402)EF';
      COMPONENT_TYPE='CHIPR0402';
      LEAD_LENGTH='';
      DFM_EXCLUSION='';
      DAY='20190718';
      PARENT_PART_TYPE='Q_RES';
      PARENT_PPT='Q_RES';
      PARENT_PPT_PART='Q_RES_0402LF-31.6K,1%,1/16W,CHIP,CS33162FB02';
  end_body;
end_primitive;
primitive 'Q_RES_0402LF-33.2,1%,1/16W,CHIA';
  pin
    'A':
      PIN_GROUP='1';
      PIN_NUMBER='(1)';
      PIN_TYPE='UNSPEC';
      PINUSE='UNSPEC';
    'B':
      PIN_GROUP='1';
      PIN_NUMBER='(2)';
      PIN_TYPE='UNSPEC';
      PINUSE='UNSPEC';
  end_pin;
  body
      PART_NAME='Q_RES';
      PHYS_DES_PREFIX='R';
      STANDARD='End of Design';
      LIFECYCLE='Comp-Approve';
      JEDEC_TYPE='R0402';
      ALT_SYMBOLS='(R0402-0201)';
      VALUE='33.2';
      TOL='1%';
      WATTAGE='1/16W';
      CLASS='DISCRETE';
      DESCRIPTION='RES CHIP 33.2 1/16W +-1%(0402)EF';
      COMPONENT_TYPE='CHIPR0402';
      LEAD_LENGTH='';
      DFM_EXCLUSION='';
      DAY='20180208';
      PARENT_PART_TYPE='Q_RES';
      PARENT_PPT='Q_RES';
      PARENT_PPT_PART='Q_RES_0402LF-33.2,1%,1/16W,CHIP,CS03322FB03';
  end_body;
end_primitive;
primitive 'Q_RES_0402LF-33.2,1%,1/16W,EMPA';
  pin
    'A':
      PIN_GROUP='1';
      PIN_NUMBER='(1)';
      PIN_TYPE='UNSPEC';
      PINUSE='UNSPEC';
    'B':
      PIN_GROUP='1';
      PIN_NUMBER='(2)';
      PIN_TYPE='UNSPEC';
      PINUSE='UNSPEC';
  end_pin;
  body
      PART_NAME='Q_RES';
      PHYS_DES_PREFIX='R';
      STANDARD='End of Design';
      LIFECYCLE='Comp-Approve';
      JEDEC_TYPE='R0402';
      ALT_SYMBOLS='(R0402-0201)';
      VALUE='33.2';
      TOL='1%';
      WATTAGE='1/16W';
      CLASS='IO';
      DESCRIPTION='RES CHIP 33.2 1/16W +-1%(0402)EF';
      COMPONENT_TYPE='CHIPR0402';
      LEAD_LENGTH='';
      DFM_EXCLUSION='';
      DAY='20180208';
      PARENT_PART_TYPE='Q_RES';
      PARENT_PPT='Q_RES';
      PARENT_PPT_PART='Q_RES_0402LF-33.2,1%,1/16W,EMPTY,CS03322FB03';
  end_body;
end_primitive;
primitive 'Q_RES_0402LF-33K,1%,1/16W,CHIPA';
  pin
    'A':
      PIN_GROUP='1';
      PIN_NUMBER='(1)';
      PIN_TYPE='UNSPEC';
      PINUSE='UNSPEC';
    'B':
      PIN_GROUP='1';
      PIN_NUMBER='(2)';
      PIN_TYPE='UNSPEC';
      PINUSE='UNSPEC';
  end_pin;
  body
      PART_NAME='Q_RES';
      PHYS_DES_PREFIX='R';
      STANDARD='';
      LIFECYCLE='';
      JEDEC_TYPE='R0402';
      ALT_SYMBOLS='(R0402-0201)';
      VALUE='33K';
      TOL='1%';
      WATTAGE='1/16W';
      CLASS='DISCRETE';
      DESCRIPTION='RES CHIP 33K 1/16W +-1%(0402)EF';
      COMPONENT_TYPE='CHIPR0402';
      LEAD_LENGTH='';
      DFM_EXCLUSION='';
      DAY='20180221';
      PARENT_PART_TYPE='Q_RES';
      PARENT_PPT='Q_RES';
      PARENT_PPT_PART='Q_RES_0402LF-33K,1%,1/16W,CHIP,CS33302FB00';
  end_body;
end_primitive;
primitive 'Q_RES_0402LF-34.8K,1%,1/16W,CHA';
  pin
    'A':
      PIN_GROUP='1';
      PIN_NUMBER='(1)';
      PIN_TYPE='UNSPEC';
      PINUSE='UNSPEC';
    'B':
      PIN_GROUP='1';
      PIN_NUMBER='(2)';
      PIN_TYPE='UNSPEC';
      PINUSE='UNSPEC';
  end_pin;
  body
      PART_NAME='Q_RES';
      PHYS_DES_PREFIX='R';
      STANDARD='';
      LIFECYCLE='';
      JEDEC_TYPE='R0402';
      ALT_SYMBOLS='(R0402-0201)';
      VALUE='34.8K';
      TOL='1%';
      WATTAGE='1/16W';
      CLASS='DISCRETE';
      DESCRIPTION='RES CHIP 34.8K 1/16W +-1%(0402)EF';
      COMPONENT_TYPE='CHIPR0402';
      LEAD_LENGTH='';
      DFM_EXCLUSION='';
      DAY='20200728';
      PARENT_PART_TYPE='Q_RES';
      PARENT_PPT='Q_RES';
      PARENT_PPT_PART='Q_RES_0402LF-34.8K,1%,1/16W,CHIP,CS33482FB04';
  end_body;
end_primitive;
primitive 'Q_RES_0402LF-35.7K,1%,1/16W,CHA';
  pin
    'A':
      PIN_GROUP='1';
      PIN_NUMBER='(1)';
      PIN_TYPE='UNSPEC';
      PINUSE='UNSPEC';
    'B':
      PIN_GROUP='1';
      PIN_NUMBER='(2)';
      PIN_TYPE='UNSPEC';
      PINUSE='UNSPEC';
  end_pin;
  body
      PART_NAME='Q_RES';
      PHYS_DES_PREFIX='R';
      STANDARD='End of Design';
      LIFECYCLE='Comp-Approve';
      JEDEC_TYPE='R0402';
      ALT_SYMBOLS='(R0402-0201)';
      VALUE='35.7K';
      TOL='1%';
      WATTAGE='1/16W';
      CLASS='DISCRETE';
      DESCRIPTION='RES CHIP 35.7K 1/16W +-1%(0402) EF';
      COMPONENT_TYPE='CHIPR0402';
      LEAD_LENGTH='';
      DFM_EXCLUSION='';
      DAY='20180221';
      PARENT_PART_TYPE='Q_RES';
      PARENT_PPT='Q_RES';
      PARENT_PPT_PART='Q_RES_0402LF-35.7K,1%,1/16W,CHIP,CS33572FB01';
  end_body;
end_primitive;
primitive 'Q_RES_0402LF-38.3K,0.1%,1/16W,A';
  pin
    'A':
      PIN_GROUP='1';
      PIN_NUMBER='(1)';
      PIN_TYPE='UNSPEC';
      PINUSE='UNSPEC';
    'B':
      PIN_GROUP='1';
      PIN_NUMBER='(2)';
      PIN_TYPE='UNSPEC';
      PINUSE='UNSPEC';
  end_pin;
  body
      PART_NAME='Q_RES';
      PHYS_DES_PREFIX='R';
      STANDARD='';
      LIFECYCLE='';
      JEDEC_TYPE='R0402';
      ALT_SYMBOLS='(R0402-0201)';
      VALUE='38.3K';
      TOL='0.1%';
      WATTAGE='1/16W';
      CLASS='DISCRETE';
      DESCRIPTION='RES CHIP 38.3K 1/16W +-0.1%(0402)EF';
      COMPONENT_TYPE='CHIPR0402';
      LEAD_LENGTH='';
      DFM_EXCLUSION='';
      DAY='20220316';
      PARENT_PART_TYPE='Q_RES';
      PARENT_PPT='Q_RES';
      PARENT_PPT_PART='Q_RES_0402LF-38.3K,0.1%,1/16W,CHIP,CS33832BB06';
  end_body;
end_primitive;
primitive 'Q_RES_0402LF-4.32K,1%,1/16W,CHA';
  pin
    'A':
      PIN_GROUP='1';
      PIN_NUMBER='(1)';
      PIN_TYPE='UNSPEC';
      PINUSE='UNSPEC';
    'B':
      PIN_GROUP='1';
      PIN_NUMBER='(2)';
      PIN_TYPE='UNSPEC';
      PINUSE='UNSPEC';
  end_pin;
  body
      PART_NAME='Q_RES';
      PHYS_DES_PREFIX='R';
      STANDARD='End of Design';
      LIFECYCLE='Comp-Approve';
      JEDEC_TYPE='R0402';
      ALT_SYMBOLS='(R0402-0201)';
      VALUE='4.32K';
      TOL='1%';
      WATTAGE='1/16W';
      CLASS='DISCRETE';
      DESCRIPTION='RES CHIP 4.32K 1/16W +-1%(0402)EF';
      COMPONENT_TYPE='CHIPR0402';
      LEAD_LENGTH='';
      DFM_EXCLUSION='';
      DAY='20210715';
      PARENT_PART_TYPE='Q_RES';
      PARENT_PPT='Q_RES';
      PARENT_PPT_PART='Q_RES_0402LF-4.32K,1%,1/16W,CHIP,CS24322FB03';
  end_body;
end_primitive;
primitive 'Q_RES_0402LF-4.53K,1%,1/16W,CHA';
  pin
    'A':
      PIN_GROUP='1';
      PIN_NUMBER='(1)';
      PIN_TYPE='UNSPEC';
      PINUSE='UNSPEC';
    'B':
      PIN_GROUP='1';
      PIN_NUMBER='(2)';
      PIN_TYPE='UNSPEC';
      PINUSE='UNSPEC';
  end_pin;
  body
      PART_NAME='Q_RES';
      PHYS_DES_PREFIX='R';
      STANDARD='End of Design';
      LIFECYCLE='Comp-Approve';
      JEDEC_TYPE='R0402';
      ALT_SYMBOLS='(R0402-0201)';
      VALUE='4.53K';
      TOL='1%';
      WATTAGE='1/16W';
      CLASS='DISCRETE';
      DESCRIPTION='RES CHIP 4.53K 1/16W +-1%(0402)EF';
      COMPONENT_TYPE='CHIP0402';
      LEAD_LENGTH='';
      DFM_EXCLUSION='';
      DAY='20180212';
      PARENT_PART_TYPE='Q_RES';
      PARENT_PPT='Q_RES';
      PARENT_PPT_PART='Q_RES_0402LF-4.53K,1%,1/16W,CHIP,CS24532FB03';
  end_body;
end_primitive;
primitive 'Q_RES_0402LF-4.75K,1%,1/16W,CHA';
  pin
    'A':
      PIN_GROUP='1';
      PIN_NUMBER='(1)';
      PIN_TYPE='UNSPEC';
      PINUSE='UNSPEC';
    'B':
      PIN_GROUP='1';
      PIN_NUMBER='(2)';
      PIN_TYPE='UNSPEC';
      PINUSE='UNSPEC';
  end_pin;
  body
      PART_NAME='Q_RES';
      PHYS_DES_PREFIX='R';
      STANDARD='End of Design';
      LIFECYCLE='Comp-Approve';
      JEDEC_TYPE='R0402';
      ALT_SYMBOLS='(R0402-0201)';
      VALUE='4.75K';
      TOL='1%';
      WATTAGE='1/16W';
      CLASS='DISCRETE';
      DESCRIPTION='RES CHIP 4.75K 1/16W +-1%(0402)EF';
      COMPONENT_TYPE='CHIPR0402';
      LEAD_LENGTH='';
      DFM_EXCLUSION='';
      DAY='20190124';
      PARENT_PART_TYPE='Q_RES';
      PARENT_PPT='Q_RES';
      PARENT_PPT_PART='Q_RES_0402LF-4.75K,1%,1/16W,CHIP,CS24752FB03';
  end_body;
end_primitive;
primitive 'Q_RES_0402LF-4.75K,1%,1/16W,EMA';
  pin
    'A':
      PIN_GROUP='1';
      PIN_NUMBER='(1)';
      PIN_TYPE='UNSPEC';
      PINUSE='UNSPEC';
    'B':
      PIN_GROUP='1';
      PIN_NUMBER='(2)';
      PIN_TYPE='UNSPEC';
      PINUSE='UNSPEC';
  end_pin;
  body
      PART_NAME='Q_RES';
      PHYS_DES_PREFIX='R';
      STANDARD='End of Design';
      LIFECYCLE='Comp-Approve';
      JEDEC_TYPE='R0402';
      ALT_SYMBOLS='(R0402-0201)';
      VALUE='4.75K';
      TOL='1%';
      WATTAGE='1/16W';
      CLASS='IO';
      DESCRIPTION='RES CHIP 4.75K 1/16W +-1%(0402)EF';
      COMPONENT_TYPE='CHIPR0402';
      LEAD_LENGTH='';
      DFM_EXCLUSION='';
      DAY='20190124';
      PARENT_PART_TYPE='Q_RES';
      PARENT_PPT='Q_RES';
      PARENT_PPT_PART='Q_RES_0402LF-4.75K,1%,1/16W,EMPTY,CS24752FB03';
  end_body;
end_primitive;
primitive 'Q_RES_0402LF-4.7K,1%,1/16W,CHIA';
  pin
    'A':
      PIN_GROUP='1';
      PIN_NUMBER='(1)';
      PIN_TYPE='UNSPEC';
      PINUSE='UNSPEC';
    'B':
      PIN_GROUP='1';
      PIN_NUMBER='(2)';
      PIN_TYPE='UNSPEC';
      PINUSE='UNSPEC';
  end_pin;
  body
      PART_NAME='Q_RES';
      PHYS_DES_PREFIX='R';
      STANDARD='End of Design';
      LIFECYCLE='Comp-Approve';
      JEDEC_TYPE='R0402';
      ALT_SYMBOLS='(R0402-0201)';
      VALUE='4.7K';
      TOL='1%';
      WATTAGE='1/16W';
      CLASS='DISCRETE';
      DESCRIPTION='RES CHIP 4.7K 1/16W +-1%(0402)EF';
      COMPONENT_TYPE='CHIPR0402';
      LEAD_LENGTH='';
      DFM_EXCLUSION='';
      DAY='20180208';
      PARENT_PART_TYPE='Q_RES';
      PARENT_PPT='Q_RES';
      PARENT_PPT_PART='Q_RES_0402LF-4.7K,1%,1/16W,CHIP,CS24702FB06';
  end_body;
end_primitive;
primitive 'Q_RES_0402LF-4.7K,1%,1/16W,EMPA';
  pin
    'A':
      PIN_GROUP='1';
      PIN_NUMBER='(1)';
      PIN_TYPE='UNSPEC';
      PINUSE='UNSPEC';
    'B':
      PIN_GROUP='1';
      PIN_NUMBER='(2)';
      PIN_TYPE='UNSPEC';
      PINUSE='UNSPEC';
  end_pin;
  body
      PART_NAME='Q_RES';
      PHYS_DES_PREFIX='R';
      STANDARD='End of Design';
      LIFECYCLE='Comp-Approve';
      JEDEC_TYPE='R0402';
      ALT_SYMBOLS='(R0402-0201)';
      VALUE='4.7K';
      TOL='1%';
      WATTAGE='1/16W';
      CLASS='IO';
      DESCRIPTION='RES CHIP 4.7K 1/16W +-1%(0402)EF';
      COMPONENT_TYPE='CHIPR0402';
      LEAD_LENGTH='';
      DFM_EXCLUSION='';
      DAY='20180208';
      PARENT_PART_TYPE='Q_RES';
      PARENT_PPT='Q_RES';
      PARENT_PPT_PART='Q_RES_0402LF-4.7K,1%,1/16W,EMPTY,CS24702FB06';
  end_body;
end_primitive;
primitive 'Q_RES_0402LF-4.7K,5%,1/16W,CHIA';
  pin
    'A':
      PIN_GROUP='1';
      PIN_NUMBER='(1)';
      PIN_TYPE='UNSPEC';
      PINUSE='UNSPEC';
    'B':
      PIN_GROUP='1';
      PIN_NUMBER='(2)';
      PIN_TYPE='UNSPEC';
      PINUSE='UNSPEC';
  end_pin;
  body
      PART_NAME='Q_RES';
      PHYS_DES_PREFIX='R';
      STANDARD='End of Design';
      LIFECYCLE='Comp-Approve';
      JEDEC_TYPE='R0402';
      ALT_SYMBOLS='(R0402-0201)';
      VALUE='4.7K';
      TOL='5%';
      WATTAGE='1/16W';
      CLASS='DISCRETE';
      DESCRIPTION='RES CHIP 4.7K 1/16W +-5%(0402)EF';
      COMPONENT_TYPE='CHIPR0402';
      LEAD_LENGTH='';
      DFM_EXCLUSION='';
      DAY='20190729';
      PARENT_PART_TYPE='Q_RES';
      PARENT_PPT='Q_RES';
      PARENT_PPT_PART='Q_RES_0402LF-4.7K,5%,1/16W,CHIP,CS24702JB10';
  end_body;
end_primitive;
primitive 'Q_RES_0402LF-4.7K,5%,1/16W,EMPA';
  pin
    'A':
      PIN_GROUP='1';
      PIN_NUMBER='(1)';
      PIN_TYPE='UNSPEC';
      PINUSE='UNSPEC';
    'B':
      PIN_GROUP='1';
      PIN_NUMBER='(2)';
      PIN_TYPE='UNSPEC';
      PINUSE='UNSPEC';
  end_pin;
  body
      PART_NAME='Q_RES';
      PHYS_DES_PREFIX='R';
      STANDARD='End of Design';
      LIFECYCLE='Comp-Approve';
      JEDEC_TYPE='R0402';
      ALT_SYMBOLS='(R0402-0201)';
      VALUE='4.7K';
      TOL='5%';
      WATTAGE='1/16W';
      CLASS='IO';
      DESCRIPTION='RES CHIP 4.7K 1/16W +-5%(0402)EF';
      COMPONENT_TYPE='CHIPR0402';
      LEAD_LENGTH='';
      DFM_EXCLUSION='';
      DAY='20190729';
      PARENT_PART_TYPE='Q_RES';
      PARENT_PPT='Q_RES';
      PARENT_PPT_PART='Q_RES_0402LF-4.7K,5%,1/16W,EMPTY,CS24702JB10';
  end_body;
end_primitive;
primitive 'Q_RES_0402LF-4.99K,0.1%,1/16W,A';
  pin
    'A':
      PIN_GROUP='1';
      PIN_NUMBER='(1)';
      PIN_TYPE='UNSPEC';
      PINUSE='UNSPEC';
    'B':
      PIN_GROUP='1';
      PIN_NUMBER='(2)';
      PIN_TYPE='UNSPEC';
      PINUSE='UNSPEC';
  end_pin;
  body
      PART_NAME='Q_RES';
      PHYS_DES_PREFIX='R';
      STANDARD='';
      LIFECYCLE='';
      JEDEC_TYPE='R0402';
      ALT_SYMBOLS='(R0402-0201)';
      VALUE='4.99K';
      TOL='0.1%';
      WATTAGE='1/16W';
      CLASS='DISCRETE';
      DESCRIPTION='RES CHIP 4.99K 1/16W +-0.1%(0402)EF';
      COMPONENT_TYPE='CHIPR0402';
      LEAD_LENGTH='';
      DFM_EXCLUSION='';
      DAY='20211216';
      PARENT_PART_TYPE='Q_RES';
      PARENT_PPT='Q_RES';
      PARENT_PPT_PART='Q_RES_0402LF-4.99K,0.1%,1/16W,CHIP,CS24992BB04';
  end_body;
end_primitive;
primitive 'Q_RES_0402LF-4.99K,1%,1/16W,EMA';
  pin
    'A':
      PIN_GROUP='1';
      PIN_NUMBER='(1)';
      PIN_TYPE='UNSPEC';
      PINUSE='UNSPEC';
    'B':
      PIN_GROUP='1';
      PIN_NUMBER='(2)';
      PIN_TYPE='UNSPEC';
      PINUSE='UNSPEC';
  end_pin;
  body
      PART_NAME='Q_RES';
      PHYS_DES_PREFIX='R';
      STANDARD='End of Design';
      LIFECYCLE='Comp-Approve';
      JEDEC_TYPE='R0402';
      ALT_SYMBOLS='(R0402-0201)';
      VALUE='4.99K';
      TOL='1%';
      WATTAGE='1/16W';
      CLASS='IO';
      DESCRIPTION='RES CHIP 4.99K 1/16W +-1%(0402)EF';
      COMPONENT_TYPE='CHIPR0402';
      LEAD_LENGTH='';
      DFM_EXCLUSION='';
      DAY='20190717';
      PARENT_PART_TYPE='Q_RES';
      PARENT_PPT='Q_RES';
      PARENT_PPT_PART='Q_RES_0402LF-4.99K,1%,1/16W,EMPTY,CS24992FB07';
  end_body;
end_primitive;
primitive 'Q_RES_0402LF-46.4K,1%,1/16W,CHA';
  pin
    'A':
      PIN_GROUP='1';
      PIN_NUMBER='(1)';
      PIN_TYPE='UNSPEC';
      PINUSE='UNSPEC';
    'B':
      PIN_GROUP='1';
      PIN_NUMBER='(2)';
      PIN_TYPE='UNSPEC';
      PINUSE='UNSPEC';
  end_pin;
  body
      PART_NAME='Q_RES';
      PHYS_DES_PREFIX='R';
      STANDARD='';
      LIFECYCLE='';
      JEDEC_TYPE='R0402';
      ALT_SYMBOLS='(R0402-0201)';
      VALUE='46.4K';
      TOL='1%';
      WATTAGE='1/16W';
      CLASS='DISCRETE';
      DESCRIPTION='RES CHIP 46.4K 1/16W +-1%(0402)EF';
      COMPONENT_TYPE='CHIPR0402';
      LEAD_LENGTH='';
      DFM_EXCLUSION='';
      DAY='20200227';
      PARENT_PART_TYPE='Q_RES';
      PARENT_PPT='Q_RES';
      PARENT_PPT_PART='Q_RES_0402LF-46.4K,1%,1/16W,CHIP,CS34642FB02';
  end_body;
end_primitive;
primitive 'Q_RES_0402LF-470,1%,1/16W,CHIPA';
  pin
    'A':
      PIN_GROUP='1';
      PIN_NUMBER='(1)';
      PIN_TYPE='UNSPEC';
      PINUSE='UNSPEC';
    'B':
      PIN_GROUP='1';
      PIN_NUMBER='(2)';
      PIN_TYPE='UNSPEC';
      PINUSE='UNSPEC';
  end_pin;
  body
      PART_NAME='Q_RES';
      PHYS_DES_PREFIX='R';
      STANDARD='End of Design';
      LIFECYCLE='Comp-Approve';
      JEDEC_TYPE='R0402';
      ALT_SYMBOLS='(R0402-0201)';
      VALUE='470';
      TOL='1%';
      WATTAGE='1/16W';
      CLASS='DISCRETE';
      DESCRIPTION='RES CHIP 470 1/16W +-1%(0402)EF';
      COMPONENT_TYPE='CHIPR0402';
      LEAD_LENGTH='';
      DFM_EXCLUSION='';
      DAY='20210715';
      PARENT_PART_TYPE='Q_RES';
      PARENT_PPT='Q_RES';
      PARENT_PPT_PART='Q_RES_0402LF-470,1%,1/16W,CHIP,CS14702FB04';
  end_body;
end_primitive;
primitive 'Q_RES_0402LF-47K,0.1%,1/16W,CHA';
  pin
    'A':
      PIN_GROUP='1';
      PIN_NUMBER='(1)';
      PIN_TYPE='UNSPEC';
      PINUSE='UNSPEC';
    'B':
      PIN_GROUP='1';
      PIN_NUMBER='(2)';
      PIN_TYPE='UNSPEC';
      PINUSE='UNSPEC';
  end_pin;
  body
      PART_NAME='Q_RES';
      PHYS_DES_PREFIX='R';
      STANDARD='';
      LIFECYCLE='';
      JEDEC_TYPE='R0402';
      ALT_SYMBOLS='(R0402-0201)';
      VALUE='47K';
      TOL='0.1%';
      WATTAGE='1/16W';
      CLASS='DISCRETE';
      DESCRIPTION='RES CHIP 47K 1/16W +-0.1%(0402)EF';
      COMPONENT_TYPE='CHIPR0402';
      LEAD_LENGTH='';
      DFM_EXCLUSION='';
      DAY='20211028';
      PARENT_PART_TYPE='Q_RES';
      PARENT_PPT='Q_RES';
      PARENT_PPT_PART='Q_RES_0402LF-47K,0.1%,1/16W,CHIP,CS34702BB05';
  end_body;
end_primitive;
primitive 'Q_RES_0402LF-47K,0.1%,1/16W,EMA';
  pin
    'A':
      PIN_GROUP='1';
      PIN_NUMBER='(1)';
      PIN_TYPE='UNSPEC';
      PINUSE='UNSPEC';
    'B':
      PIN_GROUP='1';
      PIN_NUMBER='(2)';
      PIN_TYPE='UNSPEC';
      PINUSE='UNSPEC';
  end_pin;
  body
      PART_NAME='Q_RES';
      PHYS_DES_PREFIX='R';
      STANDARD='';
      LIFECYCLE='';
      JEDEC_TYPE='R0402';
      ALT_SYMBOLS='(R0402-0201)';
      VALUE='47K';
      TOL='0.1%';
      WATTAGE='1/16W';
      CLASS='IO';
      DESCRIPTION='RES CHIP 47K 1/16W +-0.1%(0402)EF';
      COMPONENT_TYPE='CHIPR0402';
      LEAD_LENGTH='';
      DFM_EXCLUSION='';
      DAY='20211028';
      PARENT_PART_TYPE='Q_RES';
      PARENT_PPT='Q_RES';
      PARENT_PPT_PART='Q_RES_0402LF-47K,0.1%,1/16W,EMPTY,CS34702BB05';
  end_body;
end_primitive;
primitive 'Q_RES_0402LF-49.9,1%,1/16W,CHIA';
  pin
    'A':
      PIN_GROUP='1';
      PIN_NUMBER='(1)';
      PIN_TYPE='UNSPEC';
      PINUSE='UNSPEC';
    'B':
      PIN_GROUP='1';
      PIN_NUMBER='(2)';
      PIN_TYPE='UNSPEC';
      PINUSE='UNSPEC';
  end_pin;
  body
      PART_NAME='Q_RES';
      PHYS_DES_PREFIX='R';
      STANDARD='End of Design';
      LIFECYCLE='Comp-Approve';
      JEDEC_TYPE='R0402';
      ALT_SYMBOLS='(R0402-0201)';
      VALUE='49.9';
      TOL='1%';
      WATTAGE='1/16W';
      CLASS='DISCRETE';
      DESCRIPTION='RES CHIP 49.9 1/16W +-1%(0402)EF';
      COMPONENT_TYPE='CHIPR0402';
      LEAD_LENGTH='';
      DFM_EXCLUSION='';
      DAY='20180208';
      PARENT_PART_TYPE='Q_RES';
      PARENT_PPT='Q_RES';
      PARENT_PPT_PART='Q_RES_0402LF-49.9,1%,1/16W,CHIP,CS04992FB07';
  end_body;
end_primitive;
primitive 'Q_RES_0402LF-49.9,1%,1/16W,EMPA';
  pin
    'A':
      PIN_GROUP='1';
      PIN_NUMBER='(1)';
      PIN_TYPE='UNSPEC';
      PINUSE='UNSPEC';
    'B':
      PIN_GROUP='1';
      PIN_NUMBER='(2)';
      PIN_TYPE='UNSPEC';
      PINUSE='UNSPEC';
  end_pin;
  body
      PART_NAME='Q_RES';
      PHYS_DES_PREFIX='R';
      STANDARD='End of Design';
      LIFECYCLE='Comp-Approve';
      JEDEC_TYPE='R0402';
      ALT_SYMBOLS='(R0402-0201)';
      VALUE='49.9';
      TOL='1%';
      WATTAGE='1/16W';
      CLASS='IO';
      DESCRIPTION='RES CHIP 49.9 1/16W +-1%(0402)EF';
      COMPONENT_TYPE='CHIPR0402';
      LEAD_LENGTH='';
      DFM_EXCLUSION='';
      DAY='20180208';
      PARENT_PART_TYPE='Q_RES';
      PARENT_PPT='Q_RES';
      PARENT_PPT_PART='Q_RES_0402LF-49.9,1%,1/16W,EMPTY,CS04992FB07';
  end_body;
end_primitive;
primitive 'Q_RES_0402LF-499,1%,1/16W,CHIPA';
  pin
    'A':
      PIN_GROUP='1';
      PIN_NUMBER='(1)';
      PIN_TYPE='UNSPEC';
      PINUSE='UNSPEC';
    'B':
      PIN_GROUP='1';
      PIN_NUMBER='(2)';
      PIN_TYPE='UNSPEC';
      PINUSE='UNSPEC';
  end_pin;
  body
      PART_NAME='Q_RES';
      PHYS_DES_PREFIX='R';
      STANDARD='End of Design';
      LIFECYCLE='Comp-Approve';
      JEDEC_TYPE='R0402';
      ALT_SYMBOLS='(R0402-0201)';
      VALUE='499';
      TOL='1%';
      WATTAGE='1/16W';
      CLASS='DISCRETE';
      DESCRIPTION='RES CHIP 499 1/16W +-1%(0402)EF';
      COMPONENT_TYPE='CHIPR0402';
      LEAD_LENGTH='';
      DFM_EXCLUSION='';
      DAY='20180221';
      PARENT_PART_TYPE='Q_RES';
      PARENT_PPT='Q_RES';
      PARENT_PPT_PART='Q_RES_0402LF-499,1%,1/16W,CHIP,CS14992FB06';
  end_body;
end_primitive;
primitive 'Q_RES_0402LF-5.1,5%,1/16W,CHIPA';
  pin
    'A':
      PIN_GROUP='1';
      PIN_NUMBER='(1)';
      PIN_TYPE='UNSPEC';
      PINUSE='UNSPEC';
    'B':
      PIN_GROUP='1';
      PIN_NUMBER='(2)';
      PIN_TYPE='UNSPEC';
      PINUSE='UNSPEC';
  end_pin;
  body
      PART_NAME='Q_RES';
      PHYS_DES_PREFIX='R';
      STANDARD='';
      LIFECYCLE='';
      JEDEC_TYPE='R0402';
      ALT_SYMBOLS='(R0402-0201)';
      VALUE='5.1';
      TOL='5%';
      WATTAGE='1/16W';
      CLASS='DISCRETE';
      DESCRIPTION='RES CHIP 5.1 1/16W +-5%(0402)EF';
      COMPONENT_TYPE='CHIPR0402';
      LEAD_LENGTH='';
      DFM_EXCLUSION='';
      DAY='20210715';
      PARENT_PART_TYPE='Q_RES';
      PARENT_PPT='Q_RES';
      PARENT_PPT_PART='Q_RES_0402LF-5.1,5%,1/16W,CHIP,CS-5102JB02';
  end_body;
end_primitive;
primitive 'Q_RES_0402LF-5.11K,1%,1/16W,CHA';
  pin
    'A':
      PIN_GROUP='1';
      PIN_NUMBER='(1)';
      PIN_TYPE='UNSPEC';
      PINUSE='UNSPEC';
    'B':
      PIN_GROUP='1';
      PIN_NUMBER='(2)';
      PIN_TYPE='UNSPEC';
      PINUSE='UNSPEC';
  end_pin;
  body
      PART_NAME='Q_RES';
      PHYS_DES_PREFIX='R';
      STANDARD='End of Design';
      LIFECYCLE='Comp-Approve';
      JEDEC_TYPE='R0402';
      ALT_SYMBOLS='(R0402-0201)';
      VALUE='5.11K';
      TOL='1%';
      WATTAGE='1/16W';
      CLASS='DISCRETE';
      DESCRIPTION='RES CHIP 5.11K 1/16W +-1%(0402)EF';
      COMPONENT_TYPE='CHIPR0402';
      LEAD_LENGTH='';
      DFM_EXCLUSION='';
      DAY='20190726';
      PARENT_PART_TYPE='Q_RES';
      PARENT_PPT='Q_RES';
      PARENT_PPT_PART='Q_RES_0402LF-5.11K,1%,1/16W,CHIP,CS25112FB04';
  end_body;
end_primitive;
primitive 'Q_RES_0402LF-5.11K,1%,1/16W,EMA';
  pin
    'A':
      PIN_GROUP='1';
      PIN_NUMBER='(1)';
      PIN_TYPE='UNSPEC';
      PINUSE='UNSPEC';
    'B':
      PIN_GROUP='1';
      PIN_NUMBER='(2)';
      PIN_TYPE='UNSPEC';
      PINUSE='UNSPEC';
  end_pin;
  body
      PART_NAME='Q_RES';
      PHYS_DES_PREFIX='R';
      STANDARD='End of Design';
      LIFECYCLE='Comp-Approve';
      JEDEC_TYPE='R0402';
      ALT_SYMBOLS='(R0402-0201)';
      VALUE='5.11K';
      TOL='1%';
      WATTAGE='1/16W';
      CLASS='IO';
      DESCRIPTION='RES CHIP 5.11K 1/16W +-1%(0402)EF';
      COMPONENT_TYPE='CHIPR0402';
      LEAD_LENGTH='';
      DFM_EXCLUSION='';
      DAY='20190726';
      PARENT_PART_TYPE='Q_RES';
      PARENT_PPT='Q_RES';
      PARENT_PPT_PART='Q_RES_0402LF-5.11K,1%,1/16W,EMPTY,CS25112FB04';
  end_body;
end_primitive;
primitive 'Q_RES_0402LF-5.23K,1%,1/16W,CHA';
  pin
    'A':
      PIN_GROUP='1';
      PIN_NUMBER='(1)';
      PIN_TYPE='UNSPEC';
      PINUSE='UNSPEC';
    'B':
      PIN_GROUP='1';
      PIN_NUMBER='(2)';
      PIN_TYPE='UNSPEC';
      PINUSE='UNSPEC';
  end_pin;
  body
      PART_NAME='Q_RES';
      PHYS_DES_PREFIX='R';
      STANDARD='';
      LIFECYCLE='';
      JEDEC_TYPE='R0402';
      ALT_SYMBOLS='(R0402-0201)';
      VALUE='5.23K';
      TOL='1%';
      WATTAGE='1/16W';
      CLASS='DISCRETE';
      DESCRIPTION='RES CHIP 5.23K 1/16W +-1%(0402)EF';
      COMPONENT_TYPE='CHIPR0402';
      LEAD_LENGTH='';
      DFM_EXCLUSION='';
      DAY='20210719';
      PARENT_PART_TYPE='Q_RES';
      PARENT_PPT='Q_RES';
      PARENT_PPT_PART='Q_RES_0402LF-5.23K,1%,1/16W,CHIP,CS25232FB08';
  end_body;
end_primitive;
primitive 'Q_RES_0402LF-5.36K,1%,1/16W,CHA';
  pin
    'A':
      PIN_GROUP='1';
      PIN_NUMBER='(1)';
      PIN_TYPE='UNSPEC';
      PINUSE='UNSPEC';
    'B':
      PIN_GROUP='1';
      PIN_NUMBER='(2)';
      PIN_TYPE='UNSPEC';
      PINUSE='UNSPEC';
  end_pin;
  body
      PART_NAME='Q_RES';
      PHYS_DES_PREFIX='R';
      STANDARD='End of Design';
      LIFECYCLE='Comp-Approve';
      JEDEC_TYPE='R0402';
      ALT_SYMBOLS='(R0402-0201)';
      VALUE='5.36K';
      TOL='1%';
      WATTAGE='1/16W';
      CLASS='DISCRETE';
      DESCRIPTION='RES CHIP 5.36K 1/16W +-1%(0402)EF';
      COMPONENT_TYPE='CHIPR0402';
      LEAD_LENGTH='';
      DFM_EXCLUSION='';
      DAY='20190906';
      PARENT_PART_TYPE='Q_RES';
      PARENT_PPT='Q_RES';
      PARENT_PPT_PART='Q_RES_0402LF-5.36K,1%,1/16W,CHIP,CS25362FB02';
  end_body;
end_primitive;
primitive 'Q_RES_0402LF-510K,5%,1/16W,EMPA';
  pin
    'A':
      PIN_GROUP='1';
      PIN_NUMBER='(1)';
      PIN_TYPE='UNSPEC';
      PINUSE='UNSPEC';
    'B':
      PIN_GROUP='1';
      PIN_NUMBER='(2)';
      PIN_TYPE='UNSPEC';
      PINUSE='UNSPEC';
  end_pin;
  body
      PART_NAME='Q_RES';
      PHYS_DES_PREFIX='R';
      STANDARD='End of Design';
      LIFECYCLE='Comp-Approve';
      JEDEC_TYPE='R0402';
      ALT_SYMBOLS='(R0402-0201)';
      VALUE='510K';
      TOL='5%';
      WATTAGE='1/16W';
      CLASS='IO';
      DESCRIPTION='RES CHIP 510K 1/16W +-5%(0402)EF';
      COMPONENT_TYPE='CHIPR0402';
      LEAD_LENGTH='';
      DFM_EXCLUSION='';
      DAY='20180221';
      PARENT_PART_TYPE='Q_RES';
      PARENT_PPT='Q_RES';
      PARENT_PPT_PART='Q_RES_0402LF-510K,5%,1/16W,EMPTY,CS45102JB03';
  end_body;
end_primitive;
primitive 'Q_RES_0402LF-54.9K,1%,1/16W,CHA';
  pin
    'A':
      PIN_GROUP='1';
      PIN_NUMBER='(1)';
      PIN_TYPE='UNSPEC';
      PINUSE='UNSPEC';
    'B':
      PIN_GROUP='1';
      PIN_NUMBER='(2)';
      PIN_TYPE='UNSPEC';
      PINUSE='UNSPEC';
  end_pin;
  body
      PART_NAME='Q_RES';
      PHYS_DES_PREFIX='R';
      STANDARD='End of Design';
      LIFECYCLE='Comp-Approve';
      JEDEC_TYPE='R0402';
      ALT_SYMBOLS='(R0402-0201)';
      VALUE='54.9K';
      TOL='1%';
      WATTAGE='1/16W';
      CLASS='DISCRETE';
      DESCRIPTION='RES CHIP 54.9K 1/16W  +-1%(0402)EF';
      COMPONENT_TYPE='CHIPR0402';
      LEAD_LENGTH='';
      DFM_EXCLUSION='';
      DAY='20180221';
      PARENT_PART_TYPE='Q_RES';
      PARENT_PPT='Q_RES';
      PARENT_PPT_PART='Q_RES_0402LF-54.9K,1%,1/16W,CHIP,CS35492FB03';
  end_body;
end_primitive;
primitive 'Q_RES_0402LF-54.9K,1%,1/16W,EMA';
  pin
    'A':
      PIN_GROUP='1';
      PIN_NUMBER='(1)';
      PIN_TYPE='UNSPEC';
      PINUSE='UNSPEC';
    'B':
      PIN_GROUP='1';
      PIN_NUMBER='(2)';
      PIN_TYPE='UNSPEC';
      PINUSE='UNSPEC';
  end_pin;
  body
      PART_NAME='Q_RES';
      PHYS_DES_PREFIX='R';
      STANDARD='End of Design';
      LIFECYCLE='Comp-Approve';
      JEDEC_TYPE='R0402';
      ALT_SYMBOLS='(R0402-0201)';
      VALUE='54.9K';
      TOL='1%';
      WATTAGE='1/16W';
      CLASS='IO';
      DESCRIPTION='RES CHIP 54.9K 1/16W  +-1%(0402)EF';
      COMPONENT_TYPE='CHIPR0402';
      LEAD_LENGTH='';
      DFM_EXCLUSION='';
      DAY='20180221';
      PARENT_PART_TYPE='Q_RES';
      PARENT_PPT='Q_RES';
      PARENT_PPT_PART='Q_RES_0402LF-54.9K,1%,1/16W,EMPTY,CS35492FB03';
  end_body;
end_primitive;
primitive 'Q_RES_0402LF-560,1%,1/16W,CHIPA';
  pin
    'A':
      PIN_GROUP='1';
      PIN_NUMBER='(1)';
      PIN_TYPE='UNSPEC';
      PINUSE='UNSPEC';
    'B':
      PIN_GROUP='1';
      PIN_NUMBER='(2)';
      PIN_TYPE='UNSPEC';
      PINUSE='UNSPEC';
  end_pin;
  body
      PART_NAME='Q_RES';
      PHYS_DES_PREFIX='R';
      STANDARD='';
      LIFECYCLE='';
      JEDEC_TYPE='R0402';
      ALT_SYMBOLS='(R0402-0201)';
      VALUE='560';
      TOL='1%';
      WATTAGE='1/16W';
      CLASS='DISCRETE';
      DESCRIPTION='RES CHIP 560 1/16W +-1%(0402)EF';
      COMPONENT_TYPE='CHIPR0402';
      LEAD_LENGTH='';
      DFM_EXCLUSION='';
      DAY='20190904';
      PARENT_PART_TYPE='Q_RES';
      PARENT_PPT='Q_RES';
      PARENT_PPT_PART='Q_RES_0402LF-560,1%,1/16W,CHIP,CS15602FB03';
  end_body;
end_primitive;
primitive 'Q_RES_0402LF-56K,1%,1/16W,CHIPA';
  pin
    'A':
      PIN_GROUP='1';
      PIN_NUMBER='(1)';
      PIN_TYPE='UNSPEC';
      PINUSE='UNSPEC';
    'B':
      PIN_GROUP='1';
      PIN_NUMBER='(2)';
      PIN_TYPE='UNSPEC';
      PINUSE='UNSPEC';
  end_pin;
  body
      PART_NAME='Q_RES';
      PHYS_DES_PREFIX='R';
      STANDARD='';
      LIFECYCLE='';
      JEDEC_TYPE='R0402';
      ALT_SYMBOLS='(R0402-0201)';
      VALUE='56K';
      TOL='1%';
      WATTAGE='1/16W';
      CLASS='DISCRETE';
      DESCRIPTION='RES CHIP 56K 1/16W +-1%(0402)EF';
      COMPONENT_TYPE='CHIPR0402';
      LEAD_LENGTH='';
      DFM_EXCLUSION='';
      DAY='20190711';
      PARENT_PART_TYPE='Q_RES';
      PARENT_PPT='Q_RES';
      PARENT_PPT_PART='Q_RES_0402LF-56K,1%,1/16W,CHIP,CS35602FB00';
  end_body;
end_primitive;
primitive 'Q_RES_0402LF-6.19K,1%,1/16W,CHA';
  pin
    'A':
      PIN_GROUP='1';
      PIN_NUMBER='(1)';
      PIN_TYPE='UNSPEC';
      PINUSE='UNSPEC';
    'B':
      PIN_GROUP='1';
      PIN_NUMBER='(2)';
      PIN_TYPE='UNSPEC';
      PINUSE='UNSPEC';
  end_pin;
  body
      PART_NAME='Q_RES';
      PHYS_DES_PREFIX='R';
      STANDARD='End of Design';
      LIFECYCLE='Comp-Approve';
      JEDEC_TYPE='R0402';
      ALT_SYMBOLS='(R0402-0201)';
      VALUE='6.19K';
      TOL='1%';
      WATTAGE='1/16W';
      CLASS='DISCRETE';
      DESCRIPTION='RES CHIP 6.19K 1/16W +-1%(0402)EF';
      COMPONENT_TYPE='CHIPR0402';
      LEAD_LENGTH='';
      DFM_EXCLUSION='';
      DAY='20180221';
      PARENT_PART_TYPE='Q_RES';
      PARENT_PPT='Q_RES';
      PARENT_PPT_PART='Q_RES_0402LF-6.19K,1%,1/16W,CHIP,CS26192FB03';
  end_body;
end_primitive;
primitive 'Q_RES_0402LF-6.8K,1%,1/16W,EMPA';
  pin
    'A':
      PIN_GROUP='1';
      PIN_NUMBER='(1)';
      PIN_TYPE='UNSPEC';
      PINUSE='UNSPEC';
    'B':
      PIN_GROUP='1';
      PIN_NUMBER='(2)';
      PIN_TYPE='UNSPEC';
      PINUSE='UNSPEC';
  end_pin;
  body
      PART_NAME='Q_RES';
      PHYS_DES_PREFIX='R';
      STANDARD='';
      LIFECYCLE='';
      JEDEC_TYPE='R0402';
      ALT_SYMBOLS='(R0402-0201)';
      VALUE='6.8K';
      TOL='1%';
      WATTAGE='1/16W';
      CLASS='IO';
      DESCRIPTION='RES CHIP 6.8K 1/16W +-1%(0402)EF';
      COMPONENT_TYPE='CHIP0402';
      LEAD_LENGTH='';
      DFM_EXCLUSION='';
      DAY='20180212';
      PARENT_PART_TYPE='Q_RES';
      PARENT_PPT='Q_RES';
      PARENT_PPT_PART='Q_RES_0402LF-6.8K,1%,1/16W,EMPTY,CS26802FB02';
  end_body;
end_primitive;
primitive 'Q_RES_0402LF-60.4,1%,1/16W,CHIA';
  pin
    'A':
      PIN_GROUP='1';
      PIN_NUMBER='(1)';
      PIN_TYPE='UNSPEC';
      PINUSE='UNSPEC';
    'B':
      PIN_GROUP='1';
      PIN_NUMBER='(2)';
      PIN_TYPE='UNSPEC';
      PINUSE='UNSPEC';
  end_pin;
  body
      PART_NAME='Q_RES';
      PHYS_DES_PREFIX='R';
      STANDARD='End of Design';
      LIFECYCLE='Comp-Approve';
      JEDEC_TYPE='R0402';
      ALT_SYMBOLS='(R0402-0201)';
      VALUE='60.4';
      TOL='1%';
      WATTAGE='1/16W';
      CLASS='DISCRETE';
      DESCRIPTION='RES CHIP 60.4 1/16W +-1%(0402)EF';
      COMPONENT_TYPE='CHIPR0402';
      LEAD_LENGTH='';
      DFM_EXCLUSION='';
      DAY='20180221';
      PARENT_PART_TYPE='Q_RES';
      PARENT_PPT='Q_RES';
      PARENT_PPT_PART='Q_RES_0402LF-60.4,1%,1/16W,CHIP,CS06042FB03';
  end_body;
end_primitive;
primitive 'Q_RES_0402LF-60.4K,1%,1/16W,CHA';
  pin
    'A':
      PIN_GROUP='1';
      PIN_NUMBER='(1)';
      PIN_TYPE='UNSPEC';
      PINUSE='UNSPEC';
    'B':
      PIN_GROUP='1';
      PIN_NUMBER='(2)';
      PIN_TYPE='UNSPEC';
      PINUSE='UNSPEC';
  end_pin;
  body
      PART_NAME='Q_RES';
      PHYS_DES_PREFIX='R';
      STANDARD='End of Design';
      LIFECYCLE='Comp-Approve';
      JEDEC_TYPE='R0402';
      ALT_SYMBOLS='(R0402-0201)';
      VALUE='60.4K';
      TOL='1%';
      WATTAGE='1/16W';
      CLASS='DISCRETE';
      DESCRIPTION='RES CHIP 60.4K 1/16W +-1%(0402)EF';
      COMPONENT_TYPE='CHIP0402';
      LEAD_LENGTH='';
      DFM_EXCLUSION='';
      DAY='20180212';
      PARENT_PART_TYPE='Q_RES';
      PARENT_PPT='Q_RES';
      PARENT_PPT_PART='Q_RES_0402LF-60.4K,1%,1/16W,CHIP,CS36042FB04';
  end_body;
end_primitive;
primitive 'Q_RES_0402LF-63.4K,1%,1/16W,CHA';
  pin
    'A':
      PIN_GROUP='1';
      PIN_NUMBER='(1)';
      PIN_TYPE='UNSPEC';
      PINUSE='UNSPEC';
    'B':
      PIN_GROUP='1';
      PIN_NUMBER='(2)';
      PIN_TYPE='UNSPEC';
      PINUSE='UNSPEC';
  end_pin;
  body
      PART_NAME='Q_RES';
      PHYS_DES_PREFIX='R';
      STANDARD='End of Design';
      LIFECYCLE='Comp-Approve';
      JEDEC_TYPE='R0402';
      ALT_SYMBOLS='(R0402-0201)';
      VALUE='63.4K';
      TOL='1%';
      WATTAGE='1/16W';
      CLASS='DISCRETE';
      DESCRIPTION='RES CHIP 63.4K 1/16W +-1%(0402)EF';
      COMPONENT_TYPE='CHIP0402';
      LEAD_LENGTH='';
      DFM_EXCLUSION='';
      DAY='20180212';
      PARENT_PART_TYPE='Q_RES';
      PARENT_PPT='Q_RES';
      PARENT_PPT_PART='Q_RES_0402LF-63.4K,1%,1/16W,CHIP,CS36342FB04';
  end_body;
end_primitive;
primitive 'Q_RES_0402LF-680,1%,1/16W,CHIPA';
  pin
    'A':
      PIN_GROUP='1';
      PIN_NUMBER='(1)';
      PIN_TYPE='UNSPEC';
      PINUSE='UNSPEC';
    'B':
      PIN_GROUP='1';
      PIN_NUMBER='(2)';
      PIN_TYPE='UNSPEC';
      PINUSE='UNSPEC';
  end_pin;
  body
      PART_NAME='Q_RES';
      PHYS_DES_PREFIX='R';
      STANDARD='';
      LIFECYCLE='';
      JEDEC_TYPE='R0402';
      ALT_SYMBOLS='(R0402-0201)';
      VALUE='680';
      TOL='1%';
      WATTAGE='1/16W';
      CLASS='DISCRETE';
      DESCRIPTION='RES CHIP 680 1/16W +-1%(0402)EF';
      COMPONENT_TYPE='CHIPR0402';
      LEAD_LENGTH='';
      DFM_EXCLUSION='';
      DAY='20190829';
      PARENT_PART_TYPE='Q_RES';
      PARENT_PPT='Q_RES';
      PARENT_PPT_PART='Q_RES_0402LF-680,1%,1/16W,CHIP,CS16802FB03';
  end_body;
end_primitive;
primitive 'Q_RES_0402LF-680,1%,1/16W,EMPTA';
  pin
    'A':
      PIN_GROUP='1';
      PIN_NUMBER='(1)';
      PIN_TYPE='UNSPEC';
      PINUSE='UNSPEC';
    'B':
      PIN_GROUP='1';
      PIN_NUMBER='(2)';
      PIN_TYPE='UNSPEC';
      PINUSE='UNSPEC';
  end_pin;
  body
      PART_NAME='Q_RES';
      PHYS_DES_PREFIX='R';
      STANDARD='';
      LIFECYCLE='';
      JEDEC_TYPE='R0402';
      ALT_SYMBOLS='(R0402-0201)';
      VALUE='680';
      TOL='1%';
      WATTAGE='1/16W';
      CLASS='IO';
      DESCRIPTION='RES CHIP 680 1/16W +-1%(0402)EF';
      COMPONENT_TYPE='CHIPR0402';
      LEAD_LENGTH='';
      DFM_EXCLUSION='';
      DAY='20190829';
      PARENT_PART_TYPE='Q_RES';
      PARENT_PPT='Q_RES';
      PARENT_PPT_PART='Q_RES_0402LF-680,1%,1/16W,EMPTY,CS16802FB03';
  end_body;
end_primitive;
primitive 'Q_RES_0402LF-681,1%,1/16W,CHIPA';
  pin
    'A':
      PIN_GROUP='1';
      PIN_NUMBER='(1)';
      PIN_TYPE='UNSPEC';
      PINUSE='UNSPEC';
    'B':
      PIN_GROUP='1';
      PIN_NUMBER='(2)';
      PIN_TYPE='UNSPEC';
      PINUSE='UNSPEC';
  end_pin;
  body
      PART_NAME='Q_RES';
      PHYS_DES_PREFIX='R';
      STANDARD='End of Design';
      LIFECYCLE='Comp-Approve';
      JEDEC_TYPE='R0402';
      ALT_SYMBOLS='(R0402-0201)';
      VALUE='681';
      TOL='1%';
      WATTAGE='1/16W';
      CLASS='DISCRETE';
      DESCRIPTION='RES CHIP 681 1/16W +-1%(0402)EF';
      COMPONENT_TYPE='CHIPR0402';
      LEAD_LENGTH='';
      DFM_EXCLUSION='';
      DAY='20190325';
      PARENT_PART_TYPE='Q_RES';
      PARENT_PPT='Q_RES';
      PARENT_PPT_PART='Q_RES_0402LF-681,1%,1/16W,CHIP,CS16812FB02';
  end_body;
end_primitive;
primitive 'Q_RES_0402LF-68K,1%,1/16W,CHIPA';
  pin
    'A':
      PIN_GROUP='1';
      PIN_NUMBER='(1)';
      PIN_TYPE='UNSPEC';
      PINUSE='UNSPEC';
    'B':
      PIN_GROUP='1';
      PIN_NUMBER='(2)';
      PIN_TYPE='UNSPEC';
      PINUSE='UNSPEC';
  end_pin;
  body
      PART_NAME='Q_RES';
      PHYS_DES_PREFIX='R';
      STANDARD='End of Design';
      LIFECYCLE='Comp-Approve';
      JEDEC_TYPE='R0402';
      ALT_SYMBOLS='(R0402-0201)';
      VALUE='68K';
      TOL='1%';
      WATTAGE='1/16W';
      CLASS='DISCRETE';
      DESCRIPTION='RES CHIP 68K 1/16W +-1%(0402)EF';
      COMPONENT_TYPE='CHIPR0402';
      LEAD_LENGTH='';
      DFM_EXCLUSION='';
      DAY='20190906';
      PARENT_PART_TYPE='Q_RES';
      PARENT_PPT='Q_RES';
      PARENT_PPT_PART='Q_RES_0402LF-68K,1%,1/16W,CHIP,CS36802FB04';
  end_body;
end_primitive;
primitive 'Q_RES_0402LF-68K,1%,1/16W,EMPTA';
  pin
    'A':
      PIN_GROUP='1';
      PIN_NUMBER='(1)';
      PIN_TYPE='UNSPEC';
      PINUSE='UNSPEC';
    'B':
      PIN_GROUP='1';
      PIN_NUMBER='(2)';
      PIN_TYPE='UNSPEC';
      PINUSE='UNSPEC';
  end_pin;
  body
      PART_NAME='Q_RES';
      PHYS_DES_PREFIX='R';
      STANDARD='End of Design';
      LIFECYCLE='Comp-Approve';
      JEDEC_TYPE='R0402';
      ALT_SYMBOLS='(R0402-0201)';
      VALUE='68K';
      TOL='1%';
      WATTAGE='1/16W';
      CLASS='IO';
      DESCRIPTION='RES CHIP 68K 1/16W +-1%(0402)EF';
      COMPONENT_TYPE='CHIPR0402';
      LEAD_LENGTH='';
      DFM_EXCLUSION='';
      DAY='20190906';
      PARENT_PART_TYPE='Q_RES';
      PARENT_PPT='Q_RES';
      PARENT_PPT_PART='Q_RES_0402LF-68K,1%,1/16W,EMPTY,CS36802FB04';
  end_body;
end_primitive;
primitive 'Q_RES_0402LF-7.15K,1%,1/16W,CHA';
  pin
    'A':
      PIN_GROUP='1';
      PIN_NUMBER='(1)';
      PIN_TYPE='UNSPEC';
      PINUSE='UNSPEC';
    'B':
      PIN_GROUP='1';
      PIN_NUMBER='(2)';
      PIN_TYPE='UNSPEC';
      PINUSE='UNSPEC';
  end_pin;
  body
      PART_NAME='Q_RES';
      PHYS_DES_PREFIX='R';
      STANDARD='End of Design';
      LIFECYCLE='Comp-Approve';
      JEDEC_TYPE='R0402';
      ALT_SYMBOLS='(R0402-0201)';
      VALUE='7.15K';
      TOL='1%';
      WATTAGE='1/16W';
      CLASS='DISCRETE';
      DESCRIPTION='RES CHIP 7.15K 1/16W +-1%(0402)EF';
      COMPONENT_TYPE='CHIPR0402';
      LEAD_LENGTH='';
      DFM_EXCLUSION='';
      DAY='20200609';
      PARENT_PART_TYPE='Q_RES';
      PARENT_PPT='Q_RES';
      PARENT_PPT_PART='Q_RES_0402LF-7.15K,1%,1/16W,CHIP,CS27152FB03';
  end_body;
end_primitive;
primitive 'Q_RES_0402LF-7.32K,0.1%,1/16W,A';
  pin
    'A':
      PIN_GROUP='1';
      PIN_NUMBER='(1)';
      PIN_TYPE='UNSPEC';
      PINUSE='UNSPEC';
    'B':
      PIN_GROUP='1';
      PIN_NUMBER='(2)';
      PIN_TYPE='UNSPEC';
      PINUSE='UNSPEC';
  end_pin;
  body
      PART_NAME='Q_RES';
      PHYS_DES_PREFIX='R';
      STANDARD='';
      LIFECYCLE='';
      JEDEC_TYPE='R0402';
      ALT_SYMBOLS='(R0402-0201)';
      VALUE='7.32K';
      TOL='0.1%';
      WATTAGE='1/16W';
      CLASS='DISCRETE';
      DESCRIPTION='RES CHIP 7.32K 1/16W +-0.1% (0402)EF';
      COMPONENT_TYPE='CHIPR0402';
      LEAD_LENGTH='';
      DFM_EXCLUSION='';
      DAY='20210719';
      PARENT_PART_TYPE='Q_RES';
      PARENT_PPT='Q_RES';
      PARENT_PPT_PART='Q_RES_0402LF-7.32K,0.1%,1/16W,CHIP,CS27322BB09';
  end_body;
end_primitive;
primitive 'Q_RES_0402LF-7.87K,1%,1/16W,CHA';
  pin
    'A':
      PIN_GROUP='1';
      PIN_NUMBER='(1)';
      PIN_TYPE='UNSPEC';
      PINUSE='UNSPEC';
    'B':
      PIN_GROUP='1';
      PIN_NUMBER='(2)';
      PIN_TYPE='UNSPEC';
      PINUSE='UNSPEC';
  end_pin;
  body
      PART_NAME='Q_RES';
      PHYS_DES_PREFIX='R';
      STANDARD='End of Design';
      LIFECYCLE='Comp-Approve';
      JEDEC_TYPE='R0402';
      ALT_SYMBOLS='(R0402-0201)';
      VALUE='7.87K';
      TOL='1%';
      WATTAGE='1/16W';
      CLASS='DISCRETE';
      DESCRIPTION='RES CHIP 7.87K 1/16W +-1%(0402)EF';
      COMPONENT_TYPE='CHIPR0402';
      LEAD_LENGTH='';
      DFM_EXCLUSION='';
      DAY='20190820';
      PARENT_PART_TYPE='Q_RES';
      PARENT_PPT='Q_RES';
      PARENT_PPT_PART='Q_RES_0402LF-7.87K,1%,1/16W,CHIP,CS27872FB02';
  end_body;
end_primitive;
primitive 'Q_RES_0402LF-71.5K,1%,1/16W,EMA';
  pin
    'A':
      PIN_GROUP='1';
      PIN_NUMBER='(1)';
      PIN_TYPE='UNSPEC';
      PINUSE='UNSPEC';
    'B':
      PIN_GROUP='1';
      PIN_NUMBER='(2)';
      PIN_TYPE='UNSPEC';
      PINUSE='UNSPEC';
  end_pin;
  body
      PART_NAME='Q_RES';
      PHYS_DES_PREFIX='R';
      STANDARD='';
      LIFECYCLE='';
      JEDEC_TYPE='R0402';
      ALT_SYMBOLS='(R0402-0201)';
      VALUE='71.5K';
      TOL='1%';
      WATTAGE='1/16W';
      CLASS='IO';
      DESCRIPTION='RES CHIP 71.5K 1/16W +-1%(0402)EF';
      COMPONENT_TYPE='CHIPR0402';
      LEAD_LENGTH='';
      DFM_EXCLUSION='';
      DAY='20190717';
      PARENT_PART_TYPE='Q_RES';
      PARENT_PPT='Q_RES';
      PARENT_PPT_PART='Q_RES_0402LF-71.5K,1%,1/16W,EMPTY,CS37152FB05';
  end_body;
end_primitive;
primitive 'Q_RES_0402LF-75,1%,1/16W,CHIP,A';
  pin
    'A':
      PIN_GROUP='1';
      PIN_NUMBER='(1)';
      PIN_TYPE='UNSPEC';
      PINUSE='UNSPEC';
    'B':
      PIN_GROUP='1';
      PIN_NUMBER='(2)';
      PIN_TYPE='UNSPEC';
      PINUSE='UNSPEC';
  end_pin;
  body
      PART_NAME='Q_RES';
      PHYS_DES_PREFIX='R';
      STANDARD='End of Design';
      LIFECYCLE='Comp-Approve';
      JEDEC_TYPE='R0402';
      ALT_SYMBOLS='(R0402-0201)';
      VALUE='75';
      TOL='1%';
      WATTAGE='1/16W';
      CLASS='DISCRETE';
      DESCRIPTION='RES CHIP 75 1/16W +-1%(0402)EF';
      COMPONENT_TYPE='CHIPR0402';
      LEAD_LENGTH='';
      DFM_EXCLUSION='';
      DAY='20180221';
      PARENT_PART_TYPE='Q_RES';
      PARENT_PPT='Q_RES';
      PARENT_PPT_PART='Q_RES_0402LF-75,1%,1/16W,CHIP,CS07502FB04';
  end_body;
end_primitive;
primitive 'Q_RES_0402LF-75,1%,1/16W,EMPTYA';
  pin
    'A':
      PIN_GROUP='1';
      PIN_NUMBER='(1)';
      PIN_TYPE='UNSPEC';
      PINUSE='UNSPEC';
    'B':
      PIN_GROUP='1';
      PIN_NUMBER='(2)';
      PIN_TYPE='UNSPEC';
      PINUSE='UNSPEC';
  end_pin;
  body
      PART_NAME='Q_RES';
      PHYS_DES_PREFIX='R';
      STANDARD='End of Design';
      LIFECYCLE='Comp-Approve';
      JEDEC_TYPE='R0402';
      ALT_SYMBOLS='(R0402-0201)';
      VALUE='75';
      TOL='1%';
      WATTAGE='1/16W';
      CLASS='IO';
      DESCRIPTION='RES CHIP 75 1/16W +-1%(0402)EF';
      COMPONENT_TYPE='CHIPR0402';
      LEAD_LENGTH='';
      DFM_EXCLUSION='';
      DAY='20180221';
      PARENT_PART_TYPE='Q_RES';
      PARENT_PPT='Q_RES';
      PARENT_PPT_PART='Q_RES_0402LF-75,1%,1/16W,EMPTY,CS07502FB04';
  end_body;
end_primitive;
primitive 'Q_RES_0402LF-75K,0.1%,1/16W,CHA';
  pin
    'A':
      PIN_GROUP='1';
      PIN_NUMBER='(1)';
      PIN_TYPE='UNSPEC';
      PINUSE='UNSPEC';
    'B':
      PIN_GROUP='1';
      PIN_NUMBER='(2)';
      PIN_TYPE='UNSPEC';
      PINUSE='UNSPEC';
  end_pin;
  body
      PART_NAME='Q_RES';
      PHYS_DES_PREFIX='R';
      STANDARD='';
      LIFECYCLE='';
      JEDEC_TYPE='R0402';
      ALT_SYMBOLS='(R0402-0201)';
      VALUE='75K';
      TOL='0.1%';
      WATTAGE='1/16W';
      CLASS='DISCRETE';
      DESCRIPTION='RES CHIP 75K 1/16W +-0.1%(0402)EF';
      COMPONENT_TYPE='CHIPR0402';
      LEAD_LENGTH='';
      DFM_EXCLUSION='';
      DAY='20211207';
      PARENT_PART_TYPE='Q_RES';
      PARENT_PPT='Q_RES';
      PARENT_PPT_PART='Q_RES_0402LF-75K,0.1%,1/16W,CHIP,CS37502BB01';
  end_body;
end_primitive;
primitive 'Q_RES_0402LF-8.25K,0.1%,1/16W,A';
  pin
    'A':
      PIN_GROUP='1';
      PIN_NUMBER='(1)';
      PIN_TYPE='UNSPEC';
      PINUSE='UNSPEC';
    'B':
      PIN_GROUP='1';
      PIN_NUMBER='(2)';
      PIN_TYPE='UNSPEC';
      PINUSE='UNSPEC';
  end_pin;
  body
      PART_NAME='Q_RES';
      PHYS_DES_PREFIX='R';
      STANDARD='';
      LIFECYCLE='';
      JEDEC_TYPE='R0402';
      ALT_SYMBOLS='(R0402-0201)';
      VALUE='8.25K';
      TOL='0.1%';
      WATTAGE='1/16W';
      CLASS='DISCRETE';
      DESCRIPTION='RES CHIP 8.25K 1/16W +-0.1%(0402)EF';
      COMPONENT_TYPE='CHIPR0402';
      LEAD_LENGTH='';
      DFM_EXCLUSION='';
      DAY='20190717';
      PARENT_PART_TYPE='Q_RES';
      PARENT_PPT='Q_RES';
      PARENT_PPT_PART='Q_RES_0402LF-8.25K,0.1%,1/16W,CHIP,CS28252BB01';
  end_body;
end_primitive;
primitive 'Q_RES_0402LF-8.45K,1%,1/16W,CHA';
  pin
    'A':
      PIN_GROUP='1';
      PIN_NUMBER='(1)';
      PIN_TYPE='UNSPEC';
      PINUSE='UNSPEC';
    'B':
      PIN_GROUP='1';
      PIN_NUMBER='(2)';
      PIN_TYPE='UNSPEC';
      PINUSE='UNSPEC';
  end_pin;
  body
      PART_NAME='Q_RES';
      PHYS_DES_PREFIX='R';
      STANDARD='';
      LIFECYCLE='';
      JEDEC_TYPE='R0402';
      ALT_SYMBOLS='(R0402-0201)';
      VALUE='8.45K';
      TOL='1%';
      WATTAGE='1/16W';
      CLASS='DISCRETE';
      DESCRIPTION='RES CHIP 8.45K 1/16W +-1%( 0402)EF';
      COMPONENT_TYPE='CHIP0402';
      LEAD_LENGTH='';
      DFM_EXCLUSION='';
      DAY='20180212';
      PARENT_PART_TYPE='Q_RES';
      PARENT_PPT='Q_RES';
      PARENT_PPT_PART='Q_RES_0402LF-8.45K,1%,1/16W,CHIP,CS28452FB06';
  end_body;
end_primitive;
primitive 'Q_RES_0402LF-8.45K,1%,1/16W,EMA';
  pin
    'A':
      PIN_GROUP='1';
      PIN_NUMBER='(1)';
      PIN_TYPE='UNSPEC';
      PINUSE='UNSPEC';
    'B':
      PIN_GROUP='1';
      PIN_NUMBER='(2)';
      PIN_TYPE='UNSPEC';
      PINUSE='UNSPEC';
  end_pin;
  body
      PART_NAME='Q_RES';
      PHYS_DES_PREFIX='R';
      STANDARD='';
      LIFECYCLE='';
      JEDEC_TYPE='R0402';
      ALT_SYMBOLS='(R0402-0201)';
      VALUE='8.45K';
      TOL='1%';
      WATTAGE='1/16W';
      CLASS='IO';
      DESCRIPTION='RES CHIP 8.45K 1/16W +-1%( 0402)EF';
      COMPONENT_TYPE='CHIP0402';
      LEAD_LENGTH='';
      DFM_EXCLUSION='';
      DAY='20180212';
      PARENT_PART_TYPE='Q_RES';
      PARENT_PPT='Q_RES';
      PARENT_PPT_PART='Q_RES_0402LF-8.45K,1%,1/16W,EMPTY,CS28452FB06';
  end_body;
end_primitive;
primitive 'Q_RES_0402LF-8.87K,1%,1/16W,EMA';
  pin
    'A':
      PIN_GROUP='1';
      PIN_NUMBER='(1)';
      PIN_TYPE='UNSPEC';
      PINUSE='UNSPEC';
    'B':
      PIN_GROUP='1';
      PIN_NUMBER='(2)';
      PIN_TYPE='UNSPEC';
      PINUSE='UNSPEC';
  end_pin;
  body
      PART_NAME='Q_RES';
      PHYS_DES_PREFIX='R';
      STANDARD='End of Design';
      LIFECYCLE='Comp-Approve';
      JEDEC_TYPE='R0402';
      ALT_SYMBOLS='(R0402-0201)';
      VALUE='8.87K';
      TOL='1%';
      WATTAGE='1/16W';
      CLASS='IO';
      DESCRIPTION='RES CHIP 8.87K 1/16W +-1%(0402)EF';
      COMPONENT_TYPE='CHIPR0402';
      LEAD_LENGTH='';
      DFM_EXCLUSION='';
      DAY='20190718';
      PARENT_PART_TYPE='Q_RES';
      PARENT_PPT='Q_RES';
      PARENT_PPT_PART='Q_RES_0402LF-8.87K,1%,1/16W,EMPTY,CS28872FB01';
  end_body;
end_primitive;
primitive 'Q_RES_0402LF-82K,1%,1/16W,CHIPA';
  pin
    'A':
      PIN_GROUP='1';
      PIN_NUMBER='(1)';
      PIN_TYPE='UNSPEC';
      PINUSE='UNSPEC';
    'B':
      PIN_GROUP='1';
      PIN_NUMBER='(2)';
      PIN_TYPE='UNSPEC';
      PINUSE='UNSPEC';
  end_pin;
  body
      PART_NAME='Q_RES';
      PHYS_DES_PREFIX='R';
      STANDARD='End of Design';
      LIFECYCLE='Comp-Approve';
      JEDEC_TYPE='R0402';
      ALT_SYMBOLS='(R0402-0201)';
      VALUE='82K';
      TOL='1%';
      WATTAGE='1/16W';
      CLASS='DISCRETE';
      DESCRIPTION='RES CHIP 82K  1/16W +-1% (0402)EF';
      COMPONENT_TYPE='CHIPR0402';
      LEAD_LENGTH='';
      DFM_EXCLUSION='';
      DAY='20190718';
      PARENT_PART_TYPE='Q_RES';
      PARENT_PPT='Q_RES';
      PARENT_PPT_PART='Q_RES_0402LF-82K,1%,1/16W,CHIP,CS38202FB01';
  end_body;
end_primitive;
primitive 'Q_RES_0402LF-84.5K,1%,1/16W,CHA';
  pin
    'A':
      PIN_GROUP='1';
      PIN_NUMBER='(1)';
      PIN_TYPE='UNSPEC';
      PINUSE='UNSPEC';
    'B':
      PIN_GROUP='1';
      PIN_NUMBER='(2)';
      PIN_TYPE='UNSPEC';
      PINUSE='UNSPEC';
  end_pin;
  body
      PART_NAME='Q_RES';
      PHYS_DES_PREFIX='R';
      STANDARD='End of Design';
      LIFECYCLE='Comp-Approve';
      JEDEC_TYPE='R0402';
      ALT_SYMBOLS='(R0402-0201)';
      VALUE='84.5K';
      TOL='1%';
      WATTAGE='1/16W';
      CLASS='DISCRETE';
      DESCRIPTION='RES CHIP 84.5K 1/16W +-1%(0402)EF';
      COMPONENT_TYPE='CHIPR0402';
      LEAD_LENGTH='';
      DFM_EXCLUSION='';
      DAY='20210715';
      PARENT_PART_TYPE='Q_RES';
      PARENT_PPT='Q_RES';
      PARENT_PPT_PART='Q_RES_0402LF-84.5K,1%,1/16W,CHIP,CS38452FB05';
  end_body;
end_primitive;
primitive 'Q_RES_0402LF-845,1%,1/16W,EMPTA';
  pin
    'A':
      PIN_GROUP='1';
      PIN_NUMBER='(1)';
      PIN_TYPE='UNSPEC';
      PINUSE='UNSPEC';
    'B':
      PIN_GROUP='1';
      PIN_NUMBER='(2)';
      PIN_TYPE='UNSPEC';
      PINUSE='UNSPEC';
  end_pin;
  body
      PART_NAME='Q_RES';
      PHYS_DES_PREFIX='R';
      STANDARD='End of Design';
      LIFECYCLE='Comp-Approve';
      JEDEC_TYPE='R0402';
      ALT_SYMBOLS='(R0402-0201)';
      VALUE='845';
      TOL='1%';
      WATTAGE='1/16W';
      CLASS='IO';
      DESCRIPTION='RES CHIP 845 1/16W +-1%(0402)EF';
      COMPONENT_TYPE='CHIPR0402';
      LEAD_LENGTH='';
      DFM_EXCLUSION='';
      DAY='20180221';
      PARENT_PART_TYPE='Q_RES';
      PARENT_PPT='Q_RES';
      PARENT_PPT_PART='Q_RES_0402LF-845,1%,1/16W,EMPTY,CS18452FB01';
  end_body;
end_primitive;
primitive 'Q_RES_0402LF-86.6K,1%,1/16W,EMA';
  pin
    'A':
      PIN_GROUP='1';
      PIN_NUMBER='(1)';
      PIN_TYPE='UNSPEC';
      PINUSE='UNSPEC';
    'B':
      PIN_GROUP='1';
      PIN_NUMBER='(2)';
      PIN_TYPE='UNSPEC';
      PINUSE='UNSPEC';
  end_pin;
  body
      PART_NAME='Q_RES';
      PHYS_DES_PREFIX='R';
      STANDARD='End of Design';
      LIFECYCLE='Comp-Approve';
      JEDEC_TYPE='R0402';
      ALT_SYMBOLS='(R0402-0201)';
      VALUE='86.6K';
      TOL='1%';
      WATTAGE='1/16W';
      CLASS='IO';
      DESCRIPTION='RES CHIP 86.6K 1/16W +-1%(0402)EF';
      COMPONENT_TYPE='CHIPR0402';
      LEAD_LENGTH='';
      DFM_EXCLUSION='';
      DAY='20180221';
      PARENT_PART_TYPE='Q_RES';
      PARENT_PPT='Q_RES';
      PARENT_PPT_PART='Q_RES_0402LF-86.6K,1%,1/16W,EMPTY,CS38662FB05';
  end_body;
end_primitive;
primitive 'Q_RES_0402LF-88.7K,1%,1/16W,CHA';
  pin
    'A':
      PIN_GROUP='1';
      PIN_NUMBER='(1)';
      PIN_TYPE='UNSPEC';
      PINUSE='UNSPEC';
    'B':
      PIN_GROUP='1';
      PIN_NUMBER='(2)';
      PIN_TYPE='UNSPEC';
      PINUSE='UNSPEC';
  end_pin;
  body
      PART_NAME='Q_RES';
      PHYS_DES_PREFIX='R';
      STANDARD='End of Design';
      LIFECYCLE='Comp-Approve';
      JEDEC_TYPE='R0402';
      ALT_SYMBOLS='(R0402-0201)';
      VALUE='88.7K';
      TOL='1%';
      WATTAGE='1/16W';
      CLASS='DISCRETE';
      DESCRIPTION='RES CHIP 88.7K 1/16W +-1%(0402)';
      COMPONENT_TYPE='CHIP0402';
      LEAD_LENGTH='';
      DFM_EXCLUSION='';
      DAY='20110812';
      PARENT_PART_TYPE='Q_RES';
      PARENT_PPT='Q_RES';
      PARENT_PPT_PART='Q_RES_0402LF-88.7K,1%,1/16W,CHIP,CS38872FB18';
  end_body;
end_primitive;
primitive 'Q_RES_0402LF-9.09K,1%,1/16W,CHA';
  pin
    'A':
      PIN_GROUP='1';
      PIN_NUMBER='(1)';
      PIN_TYPE='UNSPEC';
      PINUSE='UNSPEC';
    'B':
      PIN_GROUP='1';
      PIN_NUMBER='(2)';
      PIN_TYPE='UNSPEC';
      PINUSE='UNSPEC';
  end_pin;
  body
      PART_NAME='Q_RES';
      PHYS_DES_PREFIX='R';
      STANDARD='End of Design';
      LIFECYCLE='Comp-Approve';
      JEDEC_TYPE='R0402';
      ALT_SYMBOLS='(R0402-0201)';
      VALUE='9.09K';
      TOL='1%';
      WATTAGE='1/16W';
      CLASS='DISCRETE';
      DESCRIPTION='RES CHIP 9.09K 1/16W +-1%(0402)EF';
      COMPONENT_TYPE='CHIPR0402';
      LEAD_LENGTH='';
      DFM_EXCLUSION='';
      DAY='20210715';
      PARENT_PART_TYPE='Q_RES';
      PARENT_PPT='Q_RES';
      PARENT_PPT_PART='Q_RES_0402LF-9.09K,1%,1/16W,CHIP,CS29092FB05';
  end_body;
end_primitive;
primitive 'Q_RES_0402LF-9.31K,1%,1/16W,EMA';
  pin
    'A':
      PIN_GROUP='1';
      PIN_NUMBER='(1)';
      PIN_TYPE='UNSPEC';
      PINUSE='UNSPEC';
    'B':
      PIN_GROUP='1';
      PIN_NUMBER='(2)';
      PIN_TYPE='UNSPEC';
      PINUSE='UNSPEC';
  end_pin;
  body
      PART_NAME='Q_RES';
      PHYS_DES_PREFIX='R';
      STANDARD='End of Design';
      LIFECYCLE='Comp-Approve';
      JEDEC_TYPE='R0402';
      ALT_SYMBOLS='(R0402-0201)';
      VALUE='9.31K';
      TOL='1%';
      WATTAGE='1/16W';
      CLASS='IO';
      DESCRIPTION='RES CHIP 9.31K 1/16W +-1%(0402)EF';
      COMPONENT_TYPE='CHIPR0402';
      LEAD_LENGTH='';
      DFM_EXCLUSION='';
      DAY='20180221';
      PARENT_PART_TYPE='Q_RES';
      PARENT_PPT='Q_RES';
      PARENT_PPT_PART='Q_RES_0402LF-9.31K,1%,1/16W,EMPTY,CS29312FB02';
  end_body;
end_primitive;
primitive 'Q_RES_0402LF-9.76K,1%,1/16W,CHA';
  pin
    'A':
      PIN_GROUP='1';
      PIN_NUMBER='(1)';
      PIN_TYPE='UNSPEC';
      PINUSE='UNSPEC';
    'B':
      PIN_GROUP='1';
      PIN_NUMBER='(2)';
      PIN_TYPE='UNSPEC';
      PINUSE='UNSPEC';
  end_pin;
  body
      PART_NAME='Q_RES';
      PHYS_DES_PREFIX='R';
      STANDARD='End of Design';
      LIFECYCLE='Comp-Approve';
      JEDEC_TYPE='R0402';
      ALT_SYMBOLS='(R0402-0201)';
      VALUE='9.76K';
      TOL='1%';
      WATTAGE='1/16W';
      CLASS='DISCRETE';
      DESCRIPTION='RES CHIP 9.76K 1/16W +-1%(0402)EF';
      COMPONENT_TYPE='CHIP0402';
      LEAD_LENGTH='';
      DFM_EXCLUSION='';
      DAY='20180212';
      PARENT_PART_TYPE='Q_RES';
      PARENT_PPT='Q_RES';
      PARENT_PPT_PART='Q_RES_0402LF-9.76K,1%,1/16W,CHIP,CS29762FB05';
  end_body;
end_primitive;
primitive 'Q_RES_0603LF-1,1%,1/10W,CHIP,CA';
  pin
    'A':
      PIN_GROUP='1';
      PIN_NUMBER='(1)';
      PIN_TYPE='UNSPEC';
      PINUSE='UNSPEC';
    'B':
      PIN_GROUP='1';
      PIN_NUMBER='(2)';
      PIN_TYPE='UNSPEC';
      PINUSE='UNSPEC';
  end_pin;
  body
      PART_NAME='Q_RES';
      PHYS_DES_PREFIX='R';
      STANDARD='End of Design';
      LIFECYCLE='Comp-Approve';
      JEDEC_TYPE='R0603_H24';
      ALT_SYMBOLS='(SMR0603AW)';
      VALUE='1';
      TOL='1%';
      WATTAGE='1/10W';
      CLASS='DISCRETE';
      DESCRIPTION='RES CHIP 1 1/10W +-1%(0603)EF';
      COMPONENT_TYPE='CHIPR0603';
      LEAD_LENGTH='';
      DFM_EXCLUSION='';
      DAY='20190904';
      PARENT_PART_TYPE='Q_RES';
      PARENT_PPT='Q_RES';
      PARENT_PPT_PART='Q_RES_0603LF-1,1%,1/10W,CHIP,CS-1003F900';
  end_body;
end_primitive;
primitive 'Q_RES_0603LF-10M,1%,1/10W,CHIPA';
  pin
    'A':
      PIN_GROUP='1';
      PIN_NUMBER='(1)';
      PIN_TYPE='UNSPEC';
      PINUSE='UNSPEC';
    'B':
      PIN_GROUP='1';
      PIN_NUMBER='(2)';
      PIN_TYPE='UNSPEC';
      PINUSE='UNSPEC';
  end_pin;
  body
      PART_NAME='Q_RES';
      PHYS_DES_PREFIX='R';
      STANDARD='End of Design';
      LIFECYCLE='Comp-Approve';
      JEDEC_TYPE='R0603';
      ALT_SYMBOLS='(SMR0603AW)';
      VALUE='10M';
      TOL='1%';
      WATTAGE='1/10W';
      CLASS='DISCRETE';
      DESCRIPTION='RES CHIP 10M 1/10W +-1%(0603)EF';
      COMPONENT_TYPE='CHIPR0603';
      LEAD_LENGTH='';
      DFM_EXCLUSION='';
      DAY='20180221';
      PARENT_PART_TYPE='Q_RES';
      PARENT_PPT='Q_RES';
      PARENT_PPT_PART='Q_RES_0603LF-10M,1%,1/10W,CHIP,CS61003F901';
  end_body;
end_primitive;
primitive 'Q_RES_0603LF-2.2,1%,1/10W,CHIPA';
  pin
    'A':
      PIN_GROUP='1';
      PIN_NUMBER='(1)';
      PIN_TYPE='UNSPEC';
      PINUSE='UNSPEC';
    'B':
      PIN_GROUP='1';
      PIN_NUMBER='(2)';
      PIN_TYPE='UNSPEC';
      PINUSE='UNSPEC';
  end_pin;
  body
      PART_NAME='Q_RES';
      PHYS_DES_PREFIX='R';
      STANDARD='End of Design';
      LIFECYCLE='Comp-Approve';
      JEDEC_TYPE='R0603';
      ALT_SYMBOLS='(SMR0603AW)';
      VALUE='2.2';
      TOL='1%';
      WATTAGE='1/10W';
      CLASS='DISCRETE';
      DESCRIPTION='RES CHIP 2.2 1/10W +-1%(0603)EF';
      COMPONENT_TYPE='CHIPR0603';
      LEAD_LENGTH='';
      DFM_EXCLUSION='';
      DAY='20180221';
      PARENT_PART_TYPE='Q_RES';
      PARENT_PPT='Q_RES';
      PARENT_PPT_PART='Q_RES_0603LF-2.2,1%,1/10W,CHIP,CS-2203F902';
  end_body;
end_primitive;
primitive 'Q_RES_0603LF-200K,0.1%,1/10W,EA';
  pin
    'A':
      PIN_GROUP='1';
      PIN_NUMBER='(1)';
      PIN_TYPE='UNSPEC';
      PINUSE='UNSPEC';
    'B':
      PIN_GROUP='1';
      PIN_NUMBER='(2)';
      PIN_TYPE='UNSPEC';
      PINUSE='UNSPEC';
  end_pin;
  body
      PART_NAME='Q_RES';
      PHYS_DES_PREFIX='R';
      STANDARD='End of Design';
      LIFECYCLE='Comp-Approve';
      JEDEC_TYPE='R0603_H24';
      ALT_SYMBOLS='(SMR0603AW)';
      VALUE='200K';
      TOL='0.1%';
      WATTAGE='1/10W';
      CLASS='IO';
      DESCRIPTION='RES CHIP 200K 1/10W +-0.1%(0603)EF';
      COMPONENT_TYPE='CHIPR0603';
      LEAD_LENGTH='';
      DFM_EXCLUSION='';
      DAY='20180213';
      PARENT_PART_TYPE='Q_RES';
      PARENT_PPT='Q_RES';
      PARENT_PPT_PART='Q_RES_0603LF-200K,0.1%,1/10W,EMPTY,CS42003B902';
  end_body;
end_primitive;
primitive 'Q_RES_0603LF-49.9,1%,1/10W,CHIA';
  pin
    'A':
      PIN_GROUP='1';
      PIN_NUMBER='(1)';
      PIN_TYPE='UNSPEC';
      PINUSE='UNSPEC';
    'B':
      PIN_GROUP='1';
      PIN_NUMBER='(2)';
      PIN_TYPE='UNSPEC';
      PINUSE='UNSPEC';
  end_pin;
  body
      PART_NAME='Q_RES';
      PHYS_DES_PREFIX='R';
      STANDARD='End of Design';
      LIFECYCLE='Comp-Approve';
      JEDEC_TYPE='R0603';
      ALT_SYMBOLS='(SMR0603AW)';
      VALUE='49.9';
      TOL='1%';
      WATTAGE='1/10W';
      CLASS='DISCRETE';
      DESCRIPTION='RES CHIP 49.9 1/10W +-1%(0603)EF';
      COMPONENT_TYPE='CHIPR0603';
      LEAD_LENGTH='';
      DFM_EXCLUSION='';
      DAY='20211026';
      PARENT_PART_TYPE='Q_RES';
      PARENT_PPT='Q_RES';
      PARENT_PPT_PART='Q_RES_0603LF-49.9,1%,1/10W,CHIP,CS04993F909';
  end_body;
end_primitive;
primitive 'Q_RES_0805LF-0,5%,1/8W,CHIP,CSA';
  pin
    'A':
      PIN_GROUP='1';
      PIN_NUMBER='(1)';
      PIN_TYPE='UNSPEC';
      PINUSE='UNSPEC';
    'B':
      PIN_GROUP='1';
      PIN_NUMBER='(2)';
      PIN_TYPE='UNSPEC';
      PINUSE='UNSPEC';
  end_pin;
  body
      PART_NAME='Q_RES';
      PHYS_DES_PREFIX='R';
      STANDARD='End of Design';
      LIFECYCLE='Comp-Approve';
      JEDEC_TYPE='R0805';
      ALT_SYMBOLS='(SMR0805AW)';
      VALUE='0';
      TOL='5%';
      WATTAGE='1/8W';
      CLASS='DISCRETE';
      DESCRIPTION='RES CHIP 0 1/8W +-5% (0805)EF';
      COMPONENT_TYPE='CHIPR0805';
      LEAD_LENGTH='';
      DFM_EXCLUSION='';
      DAY='20191218';
      PARENT_PART_TYPE='Q_RES';
      PARENT_PPT='Q_RES';
      PARENT_PPT_PART='Q_RES_0805LF-0,5%,1/8W,CHIP,CS00004JA05';
  end_body;
end_primitive;
primitive 'Q_RES_0805LF-0,5%,1/8W,EMPTY,CA';
  pin
    'A':
      PIN_GROUP='1';
      PIN_NUMBER='(1)';
      PIN_TYPE='UNSPEC';
      PINUSE='UNSPEC';
    'B':
      PIN_GROUP='1';
      PIN_NUMBER='(2)';
      PIN_TYPE='UNSPEC';
      PINUSE='UNSPEC';
  end_pin;
  body
      PART_NAME='Q_RES';
      PHYS_DES_PREFIX='R';
      STANDARD='End of Design';
      LIFECYCLE='Comp-Approve';
      JEDEC_TYPE='R0805';
      ALT_SYMBOLS='(SMR0805AW)';
      VALUE='0';
      TOL='5%';
      WATTAGE='1/8W';
      CLASS='IO';
      DESCRIPTION='RES CHIP 0 1/8W +-5% (0805)EF';
      COMPONENT_TYPE='CHIPR0805';
      LEAD_LENGTH='';
      DFM_EXCLUSION='';
      DAY='20191218';
      PARENT_PART_TYPE='Q_RES';
      PARENT_PPT='Q_RES';
      PARENT_PPT_PART='Q_RES_0805LF-0,5%,1/8W,EMPTY,CS00004JA05';
  end_body;
end_primitive;
primitive 'Q_RES_1206LF-0,,1/2W,CHIP,CS00A';
  pin
    'A':
      PIN_GROUP='1';
      PIN_NUMBER='(1)';
      PIN_TYPE='UNSPEC';
      PINUSE='UNSPEC';
    'B':
      PIN_GROUP='1';
      PIN_NUMBER='(2)';
      PIN_TYPE='UNSPEC';
      PINUSE='UNSPEC';
  end_pin;
  body
      PART_NAME='Q_RES';
      PHYS_DES_PREFIX='R';
      STANDARD='End of Design';
      LIFECYCLE='Comp-Approve';
      JEDEC_TYPE='R1206XI';
      ALT_SYMBOLS='(SMRR1206AW)';
      VALUE='0';
      TOL='';
      WATTAGE='1/2W';
      CLASS='DISCRETE';
      DESCRIPTION='RES CHIP 0 1/2W (1206)EF';
      COMPONENT_TYPE='CHIPR1206';
      LEAD_LENGTH='';
      DFM_EXCLUSION='';
      DAY='20180221';
      PARENT_PART_TYPE='Q_RES';
      PARENT_PPT='Q_RES';
      PARENT_PPT_PART='Q_RES_1206LF-0,,1/2W,CHIP,CS00007T200';
  end_body;
end_primitive;
primitive 'Q_RES_1206LF-0,,1/2W,EMPTY,CS0A';
  pin
    'A':
      PIN_GROUP='1';
      PIN_NUMBER='(1)';
      PIN_TYPE='UNSPEC';
      PINUSE='UNSPEC';
    'B':
      PIN_GROUP='1';
      PIN_NUMBER='(2)';
      PIN_TYPE='UNSPEC';
      PINUSE='UNSPEC';
  end_pin;
  body
      PART_NAME='Q_RES';
      PHYS_DES_PREFIX='R';
      STANDARD='End of Design';
      LIFECYCLE='Comp-Approve';
      JEDEC_TYPE='R1206XI';
      ALT_SYMBOLS='(SMRR1206AW)';
      VALUE='0';
      TOL='';
      WATTAGE='1/2W';
      CLASS='IO';
      DESCRIPTION='RES CHIP 0 1/2W (1206)EF';
      COMPONENT_TYPE='CHIPR1206';
      LEAD_LENGTH='';
      DFM_EXCLUSION='';
      DAY='20180221';
      PARENT_PART_TYPE='Q_RES';
      PARENT_PPT='Q_RES';
      PARENT_PPT_PART='Q_RES_1206LF-0,,1/2W,EMPTY,CS00007T200';
  end_body;
end_primitive;
primitive 'Q_RES_1206LF-243,1%,1/4W,CHIP,A';
  pin
    'A':
      PIN_GROUP='1';
      PIN_NUMBER='(1)';
      PIN_TYPE='UNSPEC';
      PINUSE='UNSPEC';
    'B':
      PIN_GROUP='1';
      PIN_NUMBER='(2)';
      PIN_TYPE='UNSPEC';
      PINUSE='UNSPEC';
  end_pin;
  body
      PART_NAME='Q_RES';
      PHYS_DES_PREFIX='R';
      STANDARD='';
      LIFECYCLE='';
      JEDEC_TYPE='R1206XN';
      ALT_SYMBOLS='(SMR1206AW)';
      VALUE='243';
      TOL='1%';
      WATTAGE='1/4W';
      CLASS='DISCRETE';
      DESCRIPTION='RES CHIP 243 1/4W +-1%(1206)EF';
      COMPONENT_TYPE='CHIPR1206';
      LEAD_LENGTH='';
      DFM_EXCLUSION='';
      DAY='20220322';
      PARENT_PART_TYPE='Q_RES';
      PARENT_PPT='Q_RES';
      PARENT_PPT_PART='Q_RES_1206LF-243,1%,1/4W,CHIP,CS12436F201';
  end_body;
end_primitive;
primitive 'Q_RES_2512LF-0.01,1%,1W,CHIP,CA';
  pin
    'A':
      PIN_GROUP='1';
      PIN_NUMBER='(1)';
      PIN_TYPE='UNSPEC';
      PINUSE='UNSPEC';
    'B':
      PIN_GROUP='1';
      PIN_NUMBER='(2)';
      PIN_TYPE='UNSPEC';
      PINUSE='UNSPEC';
  end_pin;
  body
      PART_NAME='Q_RES';
      PHYS_DES_PREFIX='R';
      STANDARD='End of Design';
      LIFECYCLE='Comp-Release Qty';
      JEDEC_TYPE='R2512';
      ALT_SYMBOLS='(SMR2512AW)';
      VALUE='0.01';
      TOL='1%';
      WATTAGE='1W';
      CLASS='DISCRETE';
      DESCRIPTION='RES CHIP 0.01 1W +-1%(2512)';
      COMPONENT_TYPE='CHIP2512';
      LEAD_LENGTH='';
      DFM_EXCLUSION='';
      DAY='20111219';
      PARENT_PART_TYPE='Q_RES';
      PARENT_PPT='Q_RES';
      PARENT_PPT_PART='Q_RES_2512LF-0.01,1%,1W,CHIP,CS+0108F128';
  end_body;
end_primitive;
primitive 'Q_RES_2512LF-0.03,0.1%,1W,EMPTA';
  pin
    'A':
      PIN_GROUP='1';
      PIN_NUMBER='(1)';
      PIN_TYPE='UNSPEC';
      PINUSE='UNSPEC';
    'B':
      PIN_GROUP='1';
      PIN_NUMBER='(2)';
      PIN_TYPE='UNSPEC';
      PINUSE='UNSPEC';
  end_pin;
  body
      PART_NAME='Q_RES';
      PHYS_DES_PREFIX='R';
      STANDARD='';
      LIFECYCLE='';
      JEDEC_TYPE='R2512';
      ALT_SYMBOLS='(SMR2512AW)';
      VALUE='0.03';
      TOL='0.1%';
      WATTAGE='1W';
      CLASS='IO';
      DESCRIPTION='0.03ohm 2512';
      COMPONENT_TYPE='CHIP2512';
      LEAD_LENGTH='';
      DFM_EXCLUSION='';
      DAY='';
      PARENT_PART_TYPE='Q_RES';
      PARENT_PPT='Q_RES';
      PARENT_PPT_PART='Q_RES_2512LF-0.03,0.1%,1W,EMPTY,TMP_QCS+0308BR00';
  end_body;
end_primitive;
primitive 'Q_RES_4P_12-0.001,1%,3W,SMLF,CA';
  pin
    '1':
      PIN_NUMBER='(1)';
      PIN_TYPE='ANALOG';
      NO_LOAD_CHECK='Both';
      NO_IO_CHECK='Both';
      NO_ASSERT_CHECK='TRUE';
      NO_DIR_CHECK='TRUE';
      ALLOW_CONNECT='TRUE';
      PINUSE='UNSPEC';
    '2':
      PIN_NUMBER='(2)';
      PIN_TYPE='ANALOG';
      NO_LOAD_CHECK='Both';
      NO_IO_CHECK='Both';
      NO_ASSERT_CHECK='TRUE';
      NO_DIR_CHECK='TRUE';
      ALLOW_CONNECT='TRUE';
      PINUSE='UNSPEC';
    '3':
      PIN_NUMBER='(3)';
      PIN_TYPE='ANALOG';
      NO_LOAD_CHECK='Both';
      NO_IO_CHECK='Both';
      NO_ASSERT_CHECK='TRUE';
      NO_DIR_CHECK='TRUE';
      ALLOW_CONNECT='TRUE';
      PINUSE='UNSPEC';
    '4':
      PIN_NUMBER='(4)';
      PIN_TYPE='ANALOG';
      NO_LOAD_CHECK='Both';
      NO_IO_CHECK='Both';
      NO_ASSERT_CHECK='TRUE';
      NO_DIR_CHECK='TRUE';
      ALLOW_CONNECT='TRUE';
      PINUSE='UNSPEC';
  end_pin;
  body
      PART_NAME='Q_RES_4P_12';
      BODY_NAME='Q_RES_4P_12';
      PHYS_DES_PREFIX='R';
      CLASS='DISCRETE';
      STANDARD='';
      LIFECYCLE='';
      JEDEC_TYPE='R2512_4P_H41';
      DESCRIPTION='RES CHIP 0.001 3W +-1%(2512)RLC_4P';
      MANUFTR='RLC';
      MANUF_PN='LR2512-23R001F4';
      RD_CMPLS_LVL='EP(V1)';
      CMPLS_LVL='EP(V1)';
      DIP_SMD='';
      FROM_PJ='S8Z-BRIAN';
      DATA='RLC_LR2512-23R001F4.pdf';
      FP_ECN='LR2512-23R001F4.msg';
      EE_CHECK_LIST='';
      PSL='';
      PREFERENCE='';
      CREATOR='';
      STATUS='';
      CREATEDAY='20210428';
      PARENT_PART_TYPE='Q_RES_4P_12';
      PARENT_PPT='Q_RES_4P_12';
      PARENT_PPT_PART='Q_RES_4P_12-0.001,1%,3W,SMLF,CHIP,SP_CS+001DFR10';
  end_body;
end_primitive;
primitive 'Q_RES_4P_12-0.003,1%,3W,SMLF,EA';
  pin
    '1':
      PIN_NUMBER='(1)';
      PIN_TYPE='ANALOG';
      NO_LOAD_CHECK='Both';
      NO_IO_CHECK='Both';
      NO_ASSERT_CHECK='TRUE';
      NO_DIR_CHECK='TRUE';
      ALLOW_CONNECT='TRUE';
      PINUSE='UNSPEC';
    '2':
      PIN_NUMBER='(2)';
      PIN_TYPE='ANALOG';
      NO_LOAD_CHECK='Both';
      NO_IO_CHECK='Both';
      NO_ASSERT_CHECK='TRUE';
      NO_DIR_CHECK='TRUE';
      ALLOW_CONNECT='TRUE';
      PINUSE='UNSPEC';
    '3':
      PIN_NUMBER='(3)';
      PIN_TYPE='ANALOG';
      NO_LOAD_CHECK='Both';
      NO_IO_CHECK='Both';
      NO_ASSERT_CHECK='TRUE';
      NO_DIR_CHECK='TRUE';
      ALLOW_CONNECT='TRUE';
      PINUSE='UNSPEC';
    '4':
      PIN_NUMBER='(4)';
      PIN_TYPE='ANALOG';
      NO_LOAD_CHECK='Both';
      NO_IO_CHECK='Both';
      NO_ASSERT_CHECK='TRUE';
      NO_DIR_CHECK='TRUE';
      ALLOW_CONNECT='TRUE';
      PINUSE='UNSPEC';
  end_pin;
  body
      PART_NAME='Q_RES_4P_12';
      BODY_NAME='Q_RES_4P_12';
      PHYS_DES_PREFIX='R';
      CLASS='DISCRETE';
      STANDARD='';
      LIFECYCLE='';
      JEDEC_TYPE='R2512_4P_H41';
      DESCRIPTION='RES CHIP 0.003 3W +-1%(2512)RLC_4P';
      MANUFTR='RLC';
      MANUF_PN='LR2512-23R003F4';
      RD_CMPLS_LVL='EP(V1)';
      CMPLS_LVL='EP(V1)';
      DIP_SMD='';
      FROM_PJ='MFZ-FRANK';
      DATA='RLC_LR2512-23R003F4.pdf';
      FP_ECN='SP_CS+003DFR03.msg';
      EE_CHECK_LIST='';
      PSL='';
      PREFERENCE='';
      CREATOR='';
      STATUS='';
      CREATEDAY='20220421';
      PARENT_PART_TYPE='Q_RES_4P_12';
      PARENT_PPT='Q_RES_4P_12';
      PARENT_PPT_PART='Q_RES_4P_12-0.003,1%,3W,SMLF,EMPTY,SP_CS+003DFR03_1';
  end_body;
end_primitive;
primitive 'Q_SHORT_SM-EMPTY,SHORT6';
  pin
    '1':
      PIN_NUMBER='(1)';
      INPUT_LOAD='(-0.01,0.01)';
      OUTPUT_LOAD='(1.0,-1.0)';
      BIDIRECTIONAL='TRUE';
      PINUSE='BI';
    '2':
      PIN_NUMBER='(2)';
      INPUT_LOAD='(-0.01,0.01)';
      OUTPUT_LOAD='(1.0,-1.0)';
      BIDIRECTIONAL='TRUE';
      PINUSE='BI';
  end_pin;
  body
      CLASS='IO';
      PART_NAME='Q_SHORT';
      PHYS_DES_PREFIX='J';
      STANDARD='';
      LIFECYCLE='';
      JEDEC_TYPE='SHORT_R0603';
      DESCRIPTION='JUMP,SHORT_R0603';
      HEIGHT='';
      COMPONENT_TYPE='';
      LEAD_LENGTH='';
      DFM_EXCLUSION='';
      I_PN='';
      FROM_PJ='T73-CT';
      LEAD_FREE='';
      PARENT_PART_TYPE='Q_SHORT';
      PARENT_PPT='Q_SHORT';
      PARENT_PPT_PART='Q_SHORT_SM-EMPTY,SHORT6';
  end_body;
end_primitive;
primitive 'Q_SP_RES4P-0.0003,1%,4W,SMLF,EA';
  pin
    '2B':
      PIN_NUMBER='(2B)';
      BIDIRECTIONAL='TRUE';
      INPUT_LOAD='(-0.01,0.01)';
      OUTPUT_LOAD='(1.0,-1.0)';
      PINUSE='BI';
    '1B':
      PIN_NUMBER='(1B)';
      BIDIRECTIONAL='TRUE';
      INPUT_LOAD='(-0.01,0.01)';
      OUTPUT_LOAD='(1.0,-1.0)';
      PINUSE='BI';
    '2A':
      PIN_NUMBER='(2A)';
      BIDIRECTIONAL='TRUE';
      INPUT_LOAD='(-0.01,0.01)';
      OUTPUT_LOAD='(1.0,-1.0)';
      PINUSE='BI';
    '1A':
      PIN_NUMBER='(1A)';
      BIDIRECTIONAL='TRUE';
      INPUT_LOAD='(-0.01,0.01)';
      OUTPUT_LOAD='(1.0,-1.0)';
      PINUSE='BI';
  end_pin;
  body
      PART_NAME='Q_SP_RES4P';
      BODY_NAME='Q_SP_RES4P';
      PHYS_DES_PREFIX='R';
      CLASS='DISCRETE';
      STANDARD='End of Design';
      LIFECYCLE='Comp-Approve';
      JEDEC_TYPE='R2725_4P';
      DESCRIPTION='RES CHIP 0.0003 4W +-1%(2725)';
      MANUFTR='RLC';
      MANUF_PN='LR2725-24R0003F1';
      RD_CMPLS_LVL='EP(V1)';
      CMPLS_LVL='EP(V1)';
      DIP_SMD='';
      FROM_PJ='S2VM-HANK';
      DATA='RLC_LR2725-24R0003F1.pdf';
      FP_ECN='';
      EE_CHECK_LIST='';
      PSL='';
      PREFERENCE='';
      CREATOR='';
      STATUS='';
      CREATEDAY='20160201';
      PARENT_PART_TYPE='Q_SP_RES4P';
      PARENT_PPT='Q_SP_RES4P';
      PARENT_PPT_PART='Q_SP_RES4P-0.0003,1%,4W,SMLF,EMPTY,SP_CS0000FFT04';
  end_body;
end_primitive;
primitive 'Q_XTAL_4P_13BI_24GND-12MHZ,SMLA';
  pin
    'X1':
      PIN_NUMBER='(1)';
      BIDIRECTIONAL='TRUE';
      INPUT_LOAD='(-0.01,0.01)';
      OUTPUT_LOAD='(1.0,-1.0)';
      PINUSE='BI';
    'G1':
      PIN_NUMBER='(2)';
      PINUSE='POWER';
      NO_LOAD_CHECK='Both';
      NO_IO_CHECK='Both';
      NO_ASSERT_CHECK='TRUE';
      NO_DIR_CHECK='TRUE';
      ALLOW_CONNECT='TRUE';
    'G2':
      PIN_NUMBER='(4)';
      PINUSE='POWER';
      NO_LOAD_CHECK='Both';
      NO_IO_CHECK='Both';
      NO_ASSERT_CHECK='TRUE';
      NO_DIR_CHECK='TRUE';
      ALLOW_CONNECT='TRUE';
    'X2':
      PIN_NUMBER='(3)';
      BIDIRECTIONAL='TRUE';
      INPUT_LOAD='(-0.01,0.01)';
      OUTPUT_LOAD='(1.0,-1.0)';
      PINUSE='BI';
  end_pin;
  body
      PART_NAME='Q_XTAL_4P_13BI_24GND';
      BODY_NAME='Q_XTAL_4P_13BI_24GND';
      PHYS_DES_PREFIX='Y';
      CLASS='IO';
      STANDARD='';
      LIFECYCLE='';
      JEDEC_TYPE='OSC4_DNCA250000ETS_2-5X2_H26';
      ALT_SYMBOLS='';
      DESCRIPTION='XTAL 12MHZ(+-20PPM,10PF)E2SB12E00000EE';
      MANUFTR='HHE';
      MANUF_PN='E2SB12E00000EE';
      RD_CMPLS_LVL='EP(V1)';
      CMPLS_LVL='EP(V1)';
      DIP_SMD='';
      FROM_PJ='F0T-IVES';
      DATA='HHE_E2SB12E00000EE.pdf';
      FP_ECN='';
      EE_CHECK_LIST='';
      STATUS='';
      PSL='';
      PREFERENCE='';
      CREATOR='';
      CREATEDAY='20211029';
      PARENT_PART_TYPE='Q_XTAL_4P_13BI_24GND';
      PARENT_PPT='Q_XTAL_4P_13BI_24GND';
      PARENT_PPT_PART='Q_XTAL_4P_13BI_24GND-12MHZ,SMLF,MISC,BG6120000E0';
  end_body;
end_primitive;
primitive 'Q_XTAL_4P_13BI_24GND-12MHZ,SMLB';
  pin
    'X1':
      PIN_NUMBER='(1)';
      BIDIRECTIONAL='TRUE';
      INPUT_LOAD='(-0.01,0.01)';
      OUTPUT_LOAD='(1.0,-1.0)';
      PINUSE='BI';
    'G1':
      PIN_NUMBER='(2)';
      PINUSE='POWER';
      NO_LOAD_CHECK='Both';
      NO_IO_CHECK='Both';
      NO_ASSERT_CHECK='TRUE';
      NO_DIR_CHECK='TRUE';
      ALLOW_CONNECT='TRUE';
    'G2':
      PIN_NUMBER='(4)';
      PINUSE='POWER';
      NO_LOAD_CHECK='Both';
      NO_IO_CHECK='Both';
      NO_ASSERT_CHECK='TRUE';
      NO_DIR_CHECK='TRUE';
      ALLOW_CONNECT='TRUE';
    'X2':
      PIN_NUMBER='(3)';
      BIDIRECTIONAL='TRUE';
      INPUT_LOAD='(-0.01,0.01)';
      OUTPUT_LOAD='(1.0,-1.0)';
      PINUSE='BI';
  end_pin;
  body
      PART_NAME='Q_XTAL_4P_13BI_24GND';
      BODY_NAME='Q_XTAL_4P_13BI_24GND';
      PHYS_DES_PREFIX='Y';
      CLASS='IO';
      STANDARD='';
      LIFECYCLE='';
      JEDEC_TYPE='OSC4_DNCA250000ETS_2-5X2_H26';
      ALT_SYMBOLS='';
      DESCRIPTION='XTAL 12MHZ(+-20PPM,10PF)E2SB12E00000EE';
      MANUFTR='HHE';
      MANUF_PN='E2SB12E00000EE';
      RD_CMPLS_LVL='EP(V1)';
      CMPLS_LVL='EP(V1)';
      DIP_SMD='';
      FROM_PJ='F0T-IVES';
      DATA='HHE_E2SB12E00000EE.pdf';
      FP_ECN='';
      EE_CHECK_LIST='';
      STATUS='';
      PSL='';
      PREFERENCE='';
      CREATOR='';
      CREATEDAY='20211029';
      PARENT_PART_TYPE='Q_XTAL_4P_13BI_24GND';
      PARENT_PPT='Q_XTAL_4P_13BI_24GND';
      PARENT_PPT_PART='Q_XTAL_4P_13BI_24GND-12MHZ,SMLF,EMPTY,BG6120000E0';
  end_body;
end_primitive;
primitive 'Q_XTAL_4P_13BI_24GND-25MHZ,SMLA';
  pin
    'X1':
      PIN_NUMBER='(1)';
      BIDIRECTIONAL='TRUE';
      INPUT_LOAD='(-0.01,0.01)';
      OUTPUT_LOAD='(1.0,-1.0)';
      PINUSE='BI';
    'G1':
      PIN_NUMBER='(2)';
      PINUSE='POWER';
      NO_LOAD_CHECK='Both';
      NO_IO_CHECK='Both';
      NO_ASSERT_CHECK='TRUE';
      NO_DIR_CHECK='TRUE';
      ALLOW_CONNECT='TRUE';
    'G2':
      PIN_NUMBER='(4)';
      PINUSE='POWER';
      NO_LOAD_CHECK='Both';
      NO_IO_CHECK='Both';
      NO_ASSERT_CHECK='TRUE';
      NO_DIR_CHECK='TRUE';
      ALLOW_CONNECT='TRUE';
    'X2':
      PIN_NUMBER='(3)';
      BIDIRECTIONAL='TRUE';
      INPUT_LOAD='(-0.01,0.01)';
      OUTPUT_LOAD='(1.0,-1.0)';
      PINUSE='BI';
  end_pin;
  body
      PART_NAME='Q_XTAL_4P_13BI_24GND';
      BODY_NAME='Q_XTAL_4P_13BI_24GND';
      PHYS_DES_PREFIX='Y';
      CLASS='IO';
      STANDARD='';
      LIFECYCLE='';
      JEDEC_TYPE='X_7MXA';
      ALT_SYMBOLS='';
      DESCRIPTION='XTAL SMD 25MHZ(+-20PPM,20PF)7M25020008';
      MANUFTR='TXC';
      MANUF_PN='7M25020008';
      RD_CMPLS_LVL='EP(V1)';
      CMPLS_LVL='EP(V1)';
      DIP_SMD='';
      FROM_PJ='S5M-GLEN';
      DATA='TXC_7M25020008_REVA1.pdf';
      FP_ECN='';
      EE_CHECK_LIST='';
      STATUS='';
      PSL='';
      PREFERENCE='';
      CREATOR='';
      CREATEDAY='20150112';
      PARENT_PART_TYPE='Q_XTAL_4P_13BI_24GND';
      PARENT_PPT='Q_XTAL_4P_13BI_24GND';
      PARENT_PPT_PART='Q_XTAL_4P_13BI_24GND-25MHZ,SMLF,EMPTY,BG625000802';
  end_body;
end_primitive;
primitive 'Q_XTAL_4P_13BI_24GND-25MHZ,SMLB';
  pin
    'X1':
      PIN_NUMBER='(1)';
      BIDIRECTIONAL='TRUE';
      INPUT_LOAD='(-0.01,0.01)';
      OUTPUT_LOAD='(1.0,-1.0)';
      PINUSE='BI';
    'G1':
      PIN_NUMBER='(2)';
      PINUSE='POWER';
      NO_LOAD_CHECK='Both';
      NO_IO_CHECK='Both';
      NO_ASSERT_CHECK='TRUE';
      NO_DIR_CHECK='TRUE';
      ALLOW_CONNECT='TRUE';
    'G2':
      PIN_NUMBER='(4)';
      PINUSE='POWER';
      NO_LOAD_CHECK='Both';
      NO_IO_CHECK='Both';
      NO_ASSERT_CHECK='TRUE';
      NO_DIR_CHECK='TRUE';
      ALLOW_CONNECT='TRUE';
    'X2':
      PIN_NUMBER='(3)';
      BIDIRECTIONAL='TRUE';
      INPUT_LOAD='(-0.01,0.01)';
      OUTPUT_LOAD='(1.0,-1.0)';
      PINUSE='BI';
  end_pin;
  body
      PART_NAME='Q_XTAL_4P_13BI_24GND';
      BODY_NAME='Q_XTAL_4P_13BI_24GND';
      PHYS_DES_PREFIX='Y';
      CLASS='IO';
      STANDARD='';
      LIFECYCLE='';
      JEDEC_TYPE='X_4S_FL4000120_3-2X2-5';
      ALT_SYMBOLS='';
      DESCRIPTION='XTAL SMD 25MHZ(+-10PPM,8PF)FL2500498';
      MANUFTR='DDS';
      MANUF_PN='FL2500498';
      RD_CMPLS_LVL='EP(V1)';
      CMPLS_LVL='EP(V1)';
      DIP_SMD='';
      FROM_PJ='F0C-IVES';
      DATA='DDS_FL2500498.pdf';
      FP_ECN='';
      EE_CHECK_LIST='';
      STATUS='';
      PSL='';
      PREFERENCE='';
      CREATOR='';
      CREATEDAY='20211129';
      PARENT_PART_TYPE='Q_XTAL_4P_13BI_24GND';
      PARENT_PPT='Q_XTAL_4P_13BI_24GND';
      PARENT_PPT_PART='Q_XTAL_4P_13BI_24GND-25MHZ,SMLF,MISC,BG6250000F0';
  end_body;
end_primitive;
primitive 'RAA2213404GNPHB0-RAA2213404GNPA';
  pin
    'PWM':
      PIN_NUMBER='(21)';
      INPUT_LOAD='(-0.01,0.01)';
      PINUSE='IN';
    'REFIN':
      PIN_NUMBER='(24)';
      INPUT_LOAD='(-0.01,0.01)';
      PINUSE='IN';
    'GND2':
      PIN_NUMBER='(23)';
      PINUSE='POWER';
      NO_LOAD_CHECK='Both';
      NO_IO_CHECK='Both';
      NO_ASSERT_CHECK='TRUE';
      NO_DIR_CHECK='TRUE';
      ALLOW_CONNECT='TRUE';
    'BOOT':
      PIN_NUMBER='(20)';
      PINUSE='POWER';
      NO_LOAD_CHECK='Both';
      NO_IO_CHECK='Both';
      NO_ASSERT_CHECK='TRUE';
      NO_DIR_CHECK='TRUE';
      ALLOW_CONNECT='TRUE';
    'VIN':
      PIN_NUMBER='(16_18-28)';
      PINUSE='POWER';
      NO_LOAD_CHECK='Both';
      NO_IO_CHECK='Both';
      NO_ASSERT_CHECK='TRUE';
      NO_DIR_CHECK='TRUE';
      ALLOW_CONNECT='TRUE';
    'PHASE':
      PIN_NUMBER='(19)';
      PINUSE='POWER';
      NO_LOAD_CHECK='Both';
      NO_IO_CHECK='Both';
      NO_ASSERT_CHECK='TRUE';
      NO_DIR_CHECK='TRUE';
      ALLOW_CONNECT='TRUE';
    'VCC':
      PIN_NUMBER='(4)';
      PINUSE='POWER';
      NO_LOAD_CHECK='Both';
      NO_IO_CHECK='Both';
      NO_ASSERT_CHECK='TRUE';
      NO_DIR_CHECK='TRUE';
      ALLOW_CONNECT='TRUE';
    'TMON':
      PIN_NUMBER='(1)';
      OUTPUT_LOAD='(1.0,-1.0)';
      PINUSE='OUT';
    'IMON':
      PIN_NUMBER='(25)';
      OUTPUT_LOAD='(1.0,-1.0)';
      PINUSE='OUT';
    'GND1':
      PIN_NUMBER='(6_7-13_15-29)';
      PINUSE='POWER';
      NO_LOAD_CHECK='Both';
      NO_IO_CHECK='Both';
      NO_ASSERT_CHECK='TRUE';
      NO_DIR_CHECK='TRUE';
      ALLOW_CONNECT='TRUE';
    'GL2':
      PIN_NUMBER='(27)';
      OUTPUT_LOAD='(1.0,-1.0)';
      PINUSE='OUT';
    'SW':
      PIN_NUMBER='(8_12)';
      OUTPUT_LOAD='(1.0,-1.0)';
      PINUSE='OUT';
    'FAULT#':
      PIN_NUMBER='(2)';
      OUTPUT_TYPE='(OC,AND)';
      OUTPUT_LOAD='(1.0,*)';
      PINUSE='OCA';
    'GND3':
      PIN_NUMBER='(26)';
      PINUSE='POWER';
      NO_LOAD_CHECK='Both';
      NO_IO_CHECK='Both';
      NO_ASSERT_CHECK='TRUE';
      NO_DIR_CHECK='TRUE';
      ALLOW_CONNECT='TRUE';
    'NC1':
      PIN_NUMBER='(22)';
      OUTPUT_TYPE='(TS,TS)';
      INPUT_LOAD='(-0.01,0.01)';
      OUTPUT_LOAD='(1.0,-1.0)';
      PINUSE='TRI';
    'GL1':
      PIN_NUMBER='(5)';
      OUTPUT_LOAD='(1.0,-1.0)';
      PINUSE='OUT';
    'LGCTRL':
      PIN_NUMBER='(3)';
      INPUT_LOAD='(-0.01,0.01)';
      PINUSE='IN';
  end_pin;
  body
      PART_NAME='RAA2213404GNPHB0';
      BODY_NAME='RAA2213404GNPHB0';
      PHYS_DES_PREFIX='U';
      CLASS='IC';
      STANDARD='';
      LIFECYCLE='';
      JEDEC_TYPE='PQFN17_TH_5X4';
      DESCRIPTION='IC (29P) RAA2213404GNP#HB0(PQFN)';
      MANUFTR='RTT';
      MANUF_PN='RAA2213404GNP#HB0';
      RD_CMPLS_LVL='EP(V1)';
      CMPLS_LVL='';
      FROM_PJ='S6Q-KIMI';
      DIP_SMD='';
      DATA='RTT_RAA2213404GNPHB0.pdf';
      EE_CHECK_LIST='';
      FP_ECN='RAA2213404GNPHB0.msg';
      PSL='';
      CREATOR='';
      STATUS='';
      MSD='NA';
      ESD_CDM='NA';
      ESD_HBM='NA';
      ESD_MM='NA';
      PIN_LENGTH_SHORT_PIN='0 MILS';
      PIN_LENGTH_LONG_PIN='0 MILS';
      CREATEDAY='20201006';
      PARENT_PART_TYPE='RAA2213404GNPHB0';
      PARENT_PPT='RAA2213404GNPHB0';
      PARENT_PPT_PART='RAA2213404GNPHB0-RAA2213404GNP#HB0,SMLF,IC,AL221340002';
  end_body;
end_primitive;
primitive 'RAA229126GNPHA0-RAA229126GNP#HA';
  pin
    'CS11':
      PIN_NUMBER='(27)';
      INPUT_LOAD='(-0.01,0.01)';
      PINUSE='IN';
    'VCC':
      PIN_NUMBER='(47)';
      PINUSE='POWER';
      NO_LOAD_CHECK='Both';
      NO_IO_CHECK='Both';
      NO_ASSERT_CHECK='TRUE';
      NO_DIR_CHECK='TRUE';
      ALLOW_CONNECT='TRUE';
    'EN1':
      PIN_NUMBER='(24)';
      INPUT_LOAD='(-0.01,0.01)';
      PINUSE='IN';
    'PMSCL':
      PIN_NUMBER='(14)';
      INPUT_LOAD='(-0.01,0.01)';
      PINUSE='IN';
    'SVDATA':
      PIN_NUMBER='(22)';
      BIDIRECTIONAL='TRUE';
      INPUT_LOAD='(-0.01,0.01)';
      OUTPUT_LOAD='(1.0,-1.0)';
      PINUSE='BI';
    'CS6':
      PIN_NUMBER='(32)';
      INPUT_LOAD='(-0.01,0.01)';
      PINUSE='IN';
    'NSVALERT':
      PIN_NUMBER='(23)';
      OUTPUT_LOAD='(1.0,-1.0)';
      PINUSE='OUT';
    'NVRHOT':
      PIN_NUMBER='(18)';
      OUTPUT_LOAD='(1.0,-1.0)';
      PINUSE='OUT';
    'CS5':
      PIN_NUMBER='(33)';
      INPUT_LOAD='(-0.01,0.01)';
      PINUSE='IN';
    'CS4':
      PIN_NUMBER='(34)';
      INPUT_LOAD='(-0.01,0.01)';
      PINUSE='IN';
    'PG1':
      PIN_NUMBER='(20)';
      OUTPUT_LOAD='(1.0,-1.0)';
      PINUSE='OUT';
    'SVCLK':
      PIN_NUMBER='(21)';
      INPUT_LOAD='(-0.01,0.01)';
      PINUSE='IN';
    'NPMALERT':
      PIN_NUMBER='(15)';
      OUTPUT_LOAD='(1.0,-1.0)';
      PINUSE='OUT';
    'EN0':
      PIN_NUMBER='(17)';
      INPUT_LOAD='(-0.01,0.01)';
      PINUSE='IN';
    'RGND0':
      PIN_NUMBER='(26)';
      INPUT_LOAD='(-0.01,0.01)';
      PINUSE='IN';
    'PMSDA':
      PIN_NUMBER='(13)';
      BIDIRECTIONAL='TRUE';
      INPUT_LOAD='(-0.01,0.01)';
      OUTPUT_LOAD='(1.0,-1.0)';
      PINUSE='BI';
    'PWM4':
      PIN_NUMBER='(5)';
      OUTPUT_LOAD='(1.0,-1.0)';
      PINUSE='OUT';
    'PWM5':
      PIN_NUMBER='(6)';
      OUTPUT_LOAD='(1.0,-1.0)';
      PINUSE='OUT';
    'VSEN0':
      PIN_NUMBER='(25)';
      INPUT_LOAD='(-0.01,0.01)';
      PINUSE='IN';
    'PWM1':
      PIN_NUMBER='(2)';
      OUTPUT_LOAD='(1.0,-1.0)';
      PINUSE='OUT';
    'PG0':
      PIN_NUMBER='(16)';
      OUTPUT_LOAD='(1.0,-1.0)';
      PINUSE='OUT';
    'PWM6':
      PIN_NUMBER='(7)';
      OUTPUT_LOAD='(1.0,-1.0)';
      PINUSE='OUT';
    'VCCS':
      PIN_NUMBER='(48)';
      PINUSE='POWER';
      NO_LOAD_CHECK='Both';
      NO_IO_CHECK='Both';
      NO_ASSERT_CHECK='TRUE';
      NO_DIR_CHECK='TRUE';
      ALLOW_CONNECT='TRUE';
    'VMON||IINSEN||VSYS||ISYS':
      PIN_NUMBER='(45)';
      INPUT_LOAD='(-0.01,0.01)';
      PINUSE='IN';
    'VINSEN||VSYS':
      PIN_NUMBER='(46)';
      INPUT_LOAD='(-0.01,0.01)';
      PINUSE='IN';
    'TEMP1||ISYS':
      PIN_NUMBER='(44)';
      INPUT_LOAD='(-0.01,0.01)';
      PINUSE='IN';
    'NPINALERT||NPSYS_CRIT':
      PIN_NUMBER='(19)';
      OUTPUT_LOAD='(1.0,-1.0)';
      PINUSE='OUT';
    'VSEN1':
      PIN_NUMBER='(40)';
      INPUT_LOAD='(-0.01,0.01)';
      PINUSE='IN';
    'RGND1':
      PIN_NUMBER='(39)';
      INPUT_LOAD='(-0.01,0.01)';
      PINUSE='IN';
    'CS1':
      PIN_NUMBER='(37)';
      INPUT_LOAD='(-0.01,0.01)';
      PINUSE='IN';
    'PWM11':
      PIN_NUMBER='(12)';
      OUTPUT_LOAD='(1.0,-1.0)';
      PINUSE='OUT';
    'PWM3':
      PIN_NUMBER='(4)';
      OUTPUT_LOAD='(1.0,-1.0)';
      PINUSE='OUT';
    'CS3':
      PIN_NUMBER='(35)';
      INPUT_LOAD='(-0.01,0.01)';
      PINUSE='IN';
    'PWM2':
      PIN_NUMBER='(3)';
      OUTPUT_LOAD='(1.0,-1.0)';
      PINUSE='OUT';
    'CS2':
      PIN_NUMBER='(36)';
      INPUT_LOAD='(-0.01,0.01)';
      PINUSE='IN';
    'CFP':
      PIN_NUMBER='(41)';
      OUTPUT_LOAD='(1.0,-1.0)';
      PINUSE='OUT';
    'TH_GND':
      PIN_NUMBER='(TH)';
      PINUSE='POWER';
      NO_LOAD_CHECK='Both';
      NO_IO_CHECK='Both';
      NO_ASSERT_CHECK='TRUE';
      NO_DIR_CHECK='TRUE';
      ALLOW_CONNECT='TRUE';
    'ADDR_CFG':
      PIN_NUMBER='(42)';
      INPUT_LOAD='(-0.01,0.01)';
      PINUSE='IN';
    'TEMP0':
      PIN_NUMBER='(43)';
      INPUT_LOAD='(-0.01,0.01)';
      PINUSE='IN';
    'PWM0':
      PIN_NUMBER='(1)';
      OUTPUT_LOAD='(1.0,-1.0)';
      PINUSE='OUT';
    'CS0':
      PIN_NUMBER='(38)';
      INPUT_LOAD='(-0.01,0.01)';
      PINUSE='IN';
    'PWM7':
      PIN_NUMBER='(8)';
      OUTPUT_LOAD='(1.0,-1.0)';
      PINUSE='OUT';
    'CS7':
      PIN_NUMBER='(31)';
      INPUT_LOAD='(-0.01,0.01)';
      PINUSE='IN';
    'PWM8':
      PIN_NUMBER='(9)';
      OUTPUT_LOAD='(1.0,-1.0)';
      PINUSE='OUT';
    'CS8':
      PIN_NUMBER='(30)';
      INPUT_LOAD='(-0.01,0.01)';
      PINUSE='IN';
    'PWM9':
      PIN_NUMBER='(10)';
      OUTPUT_LOAD='(1.0,-1.0)';
      PINUSE='OUT';
    'CS9':
      PIN_NUMBER='(29)';
      INPUT_LOAD='(-0.01,0.01)';
      PINUSE='IN';
    'PWM10':
      PIN_NUMBER='(11)';
      OUTPUT_LOAD='(1.0,-1.0)';
      PINUSE='OUT';
    'CS10':
      PIN_NUMBER='(28)';
      INPUT_LOAD='(-0.01,0.01)';
      PINUSE='IN';
  end_pin;
  body
      PART_NAME='RAA229126GNPHA0';
      BODY_NAME='RAA229126GNPHA0';
      PHYS_DES_PREFIX='U';
      CLASS='IC';
      STANDARD='';
      LIFECYCLE='';
      JEDEC_TYPE='QFN48_THXT';
      DESCRIPTION='IC CTRL(48P)RAA229126GNP#HA0(QFN)';
      MANUFTR='RTT';
      MANUF_PN='RAA229126GNP#HA0';
      RD_CMPLS_LVL='EP(V1)';
      CMPLS_LVL='';
      FROM_PJ='S8Z-CARLOS';
      DIP_SMD='';
      DATA='RTT_RAA229126GNPHA0.pdf';
      EE_CHECK_LIST='';
      FP_ECN='';
      PSL='';
      CREATOR='';
      STATUS='';
      MSD='NA';
      ESD_CDM='N/A';
      ESD_HBM='N/A';
      ESD_MM='N/A';
      PIN_LENGTH_SHORT_PIN='0 MILS';
      PIN_LENGTH_LONG_PIN='0 MILS';
      CREATEDAY='20200420';
      PARENT_PART_TYPE='RAA229126GNPHA0';
      PARENT_PPT='RAA229126GNPHA0';
      PARENT_PPT_PART='RAA229126GNPHA0-RAA229126GNP#HA0,SMLF,IC,AL229126000';
  end_body;
end_primitive;
primitive 'RS31312R-RS31312R,SMLF,IC,AL03A';
  pin
    'VOUT_20':
      PIN_NUMBER='(20)';
      OUTPUT_LOAD='(1.0,-1.0)';
      PINUSE='OUT';
    'VIN_21_22':
      PIN_NUMBER='(21_22)';
      INPUT_LOAD='(-0.01,0.01)';
      PINUSE='IN';
    'VOUT_19':
      PIN_NUMBER='(19)';
      OUTPUT_LOAD='(1.0,-1.0)';
      PINUSE='OUT';
    'VOUT_18':
      PIN_NUMBER='(18)';
      OUTPUT_LOAD='(1.0,-1.0)';
      PINUSE='OUT';
    'VOUT_17':
      PIN_NUMBER='(17)';
      OUTPUT_LOAD='(1.0,-1.0)';
      PINUSE='OUT';
    'VOUT_16':
      PIN_NUMBER='(16)';
      OUTPUT_LOAD='(1.0,-1.0)';
      PINUSE='OUT';
    'VOUT_15':
      PIN_NUMBER='(15)';
      OUTPUT_LOAD='(1.0,-1.0)';
      PINUSE='OUT';
    'VOUT_14':
      PIN_NUMBER='(14)';
      OUTPUT_LOAD='(1.0,-1.0)';
      PINUSE='OUT';
    'AVIN':
      PIN_NUMBER='(12)';
      INPUT_LOAD='(-0.01,0.01)';
      PINUSE='IN';
    'VOUT_13':
      PIN_NUMBER='(13)';
      OUTPUT_LOAD='(1.0,-1.0)';
      PINUSE='OUT';
    'OV':
      PIN_NUMBER='(11)';
      INPUT_LOAD='(-0.01,0.01)';
      PINUSE='IN';
    'PG':
      PIN_NUMBER='(10)';
      OUTPUT_LOAD='(1.0,-1.0)';
      PINUSE='OUT';
    'FLTB':
      PIN_NUMBER='(9)';
      OUTPUT_LOAD='(1.0,-1.0)';
      PINUSE='OUT';
    'IMON':
      PIN_NUMBER='(8)';
      OUTPUT_LOAD='(1.0,-1.0)';
      PINUSE='OUT';
    'VIN_23':
      PIN_NUMBER='(23)';
      INPUT_LOAD='(-0.01,0.01)';
      PINUSE='IN';
    'VIN_24':
      PIN_NUMBER='(24)';
      INPUT_LOAD='(-0.01,0.01)';
      PINUSE='IN';
    'VIN_25':
      PIN_NUMBER='(25)';
      INPUT_LOAD='(-0.01,0.01)';
      PINUSE='IN';
    'VIN_26':
      PIN_NUMBER='(26)';
      INPUT_LOAD='(-0.01,0.01)';
      PINUSE='IN';
    'EN':
      PIN_NUMBER='(1)';
      INPUT_LOAD='(-0.01,0.01)';
      PINUSE='IN';
    'LOADEN':
      PIN_NUMBER='(2)';
      INPUT_LOAD='(-0.01,0.01)';
      PINUSE='IN';
    'ENTM':
      PIN_NUMBER='(3)';
      INPUT_LOAD='(-0.01,0.01)';
      PINUSE='IN';
    'TIMER':
      PIN_NUMBER='(4)';
      INPUT_LOAD='(-0.01,0.01)';
      PINUSE='IN';
    'ISET':
      PIN_NUMBER='(5)';
      INPUT_LOAD='(-0.01,0.01)';
      PINUSE='IN';
    'SS':
      PIN_NUMBER='(6)';
      INPUT_LOAD='(-0.01,0.01)';
      PINUSE='IN';
    'GND':
      PIN_NUMBER='(7)';
      PINUSE='POWER';
      NO_LOAD_CHECK='Both';
      NO_IO_CHECK='Both';
      NO_ASSERT_CHECK='TRUE';
      NO_DIR_CHECK='TRUE';
      ALLOW_CONNECT='TRUE';
  end_pin;
  body
      PART_NAME='RS31312R';
      BODY_NAME='RS31312R';
      PHYS_DES_PREFIX='U';
      CLASS='IC';
      STANDARD='';
      LIFECYCLE='';
      JEDEC_TYPE='QFN22_TH_3X5';
      DESCRIPTION='IC(22P)RS31312R(QFN)';
      MANUFTR='RDS';
      MANUF_PN='RS31312R';
      RD_CMPLS_LVL='EP(V1)';
      CMPLS_LVL='';
      FROM_PJ='F0T-GREG';
      DIP_SMD='';
      DATA='RDS_RS31312R.pdf';
      EE_CHECK_LIST='';
      FP_ECN='RS31312R.msg';
      PSL='';
      CREATOR='';
      STATUS='';
      MSD='';
      ESD_CDM='';
      ESD_HBM='';
      ESD_MM='';
      PIN_LENGTH_SHORT_PIN='0 MILS';
      PIN_LENGTH_LONG_PIN='0 MILS';
      CREATEDAY='20220608';
      PARENT_PART_TYPE='RS31312R';
      PARENT_PPT='RS31312R';
      PARENT_PPT_PART='RS31312R-RS31312R,SMLF,IC,AL031312000';
  end_body;
end_primitive;
primitive 'RS53317LR-RS53317LR,SMLF,IC,ALA';
  pin
    'VIN':
      PIN_NUMBER='(3)';
      INPUT_LOAD='(-0.01,0.01)';
      PINUSE='IN';
    'PGOOD':
      PIN_NUMBER='(9)';
      OUTPUT_LOAD='(1.0,-1.0)';
      PINUSE='OUT';
    'PGND2':
      PIN_NUMBER='(14)';
      PINUSE='POWER';
      NO_LOAD_CHECK='Both';
      NO_IO_CHECK='Both';
      NO_ASSERT_CHECK='TRUE';
      NO_DIR_CHECK='TRUE';
      ALLOW_CONNECT='TRUE';
    'EN':
      PIN_NUMBER='(5)';
      INPUT_LOAD='(-0.01,0.01)';
      PINUSE='IN';
    'BST':
      PIN_NUMBER='(10)';
      BIDIRECTIONAL='TRUE';
      INPUT_LOAD='(-0.01,0.01)';
      OUTPUT_LOAD='(1.0,-1.0)';
      PINUSE='BI';
    'FB':
      PIN_NUMBER='(6)';
      INPUT_LOAD='(-0.01,0.01)';
      PINUSE='IN';
    'AGND':
      PIN_NUMBER='(7)';
      PINUSE='POWER';
      NO_LOAD_CHECK='Both';
      NO_IO_CHECK='Both';
      NO_ASSERT_CHECK='TRUE';
      NO_DIR_CHECK='TRUE';
      ALLOW_CONNECT='TRUE';
    'VCC':
      PIN_NUMBER='(13)';
      PINUSE='POWER';
      NO_LOAD_CHECK='Both';
      NO_IO_CHECK='Both';
      NO_ASSERT_CHECK='TRUE';
      NO_DIR_CHECK='TRUE';
      ALLOW_CONNECT='TRUE';
    'PGND1':
      PIN_NUMBER='(1)';
      PINUSE='POWER';
      NO_LOAD_CHECK='Both';
      NO_IO_CHECK='Both';
      NO_ASSERT_CHECK='TRUE';
      NO_DIR_CHECK='TRUE';
      ALLOW_CONNECT='TRUE';
    'SW2':
      PIN_NUMBER='(11)';
      OUTPUT_LOAD='(1.0,-1.0)';
      PINUSE='OUT';
    'REF':
      PIN_NUMBER='(8)';
      BIDIRECTIONAL='TRUE';
      INPUT_LOAD='(-0.01,0.01)';
      OUTPUT_LOAD='(1.0,-1.0)';
      PINUSE='BI';
    'MODE':
      PIN_NUMBER='(12)';
      INPUT_LOAD='(-0.01,0.01)';
      PINUSE='IN';
    'CS':
      PIN_NUMBER='(4)';
      BIDIRECTIONAL='TRUE';
      INPUT_LOAD='(-0.01,0.01)';
      OUTPUT_LOAD='(1.0,-1.0)';
      PINUSE='BI';
    'SW1':
      PIN_NUMBER='(2)';
      OUTPUT_LOAD='(1.0,-1.0)';
      PINUSE='OUT';
  end_pin;
  body
      PART_NAME='RS53317LR';
      BODY_NAME='RS53317LR';
      PHYS_DES_PREFIX='U';
      CLASS='IC';
      STANDARD='';
      LIFECYCLE='';
      JEDEC_TYPE='QFN14_0-5_3X2XB';
      DESCRIPTION='IC(14P)RS53317LR(QFN)';
      MANUFTR='RDS';
      MANUF_PN='RS53317LR';
      RD_CMPLS_LVL='EP(V1)';
      CMPLS_LVL='EP(V1)';
      FROM_PJ='MF6-NINA';
      DIP_SMD='';
      DATA='RDS_RS53317LR.pdf';
      EE_CHECK_LIST='';
      FP_ECN='RS53317LR.msg';
      PSL='';
      CREATOR='';
      STATUS='';
      MSD='';
      ESD_CDM='';
      ESD_HBM='';
      ESD_MM='';
      PIN_LENGTH_SHORT_PIN='0 MILS';
      PIN_LENGTH_LONG_PIN='0 MILS';
      CREATEDAY='20220525';
      PARENT_PART_TYPE='RS53317LR';
      PARENT_PPT='RS53317LR';
      PARENT_PPT_PART='RS53317LR-RS53317LR,SMLF,IC,AL053317005';
  end_body;
end_primitive;
primitive 'RS53318LR-RS53318LR,SMLF,IC,ALA';
  pin
    'VIN1':
      PIN_NUMBER='(10)';
      PINUSE='POWER';
      NO_LOAD_CHECK='Both';
      NO_IO_CHECK='Both';
      NO_ASSERT_CHECK='TRUE';
      NO_DIR_CHECK='TRUE';
      ALLOW_CONNECT='TRUE';
    'PGOOD':
      PIN_NUMBER='(9)';
      OUTPUT_LOAD='(1.0,-1.0)';
      PINUSE='OUT';
    'PGND':
      PIN_NUMBER='(11_18)';
      PINUSE='POWER';
      NO_LOAD_CHECK='Both';
      NO_IO_CHECK='Both';
      NO_ASSERT_CHECK='TRUE';
      NO_DIR_CHECK='TRUE';
      ALLOW_CONNECT='TRUE';
    'EN':
      PIN_NUMBER='(8)';
      INPUT_LOAD='(-0.01,0.01)';
      PINUSE='IN';
    'BST':
      PIN_NUMBER='(1)';
      INPUT_LOAD='(-0.01,0.01)';
      PINUSE='IN';
    'FB':
      PIN_NUMBER='(7)';
      INPUT_LOAD='(-0.01,0.01)';
      PINUSE='IN';
    'AGND':
      PIN_NUMBER='(2)';
      PINUSE='POWER';
      NO_LOAD_CHECK='Both';
      NO_IO_CHECK='Both';
      NO_ASSERT_CHECK='TRUE';
      NO_DIR_CHECK='TRUE';
      ALLOW_CONNECT='TRUE';
    'VCC':
      PIN_NUMBER='(19)';
      PINUSE='POWER';
      NO_LOAD_CHECK='Both';
      NO_IO_CHECK='Both';
      NO_ASSERT_CHECK='TRUE';
      NO_DIR_CHECK='TRUE';
      ALLOW_CONNECT='TRUE';
    'RTN':
      PIN_NUMBER='(6)';
      PINUSE='POWER';
      NO_LOAD_CHECK='Both';
      NO_IO_CHECK='Both';
      NO_ASSERT_CHECK='TRUE';
      NO_DIR_CHECK='TRUE';
      ALLOW_CONNECT='TRUE';
    'SW':
      PIN_NUMBER='(20)';
      OUTPUT_LOAD='(1.0,-1.0)';
      PINUSE='OUT';
    'REF':
      PIN_NUMBER='(5)';
      INPUT_LOAD='(-0.01,0.01)';
      PINUSE='IN';
    'MODE':
      PIN_NUMBER='(4)';
      INPUT_LOAD='(-0.01,0.01)';
      PINUSE='IN';
    'CS':
      PIN_NUMBER='(3)';
      INPUT_LOAD='(-0.01,0.01)';
      PINUSE='IN';
    'VIN2':
      PIN_NUMBER='(21)';
      PINUSE='POWER';
      NO_LOAD_CHECK='Both';
      NO_IO_CHECK='Both';
      NO_ASSERT_CHECK='TRUE';
      NO_DIR_CHECK='TRUE';
      ALLOW_CONNECT='TRUE';
  end_pin;
  body
      PART_NAME='RS53318LR';
      BODY_NAME='RS53318LR';
      PHYS_DES_PREFIX='U';
      CLASS='IC';
      STANDARD='';
      LIFECYCLE='';
      JEDEC_TYPE='QFN21_4X3';
      DESCRIPTION='IC(21P)RS53318LR(QFN)';
      MANUFTR='RDS';
      MANUF_PN='RS53318LR';
      RD_CMPLS_LVL='EP(V1)';
      CMPLS_LVL='EP(V1)';
      FROM_PJ='F0T-GREG';
      DIP_SMD='';
      DATA='RDS_RS53318LR.pdf';
      EE_CHECK_LIST='';
      FP_ECN='';
      PSL='';
      CREATOR='';
      STATUS='';
      MSD='';
      ESD_CDM='';
      ESD_HBM='';
      ESD_MM='';
      PIN_LENGTH_SHORT_PIN='0 MILS';
      PIN_LENGTH_LONG_PIN='0 MILS';
      CREATEDAY='20220510';
      PARENT_PART_TYPE='RS53318LR';
      PARENT_PPT='RS53318LR';
      PARENT_PPT_PART='RS53318LR-RS53318LR,SMLF,IC,AL053318002';
  end_body;
end_primitive;
primitive 'RS53319LR-RS53319LR,SMLF,IC,ALA';
  pin
    'VIN1':
      PIN_NUMBER='(10)';
      PINUSE='POWER';
      NO_LOAD_CHECK='Both';
      NO_IO_CHECK='Both';
      NO_ASSERT_CHECK='TRUE';
      NO_DIR_CHECK='TRUE';
      ALLOW_CONNECT='TRUE';
    'PGOOD':
      PIN_NUMBER='(9)';
      OUTPUT_LOAD='(1.0,-1.0)';
      PINUSE='OUT';
    'PGND':
      PIN_NUMBER='(11_18)';
      PINUSE='POWER';
      NO_LOAD_CHECK='Both';
      NO_IO_CHECK='Both';
      NO_ASSERT_CHECK='TRUE';
      NO_DIR_CHECK='TRUE';
      ALLOW_CONNECT='TRUE';
    'EN':
      PIN_NUMBER='(8)';
      INPUT_LOAD='(-0.01,0.01)';
      PINUSE='IN';
    'BST':
      PIN_NUMBER='(1)';
      INPUT_LOAD='(-0.01,0.01)';
      PINUSE='IN';
    'FB':
      PIN_NUMBER='(7)';
      INPUT_LOAD='(-0.01,0.01)';
      PINUSE='IN';
    'AGND':
      PIN_NUMBER='(2)';
      PINUSE='POWER';
      NO_LOAD_CHECK='Both';
      NO_IO_CHECK='Both';
      NO_ASSERT_CHECK='TRUE';
      NO_DIR_CHECK='TRUE';
      ALLOW_CONNECT='TRUE';
    'VCC':
      PIN_NUMBER='(19)';
      PINUSE='POWER';
      NO_LOAD_CHECK='Both';
      NO_IO_CHECK='Both';
      NO_ASSERT_CHECK='TRUE';
      NO_DIR_CHECK='TRUE';
      ALLOW_CONNECT='TRUE';
    'RTN':
      PIN_NUMBER='(6)';
      PINUSE='POWER';
      NO_LOAD_CHECK='Both';
      NO_IO_CHECK='Both';
      NO_ASSERT_CHECK='TRUE';
      NO_DIR_CHECK='TRUE';
      ALLOW_CONNECT='TRUE';
    'SW':
      PIN_NUMBER='(20)';
      OUTPUT_LOAD='(1.0,-1.0)';
      PINUSE='OUT';
    'REF':
      PIN_NUMBER='(5)';
      INPUT_LOAD='(-0.01,0.01)';
      PINUSE='IN';
    'MODE':
      PIN_NUMBER='(4)';
      INPUT_LOAD='(-0.01,0.01)';
      PINUSE='IN';
    'CS':
      PIN_NUMBER='(3)';
      INPUT_LOAD='(-0.01,0.01)';
      PINUSE='IN';
    'VIN2':
      PIN_NUMBER='(21)';
      PINUSE='POWER';
      NO_LOAD_CHECK='Both';
      NO_IO_CHECK='Both';
      NO_ASSERT_CHECK='TRUE';
      NO_DIR_CHECK='TRUE';
      ALLOW_CONNECT='TRUE';
  end_pin;
  body
      PART_NAME='RS53319LR';
      BODY_NAME='RS53319LR';
      PHYS_DES_PREFIX='U';
      CLASS='IC';
      STANDARD='';
      LIFECYCLE='';
      JEDEC_TYPE='QFN21_4X3';
      DESCRIPTION='IC(21P)RS53319LR(QFN)';
      MANUFTR='RDS';
      MANUF_PN='RS53319LR';
      RD_CMPLS_LVL='EP(V1)';
      CMPLS_LVL='EP(V1)';
      FROM_PJ='F0T-GREG';
      DIP_SMD='';
      DATA='RDS_RS53319LR.pdf';
      EE_CHECK_LIST='';
      FP_ECN='';
      PSL='';
      CREATOR='';
      STATUS='';
      MSD='';
      ESD_CDM='';
      ESD_HBM='';
      ESD_MM='';
      PIN_LENGTH_SHORT_PIN='0 MILS';
      PIN_LENGTH_LONG_PIN='0 MILS';
      CREATEDAY='20220510';
      PARENT_PART_TYPE='RS53319LR';
      PARENT_PPT='RS53319LR';
      PARENT_PPT_PART='RS53319LR-RS53319LR,SMLF,IC,AL053319002';
  end_body;
end_primitive;
primitive 'RT9818C44GV-RT9818C-44GV,SMLF,A';
  pin
    'VDD':
      PIN_NUMBER='(3)';
      PINUSE='POWER';
      NO_LOAD_CHECK='Both';
      NO_IO_CHECK='Both';
      NO_ASSERT_CHECK='TRUE';
      NO_DIR_CHECK='TRUE';
      ALLOW_CONNECT='TRUE';
    'RESET#':
      PIN_NUMBER='(1)';
      OUTPUT_LOAD='(1.0,-1.0)';
      PINUSE='OUT';
    'GND':
      PIN_NUMBER='(2)';
      PINUSE='POWER';
      NO_LOAD_CHECK='Both';
      NO_IO_CHECK='Both';
      NO_ASSERT_CHECK='TRUE';
      NO_DIR_CHECK='TRUE';
      ALLOW_CONNECT='TRUE';
  end_pin;
  body
      PART_NAME='RT9818C44GV';
      BODY_NAME='RT9818C44GV';
      PHYS_DES_PREFIX='U';
      CLASS='IC';
      STANDARD='';
      LIFECYCLE='';
      JEDEC_TYPE='SOT23_123_2-89X1-6';
      DESCRIPTION='IC OTHER(3P)RT9818C-44GV(SOT23-3)';
      MANUFTR='RTK';
      MANUF_PN='RT9818C-44GV';
      RD_CMPLS_LVL='EP(V1)';
      CMPLS_LVL='';
      FROM_PJ='S5B-YU-LIN';
      DIP_SMD='';
      DATA='RTK_RT9818C-44GV.pdf';
      EE_CHECK_LIST='';
      FP_ECN='';
      PSL='';
      CREATOR='';
      STATUS='';
      CREATEDAY='20150914';
      PARENT_PART_TYPE='RT9818C44GV';
      PARENT_PPT='RT9818C44GV';
      PARENT_PPT_PART='RT9818C44GV-RT9818C-44GV,SMLF,IC,AL009818001';
  end_body;
end_primitive;
primitive 'SCHOTTKY_12-1N5819HW,SMLF,IC,BA';
  pin
    'A':
      PIN_NUMBER='(1)';
      INPUT_LOAD='(-0.01,0.01)';
      PINUSE='IN';
    'C':
      PIN_NUMBER='(2)';
      BIDIRECTIONAL='TRUE';
      INPUT_LOAD='(-0.01,0.01)';
      OUTPUT_LOAD='(1.0,-1.0)';
      PINUSE='BI';
  end_pin;
  body
      PART_NAME='SCHOTTKY_12';
      BODY_NAME='SCHOTTKY_12';
      PHYS_DES_PREFIX='D';
      CLASS='IC';
      STANDARD='End of Design';
      LIFECYCLE='Comp-Approve';
      JEDEC_TYPE='SOD123';
      DESCRIPTION='DIODE SMD 1N5819HW-7-F(40V.1A.SOD123)';
      MANUFTR='DDS';
      MANUF_PN='1N5819HW-7-F';
      RD_CMPLS_LVL='';
      CMPLS_LVL='EP';
      DIP_SMD='';
      FP_ECN='';
      FROM_PJ='T2H-WADE';
      DATA='DDS_1N5819HW.pdf';
      EE_CHECK_LIST='';
      STATUS='';
      PSL='';
      PREFERENCE='';
      CREATOR='';
      CREATEDAY='20151228';
      PARENT_PART_TYPE='SCHOTTKY_12';
      PARENT_PPT='SCHOTTKY_12';
      PARENT_PPT_PART='SCHOTTKY_12-1N5819HW,SMLF,IC,BC005819Z40';
  end_body;
end_primitive;
primitive 'SCHOTTKY_12-B0530WS7F,SMLF,IC,A';
  pin
    'A':
      PIN_NUMBER='(1)';
      INPUT_LOAD='(-0.01,0.01)';
      PINUSE='IN';
    'C':
      PIN_NUMBER='(2)';
      BIDIRECTIONAL='TRUE';
      INPUT_LOAD='(-0.01,0.01)';
      OUTPUT_LOAD='(1.0,-1.0)';
      PINUSE='BI';
  end_pin;
  body
      PART_NAME='SCHOTTKY_12';
      BODY_NAME='SCHOTTKY_12';
      PHYS_DES_PREFIX='D';
      CLASS='IC';
      STANDARD='End of Design';
      LIFECYCLE='Comp-Approve';
      JEDEC_TYPE='SOD323XB';
      DESCRIPTION='DIODE SMD B0530WS-7-F(30V,0.5A)SOD-323';
      MANUFTR='DDS';
      MANUF_PN='B0530WS-7-F';
      RD_CMPLS_LVL='EP';
      CMPLS_LVL='EP(V1)';
      DIP_SMD='';
      FP_ECN='';
      FROM_PJ='T2R-GAVEN';
      DATA='B0530WS-7-F.pdf';
      EE_CHECK_LIST='';
      STATUS='';
      PSL='';
      PREFERENCE='';
      CREATOR='';
      CREATEDAY='20140704';
      PARENT_PART_TYPE='SCHOTTKY_12';
      PARENT_PPT='SCHOTTKY_12';
      PARENT_PPT_PART='SCHOTTKY_12-B0530WS7F,SMLF,IC,BC000530Z41';
  end_body;
end_primitive;
primitive 'SCHOTTKY_AC-B340A-13-F,SMLF,ICA';
  pin
    'A':
      PIN_NUMBER='(A)';
      INPUT_LOAD='(-0.01,0.01)';
      PINUSE='IN';
    'C':
      PIN_NUMBER='(C)';
      BIDIRECTIONAL='TRUE';
      INPUT_LOAD='(-0.01,0.01)';
      OUTPUT_LOAD='(1.0,-1.0)';
      PINUSE='BI';
  end_pin;
  body
      PART_NAME='SCHOTTKY_AC';
      BODY_NAME='SCHOTTKY_AC';
      PHYS_DES_PREFIX='D';
      CLASS='IC';
      STANDARD='';
      LIFECYCLE='';
      JEDEC_TYPE='D2010XF';
      DESCRIPTION='DIODE SMD B340A-13-F(40V,3A)SCHOTTKY';
      MANUFTR='DDS';
      MANUF_PN='B340A-13-F';
      RD_CMPLS_LVL='EP(V1)';
      CMPLS_LVL='EP(V1)';
      DIP_SMD='';
      FP_ECN='';
      FROM_PJ='S5B-ROSSI';
      DATA='DDS_B340A-13-F.pdf';
      EE_CHECK_LIST='';
      PSL='';
      PREFERENCE='';
      CREATOR='';
      CREATEDAY='20151231';
      STATUS='';
      PARENT_PART_TYPE='SCHOTTKY_AC';
      PARENT_PPT='SCHOTTKY_AC';
      PARENT_PPT_PART='SCHOTTKY_AC-B340A-13-F,SMLF,IC,BC000340Z30';
  end_body;
end_primitive;
primitive 'SCONN168_ME1016810202011-SCONNA';
  pin
    'NIC_PWR_GOOD':
      PIN_NUMBER='(OB1)';
      INPUT_LOAD='(-0.01,0.01)';
      PINUSE='IN';
    'MAIN_PWR_EN':
      PIN_NUMBER='(OB2)';
      OUTPUT_LOAD='(1.0,-1.0)';
      PINUSE='OUT';
    'LD#':
      PIN_NUMBER='(OB3)';
      OUTPUT_LOAD='(1.0,-1.0)';
      PINUSE='OUT';
    'DATA_IN':
      PIN_NUMBER='(OB4)';
      INPUT_LOAD='(-0.01,0.01)';
      PINUSE='IN';
    'DATA_OUT':
      PIN_NUMBER='(OB5)';
      OUTPUT_LOAD='(1.0,-1.0)';
      PINUSE='OUT';
    'CLK':
      PIN_NUMBER='(OB6)';
      OUTPUT_LOAD='(1.0,-1.0)';
      PINUSE='OUT';
    'SLOT_ID0':
      PIN_NUMBER='(OB7)';
      OUTPUT_LOAD='(1.0,-1.0)';
      PINUSE='OUT';
    'RBT_RXD1':
      PIN_NUMBER='(OB8)';
      INPUT_LOAD='(-0.01,0.01)';
      PINUSE='IN';
    'RBT_RXD0':
      PIN_NUMBER='(OB9)';
      INPUT_LOAD='(-0.01,0.01)';
      PINUSE='IN';
    'GND_OB10':
      PIN_NUMBER='(OB10)';
      PINUSE='POWER';
      NO_LOAD_CHECK='Both';
      NO_IO_CHECK='Both';
      NO_ASSERT_CHECK='TRUE';
      NO_DIR_CHECK='TRUE';
      ALLOW_CONNECT='TRUE';
    'REFCLKN2':
      PIN_NUMBER='(OB11)';
      OUTPUT_LOAD='(1.0,-1.0)';
      PINUSE='OUT';
    'REFCLKP2':
      PIN_NUMBER='(OB12)';
      OUTPUT_LOAD='(1.0,-1.0)';
      PINUSE='OUT';
    'GND_OB13':
      PIN_NUMBER='(OB13)';
      PINUSE='POWER';
      NO_LOAD_CHECK='Both';
      NO_IO_CHECK='Both';
      NO_ASSERT_CHECK='TRUE';
      NO_DIR_CHECK='TRUE';
      ALLOW_CONNECT='TRUE';
    'RBT_CRS_DV':
      PIN_NUMBER='(OB14)';
      OUTPUT_LOAD='(1.0,-1.0)';
      PINUSE='OUT';
    '+12V_EDGE_B1':
      PIN_NUMBER='(B1)';
      PINUSE='POWER';
      NO_LOAD_CHECK='Both';
      NO_IO_CHECK='Both';
      NO_ASSERT_CHECK='TRUE';
      NO_DIR_CHECK='TRUE';
      ALLOW_CONNECT='TRUE';
    '+12V_EDGE_B2':
      PIN_NUMBER='(B2)';
      PINUSE='POWER';
      NO_LOAD_CHECK='Both';
      NO_IO_CHECK='Both';
      NO_ASSERT_CHECK='TRUE';
      NO_DIR_CHECK='TRUE';
      ALLOW_CONNECT='TRUE';
    '+12V_EDGE_B3':
      PIN_NUMBER='(B3)';
      PINUSE='POWER';
      NO_LOAD_CHECK='Both';
      NO_IO_CHECK='Both';
      NO_ASSERT_CHECK='TRUE';
      NO_DIR_CHECK='TRUE';
      ALLOW_CONNECT='TRUE';
    '+12V_EDGE_B4':
      PIN_NUMBER='(B4)';
      PINUSE='POWER';
      NO_LOAD_CHECK='Both';
      NO_IO_CHECK='Both';
      NO_ASSERT_CHECK='TRUE';
      NO_DIR_CHECK='TRUE';
      ALLOW_CONNECT='TRUE';
    '+12V_EDGE_B5':
      PIN_NUMBER='(B5)';
      PINUSE='POWER';
      NO_LOAD_CHECK='Both';
      NO_IO_CHECK='Both';
      NO_ASSERT_CHECK='TRUE';
      NO_DIR_CHECK='TRUE';
      ALLOW_CONNECT='TRUE';
    '+12V_EDGE_B6':
      PIN_NUMBER='(B6)';
      PINUSE='POWER';
      NO_LOAD_CHECK='Both';
      NO_IO_CHECK='Both';
      NO_ASSERT_CHECK='TRUE';
      NO_DIR_CHECK='TRUE';
      ALLOW_CONNECT='TRUE';
    'BIF0#':
      PIN_NUMBER='(B7)';
      OUTPUT_LOAD='(1.0,-1.0)';
      PINUSE='OUT';
    'BIF1#':
      PIN_NUMBER='(B8)';
      OUTPUT_LOAD='(1.0,-1.0)';
      PINUSE='OUT';
    'BIF2#':
      PIN_NUMBER='(B9)';
      OUTPUT_LOAD='(1.0,-1.0)';
      PINUSE='OUT';
    'PERST0#':
      PIN_NUMBER='(B10)';
      OUTPUT_LOAD='(1.0,-1.0)';
      PINUSE='OUT';
    '+3.3V_EDGE':
      PIN_NUMBER='(B11)';
      PINUSE='POWER';
      NO_LOAD_CHECK='Both';
      NO_IO_CHECK='Both';
      NO_ASSERT_CHECK='TRUE';
      NO_DIR_CHECK='TRUE';
      ALLOW_CONNECT='TRUE';
    'AUX_PWR_EN':
      PIN_NUMBER='(B12)';
      OUTPUT_LOAD='(1.0,-1.0)';
      PINUSE='OUT';
    'GND_B13':
      PIN_NUMBER='(B13)';
      PINUSE='POWER';
      NO_LOAD_CHECK='Both';
      NO_IO_CHECK='Both';
      NO_ASSERT_CHECK='TRUE';
      NO_DIR_CHECK='TRUE';
      ALLOW_CONNECT='TRUE';
    'REFCLKN0':
      PIN_NUMBER='(B14)';
      INPUT_LOAD='(-0.01,0.01)';
      PINUSE='IN';
    'REFCLKP0':
      PIN_NUMBER='(B15)';
      OUTPUT_LOAD='(1.0,-1.0)';
      PINUSE='OUT';
    'GND_B16':
      PIN_NUMBER='(B16)';
      PINUSE='POWER';
      NO_LOAD_CHECK='Both';
      NO_IO_CHECK='Both';
      NO_ASSERT_CHECK='TRUE';
      NO_DIR_CHECK='TRUE';
      ALLOW_CONNECT='TRUE';
    'PETN0':
      PIN_NUMBER='(B17)';
      OUTPUT_LOAD='(1.0,-1.0)';
      PINUSE='OUT';
    'PETP0':
      PIN_NUMBER='(B18)';
      OUTPUT_LOAD='(1.0,-1.0)';
      PINUSE='OUT';
    'GND_B19':
      PIN_NUMBER='(B19)';
      PINUSE='POWER';
      NO_LOAD_CHECK='Both';
      NO_IO_CHECK='Both';
      NO_ASSERT_CHECK='TRUE';
      NO_DIR_CHECK='TRUE';
      ALLOW_CONNECT='TRUE';
    'PETN1':
      PIN_NUMBER='(B20)';
      OUTPUT_LOAD='(1.0,-1.0)';
      PINUSE='OUT';
    'PETP1':
      PIN_NUMBER='(B21)';
      OUTPUT_LOAD='(1.0,-1.0)';
      PINUSE='OUT';
    'GND_B22':
      PIN_NUMBER='(B22)';
      PINUSE='POWER';
      NO_LOAD_CHECK='Both';
      NO_IO_CHECK='Both';
      NO_ASSERT_CHECK='TRUE';
      NO_DIR_CHECK='TRUE';
      ALLOW_CONNECT='TRUE';
    'PETN2':
      PIN_NUMBER='(B23)';
      OUTPUT_LOAD='(1.0,-1.0)';
      PINUSE='OUT';
    'PETP2':
      PIN_NUMBER='(B24)';
      OUTPUT_LOAD='(1.0,-1.0)';
      PINUSE='OUT';
    'GND_B25':
      PIN_NUMBER='(B25)';
      PINUSE='POWER';
      NO_LOAD_CHECK='Both';
      NO_IO_CHECK='Both';
      NO_ASSERT_CHECK='TRUE';
      NO_DIR_CHECK='TRUE';
      ALLOW_CONNECT='TRUE';
    'PETN3':
      PIN_NUMBER='(B26)';
      OUTPUT_LOAD='(1.0,-1.0)';
      PINUSE='OUT';
    'PETP3':
      PIN_NUMBER='(B27)';
      OUTPUT_LOAD='(1.0,-1.0)';
      PINUSE='OUT';
    'GND_B28':
      PIN_NUMBER='(B28)';
      PINUSE='POWER';
      NO_LOAD_CHECK='Both';
      NO_IO_CHECK='Both';
      NO_ASSERT_CHECK='TRUE';
      NO_DIR_CHECK='TRUE';
      ALLOW_CONNECT='TRUE';
    'GND_B29':
      PIN_NUMBER='(B29)';
      PINUSE='POWER';
      NO_LOAD_CHECK='Both';
      NO_IO_CHECK='Both';
      NO_ASSERT_CHECK='TRUE';
      NO_DIR_CHECK='TRUE';
      ALLOW_CONNECT='TRUE';
    'PETN4':
      PIN_NUMBER='(B30)';
      OUTPUT_LOAD='(1.0,-1.0)';
      PINUSE='OUT';
    'PETP4':
      PIN_NUMBER='(B31)';
      OUTPUT_LOAD='(1.0,-1.0)';
      PINUSE='OUT';
    'GND_B32':
      PIN_NUMBER='(B32)';
      PINUSE='POWER';
      NO_LOAD_CHECK='Both';
      NO_IO_CHECK='Both';
      NO_ASSERT_CHECK='TRUE';
      NO_DIR_CHECK='TRUE';
      ALLOW_CONNECT='TRUE';
    'PETN5':
      PIN_NUMBER='(B33)';
      OUTPUT_LOAD='(1.0,-1.0)';
      PINUSE='OUT';
    'PETP5':
      PIN_NUMBER='(B34)';
      OUTPUT_LOAD='(1.0,-1.0)';
      PINUSE='OUT';
    'GND_B35':
      PIN_NUMBER='(B35)';
      PINUSE='POWER';
      NO_LOAD_CHECK='Both';
      NO_IO_CHECK='Both';
      NO_ASSERT_CHECK='TRUE';
      NO_DIR_CHECK='TRUE';
      ALLOW_CONNECT='TRUE';
    'PETN6':
      PIN_NUMBER='(B36)';
      OUTPUT_LOAD='(1.0,-1.0)';
      PINUSE='OUT';
    'PETP6':
      PIN_NUMBER='(B37)';
      OUTPUT_LOAD='(1.0,-1.0)';
      PINUSE='OUT';
    'GND_B38':
      PIN_NUMBER='(B38)';
      PINUSE='POWER';
      NO_LOAD_CHECK='Both';
      NO_IO_CHECK='Both';
      NO_ASSERT_CHECK='TRUE';
      NO_DIR_CHECK='TRUE';
      ALLOW_CONNECT='TRUE';
    'PETN7':
      PIN_NUMBER='(B39)';
      OUTPUT_LOAD='(1.0,-1.0)';
      PINUSE='OUT';
    'PETP7':
      PIN_NUMBER='(B40)';
      OUTPUT_LOAD='(1.0,-1.0)';
      PINUSE='OUT';
    'GND_B41':
      PIN_NUMBER='(B41)';
      PINUSE='POWER';
      NO_LOAD_CHECK='Both';
      NO_IO_CHECK='Both';
      NO_ASSERT_CHECK='TRUE';
      NO_DIR_CHECK='TRUE';
      ALLOW_CONNECT='TRUE';
    'PRSNTB0#':
      PIN_NUMBER='(B42)';
      INPUT_LOAD='(-0.01,0.01)';
      PINUSE='IN';
    'GND_B43':
      PIN_NUMBER='(B43)';
      PINUSE='POWER';
      NO_LOAD_CHECK='Both';
      NO_IO_CHECK='Both';
      NO_ASSERT_CHECK='TRUE';
      NO_DIR_CHECK='TRUE';
      ALLOW_CONNECT='TRUE';
    'PETN8':
      PIN_NUMBER='(B44)';
      OUTPUT_LOAD='(1.0,-1.0)';
      PINUSE='OUT';
    'PETP8':
      PIN_NUMBER='(B45)';
      OUTPUT_LOAD='(1.0,-1.0)';
      PINUSE='OUT';
    'GND_B46':
      PIN_NUMBER='(B46)';
      PINUSE='POWER';
      NO_LOAD_CHECK='Both';
      NO_IO_CHECK='Both';
      NO_ASSERT_CHECK='TRUE';
      NO_DIR_CHECK='TRUE';
      ALLOW_CONNECT='TRUE';
    'PETN9':
      PIN_NUMBER='(B47)';
      OUTPUT_LOAD='(1.0,-1.0)';
      PINUSE='OUT';
    'PETP9':
      PIN_NUMBER='(B48)';
      OUTPUT_LOAD='(1.0,-1.0)';
      PINUSE='OUT';
    'GND_B49':
      PIN_NUMBER='(B49)';
      PINUSE='POWER';
      NO_LOAD_CHECK='Both';
      NO_IO_CHECK='Both';
      NO_ASSERT_CHECK='TRUE';
      NO_DIR_CHECK='TRUE';
      ALLOW_CONNECT='TRUE';
    'PETN10':
      PIN_NUMBER='(B50)';
      OUTPUT_LOAD='(1.0,-1.0)';
      PINUSE='OUT';
    'PETP10':
      PIN_NUMBER='(B51)';
      OUTPUT_LOAD='(1.0,-1.0)';
      PINUSE='OUT';
    'GND_B52':
      PIN_NUMBER='(B52)';
      PINUSE='POWER';
      NO_LOAD_CHECK='Both';
      NO_IO_CHECK='Both';
      NO_ASSERT_CHECK='TRUE';
      NO_DIR_CHECK='TRUE';
      ALLOW_CONNECT='TRUE';
    'PETN11':
      PIN_NUMBER='(B53)';
      OUTPUT_LOAD='(1.0,-1.0)';
      PINUSE='OUT';
    'PETP11':
      PIN_NUMBER='(B54)';
      OUTPUT_LOAD='(1.0,-1.0)';
      PINUSE='OUT';
    'GND_B55':
      PIN_NUMBER='(B55)';
      PINUSE='POWER';
      NO_LOAD_CHECK='Both';
      NO_IO_CHECK='Both';
      NO_ASSERT_CHECK='TRUE';
      NO_DIR_CHECK='TRUE';
      ALLOW_CONNECT='TRUE';
    'PETN12':
      PIN_NUMBER='(B56)';
      OUTPUT_LOAD='(1.0,-1.0)';
      PINUSE='OUT';
    'PERST2#':
      PIN_NUMBER='(OA1)';
      OUTPUT_LOAD='(1.0,-1.0)';
      PINUSE='OUT';
    'PERST3#':
      PIN_NUMBER='(OA2)';
      OUTPUT_LOAD='(1.0,-1.0)';
      PINUSE='OUT';
    'WAKE#':
      PIN_NUMBER='(OA3)';
      INPUT_LOAD='(-0.01,0.01)';
      PINUSE='IN';
    'RBT_ARB_IN':
      PIN_NUMBER='(OA4)';
      INPUT_LOAD='(-0.01,0.01)';
      PINUSE='IN';
    'RBT_ARB_OUT':
      PIN_NUMBER='(OA5)';
      OUTPUT_LOAD='(1.0,-1.0)';
      PINUSE='OUT';
    'SLOT_ID1':
      PIN_NUMBER='(OA6)';
      OUTPUT_LOAD='(1.0,-1.0)';
      PINUSE='OUT';
    'RBT_TX_EN':
      PIN_NUMBER='(OA7)';
      OUTPUT_LOAD='(1.0,-1.0)';
      PINUSE='OUT';
    'RBT_TXD1':
      PIN_NUMBER='(OA8)';
      OUTPUT_LOAD='(1.0,-1.0)';
      PINUSE='OUT';
    'RBT_TXD0':
      PIN_NUMBER='(OA9)';
      OUTPUT_LOAD='(1.0,-1.0)';
      PINUSE='OUT';
    'GND_OA10':
      PIN_NUMBER='(OA10)';
      PINUSE='POWER';
      NO_LOAD_CHECK='Both';
      NO_IO_CHECK='Both';
      NO_ASSERT_CHECK='TRUE';
      NO_DIR_CHECK='TRUE';
      ALLOW_CONNECT='TRUE';
    'REFCLKN3':
      PIN_NUMBER='(OA11)';
      OUTPUT_LOAD='(1.0,-1.0)';
      PINUSE='OUT';
    'REFCLKP3':
      PIN_NUMBER='(OA12)';
      OUTPUT_LOAD='(1.0,-1.0)';
      PINUSE='OUT';
    'GND_OA13':
      PIN_NUMBER='(OA13)';
      PINUSE='POWER';
      NO_LOAD_CHECK='Both';
      NO_IO_CHECK='Both';
      NO_ASSERT_CHECK='TRUE';
      NO_DIR_CHECK='TRUE';
      ALLOW_CONNECT='TRUE';
    'RBT_CLK_IN':
      PIN_NUMBER='(OA14)';
      OUTPUT_LOAD='(1.0,-1.0)';
      PINUSE='OUT';
    'GND_A1':
      PIN_NUMBER='(A1)';
      PINUSE='POWER';
      NO_LOAD_CHECK='Both';
      NO_IO_CHECK='Both';
      NO_ASSERT_CHECK='TRUE';
      NO_DIR_CHECK='TRUE';
      ALLOW_CONNECT='TRUE';
    'GND_A2':
      PIN_NUMBER='(A2)';
      PINUSE='POWER';
      NO_LOAD_CHECK='Both';
      NO_IO_CHECK='Both';
      NO_ASSERT_CHECK='TRUE';
      NO_DIR_CHECK='TRUE';
      ALLOW_CONNECT='TRUE';
    'GND_A3':
      PIN_NUMBER='(A3)';
      PINUSE='POWER';
      NO_LOAD_CHECK='Both';
      NO_IO_CHECK='Both';
      NO_ASSERT_CHECK='TRUE';
      NO_DIR_CHECK='TRUE';
      ALLOW_CONNECT='TRUE';
    'GND_A4':
      PIN_NUMBER='(A4)';
      PINUSE='POWER';
      NO_LOAD_CHECK='Both';
      NO_IO_CHECK='Both';
      NO_ASSERT_CHECK='TRUE';
      NO_DIR_CHECK='TRUE';
      ALLOW_CONNECT='TRUE';
    'GND_A5':
      PIN_NUMBER='(A5)';
      PINUSE='POWER';
      NO_LOAD_CHECK='Both';
      NO_IO_CHECK='Both';
      NO_ASSERT_CHECK='TRUE';
      NO_DIR_CHECK='TRUE';
      ALLOW_CONNECT='TRUE';
    'GND_A6':
      PIN_NUMBER='(A6)';
      PINUSE='POWER';
      NO_LOAD_CHECK='Both';
      NO_IO_CHECK='Both';
      NO_ASSERT_CHECK='TRUE';
      NO_DIR_CHECK='TRUE';
      ALLOW_CONNECT='TRUE';
    'SMCLK':
      PIN_NUMBER='(A7)';
      OUTPUT_LOAD='(1.0,-1.0)';
      PINUSE='OUT';
    'SMDAT':
      PIN_NUMBER='(A8)';
      BIDIRECTIONAL='TRUE';
      INPUT_LOAD='(-0.01,0.01)';
      OUTPUT_LOAD='(1.0,-1.0)';
      PINUSE='BI';
    'SMRST#':
      PIN_NUMBER='(A9)';
      OUTPUT_LOAD='(1.0,-1.0)';
      PINUSE='OUT';
    'PRSNTA#':
      PIN_NUMBER='(A10)';
      OUTPUT_LOAD='(1.0,-1.0)';
      PINUSE='OUT';
    'PERST1#':
      PIN_NUMBER='(A11)';
      OUTPUT_LOAD='(1.0,-1.0)';
      PINUSE='OUT';
    'PRSNTB2#':
      PIN_NUMBER='(A12)';
      INPUT_LOAD='(-0.01,0.01)';
      PINUSE='IN';
    'GND_A13':
      PIN_NUMBER='(A13)';
      PINUSE='POWER';
      NO_LOAD_CHECK='Both';
      NO_IO_CHECK='Both';
      NO_ASSERT_CHECK='TRUE';
      NO_DIR_CHECK='TRUE';
      ALLOW_CONNECT='TRUE';
    'REFCLKN1':
      PIN_NUMBER='(A14)';
      OUTPUT_LOAD='(1.0,-1.0)';
      PINUSE='OUT';
    'REFCLKP1':
      PIN_NUMBER='(A15)';
      OUTPUT_LOAD='(1.0,-1.0)';
      PINUSE='OUT';
    'GND_A16':
      PIN_NUMBER='(A16)';
      PINUSE='POWER';
      NO_LOAD_CHECK='Both';
      NO_IO_CHECK='Both';
      NO_ASSERT_CHECK='TRUE';
      NO_DIR_CHECK='TRUE';
      ALLOW_CONNECT='TRUE';
    'PERN0':
      PIN_NUMBER='(A17)';
      INPUT_LOAD='(-0.01,0.01)';
      PINUSE='IN';
    'PERP0':
      PIN_NUMBER='(A18)';
      INPUT_LOAD='(-0.01,0.01)';
      PINUSE='IN';
    'GND_A19':
      PIN_NUMBER='(A19)';
      PINUSE='POWER';
      NO_LOAD_CHECK='Both';
      NO_IO_CHECK='Both';
      NO_ASSERT_CHECK='TRUE';
      NO_DIR_CHECK='TRUE';
      ALLOW_CONNECT='TRUE';
    'PERN1':
      PIN_NUMBER='(A20)';
      INPUT_LOAD='(-0.01,0.01)';
      PINUSE='IN';
    'PERP1':
      PIN_NUMBER='(A21)';
      INPUT_LOAD='(-0.01,0.01)';
      PINUSE='IN';
    'GND_A22':
      PIN_NUMBER='(A22)';
      PINUSE='POWER';
      NO_LOAD_CHECK='Both';
      NO_IO_CHECK='Both';
      NO_ASSERT_CHECK='TRUE';
      NO_DIR_CHECK='TRUE';
      ALLOW_CONNECT='TRUE';
    'PERN2':
      PIN_NUMBER='(A23)';
      INPUT_LOAD='(-0.01,0.01)';
      PINUSE='IN';
    'PERP2':
      PIN_NUMBER='(A24)';
      INPUT_LOAD='(-0.01,0.01)';
      PINUSE='IN';
    'GND_A25':
      PIN_NUMBER='(A25)';
      PINUSE='POWER';
      NO_LOAD_CHECK='Both';
      NO_IO_CHECK='Both';
      NO_ASSERT_CHECK='TRUE';
      NO_DIR_CHECK='TRUE';
      ALLOW_CONNECT='TRUE';
    'PERN3':
      PIN_NUMBER='(A26)';
      INPUT_LOAD='(-0.01,0.01)';
      PINUSE='IN';
    'PERP3':
      PIN_NUMBER='(A27)';
      INPUT_LOAD='(-0.01,0.01)';
      PINUSE='IN';
    'GND_A28':
      PIN_NUMBER='(A28)';
      PINUSE='POWER';
      NO_LOAD_CHECK='Both';
      NO_IO_CHECK='Both';
      NO_ASSERT_CHECK='TRUE';
      NO_DIR_CHECK='TRUE';
      ALLOW_CONNECT='TRUE';
    'GND_A29':
      PIN_NUMBER='(A29)';
      PINUSE='POWER';
      NO_LOAD_CHECK='Both';
      NO_IO_CHECK='Both';
      NO_ASSERT_CHECK='TRUE';
      NO_DIR_CHECK='TRUE';
      ALLOW_CONNECT='TRUE';
    'PERN4':
      PIN_NUMBER='(A30)';
      INPUT_LOAD='(-0.01,0.01)';
      PINUSE='IN';
    'PERP4':
      PIN_NUMBER='(A31)';
      INPUT_LOAD='(-0.01,0.01)';
      PINUSE='IN';
    'GND_A32':
      PIN_NUMBER='(A32)';
      PINUSE='POWER';
      NO_LOAD_CHECK='Both';
      NO_IO_CHECK='Both';
      NO_ASSERT_CHECK='TRUE';
      NO_DIR_CHECK='TRUE';
      ALLOW_CONNECT='TRUE';
    'PERN5':
      PIN_NUMBER='(A33)';
      INPUT_LOAD='(-0.01,0.01)';
      PINUSE='IN';
    'PERP5':
      PIN_NUMBER='(A34)';
      INPUT_LOAD='(-0.01,0.01)';
      PINUSE='IN';
    'GND_A35':
      PIN_NUMBER='(A35)';
      PINUSE='POWER';
      NO_LOAD_CHECK='Both';
      NO_IO_CHECK='Both';
      NO_ASSERT_CHECK='TRUE';
      NO_DIR_CHECK='TRUE';
      ALLOW_CONNECT='TRUE';
    'PERN6':
      PIN_NUMBER='(A36)';
      INPUT_LOAD='(-0.01,0.01)';
      PINUSE='IN';
    'PERP6':
      PIN_NUMBER='(A37)';
      INPUT_LOAD='(-0.01,0.01)';
      PINUSE='IN';
    'GND_A38':
      PIN_NUMBER='(A38)';
      PINUSE='POWER';
      NO_LOAD_CHECK='Both';
      NO_IO_CHECK='Both';
      NO_ASSERT_CHECK='TRUE';
      NO_DIR_CHECK='TRUE';
      ALLOW_CONNECT='TRUE';
    'PERN7':
      PIN_NUMBER='(A39)';
      INPUT_LOAD='(-0.01,0.01)';
      PINUSE='IN';
    'PERP7':
      PIN_NUMBER='(A40)';
      INPUT_LOAD='(-0.01,0.01)';
      PINUSE='IN';
    'GND_A41':
      PIN_NUMBER='(A41)';
      PINUSE='POWER';
      NO_LOAD_CHECK='Both';
      NO_IO_CHECK='Both';
      NO_ASSERT_CHECK='TRUE';
      NO_DIR_CHECK='TRUE';
      ALLOW_CONNECT='TRUE';
    'PRSNTB1#':
      PIN_NUMBER='(A42)';
      INPUT_LOAD='(-0.01,0.01)';
      PINUSE='IN';
    'GND_A43':
      PIN_NUMBER='(A43)';
      PINUSE='POWER';
      NO_LOAD_CHECK='Both';
      NO_IO_CHECK='Both';
      NO_ASSERT_CHECK='TRUE';
      NO_DIR_CHECK='TRUE';
      ALLOW_CONNECT='TRUE';
    'PERN8':
      PIN_NUMBER='(A44)';
      INPUT_LOAD='(-0.01,0.01)';
      PINUSE='IN';
    'PERP8':
      PIN_NUMBER='(A45)';
      INPUT_LOAD='(-0.01,0.01)';
      PINUSE='IN';
    'GND_A46':
      PIN_NUMBER='(A46)';
      PINUSE='POWER';
      NO_LOAD_CHECK='Both';
      NO_IO_CHECK='Both';
      NO_ASSERT_CHECK='TRUE';
      NO_DIR_CHECK='TRUE';
      ALLOW_CONNECT='TRUE';
    'PERN9':
      PIN_NUMBER='(A47)';
      INPUT_LOAD='(-0.01,0.01)';
      PINUSE='IN';
    'PERP9':
      PIN_NUMBER='(A48)';
      INPUT_LOAD='(-0.01,0.01)';
      PINUSE='IN';
    'GND_A49':
      PIN_NUMBER='(A49)';
      PINUSE='POWER';
      NO_LOAD_CHECK='Both';
      NO_IO_CHECK='Both';
      NO_ASSERT_CHECK='TRUE';
      NO_DIR_CHECK='TRUE';
      ALLOW_CONNECT='TRUE';
    'PERN10':
      PIN_NUMBER='(A50)';
      INPUT_LOAD='(-0.01,0.01)';
      PINUSE='IN';
    'PERP10':
      PIN_NUMBER='(A51)';
      INPUT_LOAD='(-0.01,0.01)';
      PINUSE='IN';
    'GND_A52':
      PIN_NUMBER='(A52)';
      PINUSE='POWER';
      NO_LOAD_CHECK='Both';
      NO_IO_CHECK='Both';
      NO_ASSERT_CHECK='TRUE';
      NO_DIR_CHECK='TRUE';
      ALLOW_CONNECT='TRUE';
    'PERN11':
      PIN_NUMBER='(A53)';
      INPUT_LOAD='(-0.01,0.01)';
      PINUSE='IN';
    'PERP11':
      PIN_NUMBER='(A54)';
      INPUT_LOAD='(-0.01,0.01)';
      PINUSE='IN';
    'GND_A55':
      PIN_NUMBER='(A55)';
      PINUSE='POWER';
      NO_LOAD_CHECK='Both';
      NO_IO_CHECK='Both';
      NO_ASSERT_CHECK='TRUE';
      NO_DIR_CHECK='TRUE';
      ALLOW_CONNECT='TRUE';
    'PERN12':
      PIN_NUMBER='(A56)';
      INPUT_LOAD='(-0.01,0.01)';
      PINUSE='IN';
    'PERP12':
      PIN_NUMBER='(A57)';
      INPUT_LOAD='(-0.01,0.01)';
      PINUSE='IN';
    'GND_A58':
      PIN_NUMBER='(A58)';
      PINUSE='POWER';
      NO_LOAD_CHECK='Both';
      NO_IO_CHECK='Both';
      NO_ASSERT_CHECK='TRUE';
      NO_DIR_CHECK='TRUE';
      ALLOW_CONNECT='TRUE';
    'PERN13':
      PIN_NUMBER='(A59)';
      INPUT_LOAD='(-0.01,0.01)';
      PINUSE='IN';
    'PERP13':
      PIN_NUMBER='(A60)';
      INPUT_LOAD='(-0.01,0.01)';
      PINUSE='IN';
    'GND_A61':
      PIN_NUMBER='(A61)';
      PINUSE='POWER';
      NO_LOAD_CHECK='Both';
      NO_IO_CHECK='Both';
      NO_ASSERT_CHECK='TRUE';
      NO_DIR_CHECK='TRUE';
      ALLOW_CONNECT='TRUE';
    'PERN14':
      PIN_NUMBER='(A62)';
      INPUT_LOAD='(-0.01,0.01)';
      PINUSE='IN';
    'PERP14':
      PIN_NUMBER='(A63)';
      INPUT_LOAD='(-0.01,0.01)';
      PINUSE='IN';
    'GND_A64':
      PIN_NUMBER='(A64)';
      PINUSE='POWER';
      NO_LOAD_CHECK='Both';
      NO_IO_CHECK='Both';
      NO_ASSERT_CHECK='TRUE';
      NO_DIR_CHECK='TRUE';
      ALLOW_CONNECT='TRUE';
    'PERN15':
      PIN_NUMBER='(A65)';
      INPUT_LOAD='(-0.01,0.01)';
      PINUSE='IN';
    'PERP15':
      PIN_NUMBER='(A66)';
      INPUT_LOAD='(-0.01,0.01)';
      PINUSE='IN';
    'GND_A67':
      PIN_NUMBER='(A67)';
      PINUSE='POWER';
      NO_LOAD_CHECK='Both';
      NO_IO_CHECK='Both';
      NO_ASSERT_CHECK='TRUE';
      NO_DIR_CHECK='TRUE';
      ALLOW_CONNECT='TRUE';
    'USB_DATN':
      PIN_NUMBER='(A68)';
      BIDIRECTIONAL='TRUE';
      INPUT_LOAD='(-0.01,0.01)';
      OUTPUT_LOAD='(1.0,-1.0)';
      PINUSE='BI';
    'USB_DATP':
      PIN_NUMBER='(A69)';
      BIDIRECTIONAL='TRUE';
      INPUT_LOAD='(-0.01,0.01)';
      OUTPUT_LOAD='(1.0,-1.0)';
      PINUSE='BI';
    'PWRBRK0#':
      PIN_NUMBER='(A70)';
      BIDIRECTIONAL='TRUE';
      INPUT_LOAD='(-0.01,0.01)';
      OUTPUT_LOAD='(1.0,-1.0)';
      PINUSE='BI';
    'PETP12':
      PIN_NUMBER='(B57)';
      OUTPUT_LOAD='(1.0,-1.0)';
      PINUSE='OUT';
    'GND_B58':
      PIN_NUMBER='(B58)';
      PINUSE='POWER';
      NO_LOAD_CHECK='Both';
      NO_IO_CHECK='Both';
      NO_ASSERT_CHECK='TRUE';
      NO_DIR_CHECK='TRUE';
      ALLOW_CONNECT='TRUE';
    'PETN13':
      PIN_NUMBER='(B59)';
      OUTPUT_LOAD='(1.0,-1.0)';
      PINUSE='OUT';
    'PETP13':
      PIN_NUMBER='(B60)';
      OUTPUT_LOAD='(1.0,-1.0)';
      PINUSE='OUT';
    'GND_B61':
      PIN_NUMBER='(B61)';
      PINUSE='POWER';
      NO_LOAD_CHECK='Both';
      NO_IO_CHECK='Both';
      NO_ASSERT_CHECK='TRUE';
      NO_DIR_CHECK='TRUE';
      ALLOW_CONNECT='TRUE';
    'PETN14':
      PIN_NUMBER='(B62)';
      OUTPUT_LOAD='(1.0,-1.0)';
      PINUSE='OUT';
    'PETP14':
      PIN_NUMBER='(B63)';
      OUTPUT_LOAD='(1.0,-1.0)';
      PINUSE='OUT';
    'GND_B64':
      PIN_NUMBER='(B64)';
      PINUSE='POWER';
      NO_LOAD_CHECK='Both';
      NO_IO_CHECK='Both';
      NO_ASSERT_CHECK='TRUE';
      NO_DIR_CHECK='TRUE';
      ALLOW_CONNECT='TRUE';
    'PETN15':
      PIN_NUMBER='(B65)';
      OUTPUT_LOAD='(1.0,-1.0)';
      PINUSE='OUT';
    'PETP15':
      PIN_NUMBER='(B66)';
      OUTPUT_LOAD='(1.0,-1.0)';
      PINUSE='OUT';
    'GND_B67':
      PIN_NUMBER='(B67)';
      PINUSE='POWER';
      NO_LOAD_CHECK='Both';
      NO_IO_CHECK='Both';
      NO_ASSERT_CHECK='TRUE';
      NO_DIR_CHECK='TRUE';
      ALLOW_CONNECT='TRUE';
    'RFU1_NC_B68':
      PIN_NUMBER='(B68)';
      OUTPUT_TYPE='(TS,TS)';
      INPUT_LOAD='(-0.01,0.01)';
      OUTPUT_LOAD='(1.0,-1.0)';
      PINUSE='TRI';
    'RFU1_NC_B69':
      PIN_NUMBER='(B69)';
      OUTPUT_TYPE='(TS,TS)';
      INPUT_LOAD='(-0.01,0.01)';
      OUTPUT_LOAD='(1.0,-1.0)';
      PINUSE='TRI';
    'PRSNTB3#':
      PIN_NUMBER='(B70)';
      INPUT_LOAD='(-0.01,0.01)';
      PINUSE='IN';
    'G1':
      PIN_NUMBER='(G1)';
      PINUSE='POWER';
      NO_LOAD_CHECK='Both';
      NO_IO_CHECK='Both';
      NO_ASSERT_CHECK='TRUE';
      NO_DIR_CHECK='TRUE';
      ALLOW_CONNECT='TRUE';
    'G2':
      PIN_NUMBER='(G2)';
      PINUSE='POWER';
      NO_LOAD_CHECK='Both';
      NO_IO_CHECK='Both';
      NO_ASSERT_CHECK='TRUE';
      NO_DIR_CHECK='TRUE';
      ALLOW_CONNECT='TRUE';
    'G3':
      PIN_NUMBER='(G3)';
      PINUSE='POWER';
      NO_LOAD_CHECK='Both';
      NO_IO_CHECK='Both';
      NO_ASSERT_CHECK='TRUE';
      NO_DIR_CHECK='TRUE';
      ALLOW_CONNECT='TRUE';
    'G4':
      PIN_NUMBER='(G4)';
      PINUSE='POWER';
      NO_LOAD_CHECK='Both';
      NO_IO_CHECK='Both';
      NO_ASSERT_CHECK='TRUE';
      NO_DIR_CHECK='TRUE';
      ALLOW_CONNECT='TRUE';
    'G5':
      PIN_NUMBER='(G5)';
      PINUSE='POWER';
      NO_LOAD_CHECK='Both';
      NO_IO_CHECK='Both';
      NO_ASSERT_CHECK='TRUE';
      NO_DIR_CHECK='TRUE';
      ALLOW_CONNECT='TRUE';
  end_pin;
  body
      PART_NAME='SCONN168_ME1016810202011';
      BODY_NAME='SCONN168_ME1016810202011';
      PHYS_DES_PREFIX='J';
      CLASS='IO';
      NC_PINS='(H1,H2)';
      STANDARD='';
      LIFECYCLE='';
      JEDEC_TYPE='CON_F168S2H7D_P0-6W2-95_LUH';
      DESCRIPTION='CONN SMD HOUSING 168P 2R FR(P0.6,H5.35)';
      MANUFTR='APL';
      MANUF_PN='ME1016810202011';
      RD_CMPLS_LVL='EP(V1)';
      CMPLS_LVL='';
      DIP_SMD='';
      FROM_PJ='F0C-BELL';
      DATA='APL_ME1016810202011.pdf';
      FP_ECN='ME1016810202011.msg';
      EE_CHECK_LIST='';
      CREATOR='';
      CREATEDAY='20200615';
      PSL='';
      STATUS='';
      ESD_CDM='NA';
      ESD_HBM='NA';
      ESD_MM='NA';
      MSD='NA';
      PIN_LENGTH_LONG_PIN='56 MILS';
      PIN_LENGTH_SHORT_PIN='36 MILS';
      PARENT_PART_TYPE='SCONN168_ME1016810202011';
      PARENT_PPT='SCONN168_ME1016810202011';
      PARENT_PPT_PART='SCONN168_ME1016810202011-SCONN168_ME1016810202011,SMLF,IO,DFHSG8FR011';
  end_body;
end_primitive;
primitive 'SCONN20_513860200CV01-SCONN20_A';
  pin
    '1':
      PIN_NUMBER='(1)';
      BIDIRECTIONAL='TRUE';
      INPUT_LOAD='(-0.01,0.01)';
      OUTPUT_LOAD='(1.0,-1.0)';
      PINUSE='BI';
    '2':
      PIN_NUMBER='(2)';
      BIDIRECTIONAL='TRUE';
      INPUT_LOAD='(-0.01,0.01)';
      OUTPUT_LOAD='(1.0,-1.0)';
      PINUSE='BI';
    '3':
      PIN_NUMBER='(3)';
      BIDIRECTIONAL='TRUE';
      INPUT_LOAD='(-0.01,0.01)';
      OUTPUT_LOAD='(1.0,-1.0)';
      PINUSE='BI';
    '4':
      PIN_NUMBER='(4)';
      BIDIRECTIONAL='TRUE';
      INPUT_LOAD='(-0.01,0.01)';
      OUTPUT_LOAD='(1.0,-1.0)';
      PINUSE='BI';
    '5':
      PIN_NUMBER='(5)';
      BIDIRECTIONAL='TRUE';
      INPUT_LOAD='(-0.01,0.01)';
      OUTPUT_LOAD='(1.0,-1.0)';
      PINUSE='BI';
    '6':
      PIN_NUMBER='(6)';
      BIDIRECTIONAL='TRUE';
      INPUT_LOAD='(-0.01,0.01)';
      OUTPUT_LOAD='(1.0,-1.0)';
      PINUSE='BI';
    '7':
      PIN_NUMBER='(7)';
      BIDIRECTIONAL='TRUE';
      INPUT_LOAD='(-0.01,0.01)';
      OUTPUT_LOAD='(1.0,-1.0)';
      PINUSE='BI';
    '8':
      PIN_NUMBER='(8)';
      BIDIRECTIONAL='TRUE';
      INPUT_LOAD='(-0.01,0.01)';
      OUTPUT_LOAD='(1.0,-1.0)';
      PINUSE='BI';
    '9':
      PIN_NUMBER='(9)';
      BIDIRECTIONAL='TRUE';
      INPUT_LOAD='(-0.01,0.01)';
      OUTPUT_LOAD='(1.0,-1.0)';
      PINUSE='BI';
    '10':
      PIN_NUMBER='(10)';
      BIDIRECTIONAL='TRUE';
      INPUT_LOAD='(-0.01,0.01)';
      OUTPUT_LOAD='(1.0,-1.0)';
      PINUSE='BI';
    '11':
      PIN_NUMBER='(11)';
      BIDIRECTIONAL='TRUE';
      INPUT_LOAD='(-0.01,0.01)';
      OUTPUT_LOAD='(1.0,-1.0)';
      PINUSE='BI';
    '12':
      PIN_NUMBER='(12)';
      BIDIRECTIONAL='TRUE';
      INPUT_LOAD='(-0.01,0.01)';
      OUTPUT_LOAD='(1.0,-1.0)';
      PINUSE='BI';
    '13':
      PIN_NUMBER='(13)';
      BIDIRECTIONAL='TRUE';
      INPUT_LOAD='(-0.01,0.01)';
      OUTPUT_LOAD='(1.0,-1.0)';
      PINUSE='BI';
    '14':
      PIN_NUMBER='(14)';
      BIDIRECTIONAL='TRUE';
      INPUT_LOAD='(-0.01,0.01)';
      OUTPUT_LOAD='(1.0,-1.0)';
      PINUSE='BI';
    '15':
      PIN_NUMBER='(15)';
      BIDIRECTIONAL='TRUE';
      INPUT_LOAD='(-0.01,0.01)';
      OUTPUT_LOAD='(1.0,-1.0)';
      PINUSE='BI';
    '16':
      PIN_NUMBER='(16)';
      BIDIRECTIONAL='TRUE';
      INPUT_LOAD='(-0.01,0.01)';
      OUTPUT_LOAD='(1.0,-1.0)';
      PINUSE='BI';
    '17':
      PIN_NUMBER='(17)';
      BIDIRECTIONAL='TRUE';
      INPUT_LOAD='(-0.01,0.01)';
      OUTPUT_LOAD='(1.0,-1.0)';
      PINUSE='BI';
    '18':
      PIN_NUMBER='(18)';
      BIDIRECTIONAL='TRUE';
      INPUT_LOAD='(-0.01,0.01)';
      OUTPUT_LOAD='(1.0,-1.0)';
      PINUSE='BI';
    '19':
      PIN_NUMBER='(19)';
      BIDIRECTIONAL='TRUE';
      INPUT_LOAD='(-0.01,0.01)';
      OUTPUT_LOAD='(1.0,-1.0)';
      PINUSE='BI';
    '20':
      PIN_NUMBER='(20)';
      BIDIRECTIONAL='TRUE';
      INPUT_LOAD='(-0.01,0.01)';
      OUTPUT_LOAD='(1.0,-1.0)';
      PINUSE='BI';
  end_pin;
  body
      PART_NAME='SCONN20_513860200CV01';
      BODY_NAME='SCONN20_513860200CV01';
      PHYS_DES_PREFIX='J';
      CLASS='IO';
      NC_PINS='(H1,H2)';
      STANDARD='';
      LIFECYCLE='';
      JEDEC_TYPE='HEADER2X10SBHXB';
      DESCRIPTION='CONN SMD HEADER 20P 2R MS(P2,H6.4)';
      MANUFTR='ACS';
      MANUF_PN='51386-0200C-V01';
      RD_CMPLS_LVL='EP(V1)';
      CMPLS_LVL='EP(V1)';
      DIP_SMD='';
      FROM_PJ='L19-TH';
      DATA='ACS_51386-0200C-V01.pdf';
      FP_ECN='51386-0200C-V01.msg';
      EE_CHECK_LIST='';
      CREATOR='';
      CREATEDAY='20210702';
      PSL='';
      STATUS='';
      ESD_CDM='';
      ESD_HBM='';
      ESD_MM='';
      MSD='';
      PIN_LENGTH_LONG_PIN='38 MILS';
      PIN_LENGTH_SHORT_PIN='38 MILS';
      PARENT_PART_TYPE='SCONN20_513860200CV01';
      PARENT_PPT='SCONN20_513860200CV01';
      PARENT_PPT_PART='SCONN20_513860200CV01-SCONN20_51386-0200C-V01,SMLF,IO,DFHD20MS193';
  end_body;
end_primitive;
primitive 'SCONN21_9193031121LF-SCONN21_9A';
  pin
    '1':
      PIN_NUMBER='(1)';
      BIDIRECTIONAL='TRUE';
      INPUT_LOAD='(-0.01,0.01)';
      OUTPUT_LOAD='(1.0,-1.0)';
      PINUSE='BI';
    '3':
      PIN_NUMBER='(3)';
      BIDIRECTIONAL='TRUE';
      INPUT_LOAD='(-0.01,0.01)';
      OUTPUT_LOAD='(1.0,-1.0)';
      PINUSE='BI';
    '4':
      PIN_NUMBER='(4)';
      BIDIRECTIONAL='TRUE';
      INPUT_LOAD='(-0.01,0.01)';
      OUTPUT_LOAD='(1.0,-1.0)';
      PINUSE='BI';
    '5':
      PIN_NUMBER='(5)';
      BIDIRECTIONAL='TRUE';
      INPUT_LOAD='(-0.01,0.01)';
      OUTPUT_LOAD='(1.0,-1.0)';
      PINUSE='BI';
    '2':
      PIN_NUMBER='(2)';
      BIDIRECTIONAL='TRUE';
      INPUT_LOAD='(-0.01,0.01)';
      OUTPUT_LOAD='(1.0,-1.0)';
      PINUSE='BI';
    'G1':
      PIN_NUMBER='(G1)';
      PINUSE='POWER';
      NO_LOAD_CHECK='Both';
      NO_IO_CHECK='Both';
      NO_ASSERT_CHECK='TRUE';
      NO_DIR_CHECK='TRUE';
      ALLOW_CONNECT='TRUE';
    'G2':
      PIN_NUMBER='(G2)';
      PINUSE='POWER';
      NO_LOAD_CHECK='Both';
      NO_IO_CHECK='Both';
      NO_ASSERT_CHECK='TRUE';
      NO_DIR_CHECK='TRUE';
      ALLOW_CONNECT='TRUE';
    '6':
      PIN_NUMBER='(6)';
      BIDIRECTIONAL='TRUE';
      INPUT_LOAD='(-0.01,0.01)';
      OUTPUT_LOAD='(1.0,-1.0)';
      PINUSE='BI';
    '7':
      PIN_NUMBER='(7)';
      BIDIRECTIONAL='TRUE';
      INPUT_LOAD='(-0.01,0.01)';
      OUTPUT_LOAD='(1.0,-1.0)';
      PINUSE='BI';
    '8':
      PIN_NUMBER='(8)';
      BIDIRECTIONAL='TRUE';
      INPUT_LOAD='(-0.01,0.01)';
      OUTPUT_LOAD='(1.0,-1.0)';
      PINUSE='BI';
    '9':
      PIN_NUMBER='(9)';
      BIDIRECTIONAL='TRUE';
      INPUT_LOAD='(-0.01,0.01)';
      OUTPUT_LOAD='(1.0,-1.0)';
      PINUSE='BI';
    '10':
      PIN_NUMBER='(10)';
      BIDIRECTIONAL='TRUE';
      INPUT_LOAD='(-0.01,0.01)';
      OUTPUT_LOAD='(1.0,-1.0)';
      PINUSE='BI';
    '11':
      PIN_NUMBER='(11)';
      BIDIRECTIONAL='TRUE';
      INPUT_LOAD='(-0.01,0.01)';
      OUTPUT_LOAD='(1.0,-1.0)';
      PINUSE='BI';
    '12':
      PIN_NUMBER='(12)';
      BIDIRECTIONAL='TRUE';
      INPUT_LOAD='(-0.01,0.01)';
      OUTPUT_LOAD='(1.0,-1.0)';
      PINUSE='BI';
    '13':
      PIN_NUMBER='(13)';
      BIDIRECTIONAL='TRUE';
      INPUT_LOAD='(-0.01,0.01)';
      OUTPUT_LOAD='(1.0,-1.0)';
      PINUSE='BI';
    '14':
      PIN_NUMBER='(14)';
      BIDIRECTIONAL='TRUE';
      INPUT_LOAD='(-0.01,0.01)';
      OUTPUT_LOAD='(1.0,-1.0)';
      PINUSE='BI';
    '15':
      PIN_NUMBER='(15)';
      BIDIRECTIONAL='TRUE';
      INPUT_LOAD='(-0.01,0.01)';
      OUTPUT_LOAD='(1.0,-1.0)';
      PINUSE='BI';
    '16':
      PIN_NUMBER='(16)';
      BIDIRECTIONAL='TRUE';
      INPUT_LOAD='(-0.01,0.01)';
      OUTPUT_LOAD='(1.0,-1.0)';
      PINUSE='BI';
    '17':
      PIN_NUMBER='(17)';
      BIDIRECTIONAL='TRUE';
      INPUT_LOAD='(-0.01,0.01)';
      OUTPUT_LOAD='(1.0,-1.0)';
      PINUSE='BI';
    '18':
      PIN_NUMBER='(18)';
      BIDIRECTIONAL='TRUE';
      INPUT_LOAD='(-0.01,0.01)';
      OUTPUT_LOAD='(1.0,-1.0)';
      PINUSE='BI';
    '19':
      PIN_NUMBER='(19)';
      BIDIRECTIONAL='TRUE';
      INPUT_LOAD='(-0.01,0.01)';
      OUTPUT_LOAD='(1.0,-1.0)';
      PINUSE='BI';
    '20':
      PIN_NUMBER='(20)';
      BIDIRECTIONAL='TRUE';
      INPUT_LOAD='(-0.01,0.01)';
      OUTPUT_LOAD='(1.0,-1.0)';
      PINUSE='BI';
    '21':
      PIN_NUMBER='(21)';
      BIDIRECTIONAL='TRUE';
      INPUT_LOAD='(-0.01,0.01)';
      OUTPUT_LOAD='(1.0,-1.0)';
      PINUSE='BI';
  end_pin;
  body
      PART_NAME='SCONN21_9193031121LF';
      BODY_NAME='SCONN21_9193031121LF';
      PHYS_DES_PREFIX='J';
      CLASS='IO';
      NC_PINS='(H1,H2)';
      STANDARD='';
      LIFECYCLE='';
      JEDEC_TYPE='CON_F21S2H2D2S_P1W4-22_LDH';
      DESCRIPTION='CONN SMD HOUSING 21P 2R FS(P1,H3.28)';
      MANUFTR='APL';
      MANUF_PN='91930-31121LF';
      RD_CMPLS_LVL='EP(V1)';
      CMPLS_LVL='';
      DIP_SMD='';
      FROM_PJ='F0T-IVES';
      DATA='APL_91930-31121LF.pdf';
      FP_ECN='91930-31121LF.msg';
      EE_CHECK_LIST='';
      CREATOR='';
      CREATEDAY='20220421';
      PSL='';
      STATUS='';
      ESD_CDM='';
      ESD_HBM='';
      ESD_MM='';
      MSD='';
      PIN_LENGTH_LONG_PIN='20 MILS';
      PIN_LENGTH_SHORT_PIN='20 MILS';
      PARENT_PART_TYPE='SCONN21_9193031121LF';
      PARENT_PPT='SCONN21_9193031121LF';
      PARENT_PPT_PART='SCONN21_9193031121LF-SCONN21_91930-31121LF,SMLF,EMPTY,DFHS21FS003';
  end_body;
end_primitive;
primitive 'SCONN288_ADR50017P087CC-SCONN2A';
  pin
    'VIN_MGMT':
      PIN_NUMBER='(3,0,0)';
      PINUSE='POWER';
      NO_LOAD_CHECK='Both';
      NO_IO_CHECK='Both';
      NO_ASSERT_CHECK='TRUE';
      NO_DIR_CHECK='TRUE';
      ALLOW_CONNECT='TRUE';
    'RFU0':
      PIN_NUMBER='(2,0,0)';
      OUTPUT_TYPE='(TS,TS)';
      INPUT_LOAD='(-0.01,0.01)';
      OUTPUT_LOAD='(1.0,-1.0)';
      PINUSE='TRI';
    'RFU1':
      PIN_NUMBER='(144,0,0)';
      OUTPUT_TYPE='(TS,TS)';
      INPUT_LOAD='(-0.01,0.01)';
      OUTPUT_LOAD='(1.0,-1.0)';
      PINUSE='TRI';
    'RFU2':
      PIN_NUMBER='(149,0,0)';
      OUTPUT_TYPE='(TS,TS)';
      INPUT_LOAD='(-0.01,0.01)';
      OUTPUT_LOAD='(1.0,-1.0)';
      PINUSE='TRI';
    'RFU3':
      PIN_NUMBER='(150,0,0)';
      OUTPUT_TYPE='(TS,TS)';
      INPUT_LOAD='(-0.01,0.01)';
      OUTPUT_LOAD='(1.0,-1.0)';
      PINUSE='TRI';
    'RFU4':
      PIN_NUMBER='(220,0,0)';
      OUTPUT_TYPE='(TS,TS)';
      INPUT_LOAD='(-0.01,0.01)';
      OUTPUT_LOAD='(1.0,-1.0)';
      PINUSE='TRI';
    'RFU5':
      PIN_NUMBER='(231,0,0)';
      OUTPUT_TYPE='(TS,TS)';
      INPUT_LOAD='(-0.01,0.01)';
      OUTPUT_LOAD='(1.0,-1.0)';
      PINUSE='TRI';
    'RFU6':
      PIN_NUMBER='(232,0,0)';
      OUTPUT_TYPE='(TS,TS)';
      INPUT_LOAD='(-0.01,0.01)';
      OUTPUT_LOAD='(1.0,-1.0)';
      PINUSE='TRI';
    'RESET_N':
      PIN_NUMBER='(207,0,0)';
      INPUT_LOAD='(-0.01,0.01)';
      PINUSE='IN';
    'PWR_GOOD||FAIL_N':
      PIN_NUMBER='(147,0,0)';
      BIDIRECTIONAL='TRUE';
      INPUT_LOAD='(-0.01,0.01)';
      OUTPUT_LOAD='(1.0,-1.0)';
      PINUSE='BI';
    'PAR_B':
      PIN_NUMBER='(227,0,0)';
      INPUT_LOAD='(-0.01,0.01)';
      PINUSE='IN';
    'PAR_A':
      PIN_NUMBER='(74,0,0)';
      INPUT_LOAD='(-0.01,0.01)';
      PINUSE='IN';
    'LBS||RSP_B_N':
      PIN_NUMBER='(87,0,0)';
      OUTPUT_LOAD='(1.0,-1.0)';
      PINUSE='OUT';
    'LBD||RSP_A_N':
      PIN_NUMBER='(86,0,0)';
      OUTPUT_LOAD='(1.0,-1.0)';
      PINUSE='OUT';
    'HSDA':
      PIN_NUMBER='(5,0,0)';
      BIDIRECTIONAL='TRUE';
      INPUT_LOAD='(-0.01,0.01)';
      OUTPUT_LOAD='(1.0,-1.0)';
      PINUSE='BI';
    'HSCL':
      PIN_NUMBER='(4,0,0)';
      INPUT_LOAD='(-0.01,0.01)';
      PINUSE='IN';
    'HSA':
      PIN_NUMBER='(148,0,0)';
      INPUT_LOAD='(-0.01,0.01)';
      PINUSE='IN';
    'DQ0_B':
      PIN_NUMBER='(100,0,0)';
      BIDIRECTIONAL='TRUE';
      INPUT_LOAD='(-0.01,0.01)';
      OUTPUT_LOAD='(1.0,-1.0)';
      PINUSE='BI';
    'DQ1_B':
      PIN_NUMBER='(102,0,0)';
      BIDIRECTIONAL='TRUE';
      INPUT_LOAD='(-0.01,0.01)';
      OUTPUT_LOAD='(1.0,-1.0)';
      PINUSE='BI';
    'DQ2_B':
      PIN_NUMBER='(245,0,0)';
      BIDIRECTIONAL='TRUE';
      INPUT_LOAD='(-0.01,0.01)';
      OUTPUT_LOAD='(1.0,-1.0)';
      PINUSE='BI';
    'DQ3_B':
      PIN_NUMBER='(247,0,0)';
      BIDIRECTIONAL='TRUE';
      INPUT_LOAD='(-0.01,0.01)';
      OUTPUT_LOAD='(1.0,-1.0)';
      PINUSE='BI';
    'DQ4_B':
      PIN_NUMBER='(107,0,0)';
      BIDIRECTIONAL='TRUE';
      INPUT_LOAD='(-0.01,0.01)';
      OUTPUT_LOAD='(1.0,-1.0)';
      PINUSE='BI';
    'DQ5_B':
      PIN_NUMBER='(109,0,0)';
      BIDIRECTIONAL='TRUE';
      INPUT_LOAD='(-0.01,0.01)';
      OUTPUT_LOAD='(1.0,-1.0)';
      PINUSE='BI';
    'DQ6_B':
      PIN_NUMBER='(252,0,0)';
      BIDIRECTIONAL='TRUE';
      INPUT_LOAD='(-0.01,0.01)';
      OUTPUT_LOAD='(1.0,-1.0)';
      PINUSE='BI';
    'DQ7_B':
      PIN_NUMBER='(254,0,0)';
      BIDIRECTIONAL='TRUE';
      INPUT_LOAD='(-0.01,0.01)';
      OUTPUT_LOAD='(1.0,-1.0)';
      PINUSE='BI';
    'DQ8_B':
      PIN_NUMBER='(111,0,0)';
      BIDIRECTIONAL='TRUE';
      INPUT_LOAD='(-0.01,0.01)';
      OUTPUT_LOAD='(1.0,-1.0)';
      PINUSE='BI';
    'DQ9_B':
      PIN_NUMBER='(113,0,0)';
      BIDIRECTIONAL='TRUE';
      INPUT_LOAD='(-0.01,0.01)';
      OUTPUT_LOAD='(1.0,-1.0)';
      PINUSE='BI';
    'DQ10_B':
      PIN_NUMBER='(256,0,0)';
      BIDIRECTIONAL='TRUE';
      INPUT_LOAD='(-0.01,0.01)';
      OUTPUT_LOAD='(1.0,-1.0)';
      PINUSE='BI';
    'DQ11_B':
      PIN_NUMBER='(258,0,0)';
      BIDIRECTIONAL='TRUE';
      INPUT_LOAD='(-0.01,0.01)';
      OUTPUT_LOAD='(1.0,-1.0)';
      PINUSE='BI';
    'DQ12_B':
      PIN_NUMBER='(118,0,0)';
      BIDIRECTIONAL='TRUE';
      INPUT_LOAD='(-0.01,0.01)';
      OUTPUT_LOAD='(1.0,-1.0)';
      PINUSE='BI';
    'DQ13_B':
      PIN_NUMBER='(120,0,0)';
      BIDIRECTIONAL='TRUE';
      INPUT_LOAD='(-0.01,0.01)';
      OUTPUT_LOAD='(1.0,-1.0)';
      PINUSE='BI';
    'DQ14_B':
      PIN_NUMBER='(263,0,0)';
      BIDIRECTIONAL='TRUE';
      INPUT_LOAD='(-0.01,0.01)';
      OUTPUT_LOAD='(1.0,-1.0)';
      PINUSE='BI';
    'DQ15_B':
      PIN_NUMBER='(265,0,0)';
      BIDIRECTIONAL='TRUE';
      INPUT_LOAD='(-0.01,0.01)';
      OUTPUT_LOAD='(1.0,-1.0)';
      PINUSE='BI';
    'DQ16_B':
      PIN_NUMBER='(122,0,0)';
      BIDIRECTIONAL='TRUE';
      INPUT_LOAD='(-0.01,0.01)';
      OUTPUT_LOAD='(1.0,-1.0)';
      PINUSE='BI';
    'DQ17_B':
      PIN_NUMBER='(124,0,0)';
      BIDIRECTIONAL='TRUE';
      INPUT_LOAD='(-0.01,0.01)';
      OUTPUT_LOAD='(1.0,-1.0)';
      PINUSE='BI';
    'DQ18_B':
      PIN_NUMBER='(267,0,0)';
      BIDIRECTIONAL='TRUE';
      INPUT_LOAD='(-0.01,0.01)';
      OUTPUT_LOAD='(1.0,-1.0)';
      PINUSE='BI';
    'DQ19_B':
      PIN_NUMBER='(269,0,0)';
      BIDIRECTIONAL='TRUE';
      INPUT_LOAD='(-0.01,0.01)';
      OUTPUT_LOAD='(1.0,-1.0)';
      PINUSE='BI';
    'DQ20_B':
      PIN_NUMBER='(129,0,0)';
      BIDIRECTIONAL='TRUE';
      INPUT_LOAD='(-0.01,0.01)';
      OUTPUT_LOAD='(1.0,-1.0)';
      PINUSE='BI';
    'DQ21_B':
      PIN_NUMBER='(131,0,0)';
      BIDIRECTIONAL='TRUE';
      INPUT_LOAD='(-0.01,0.01)';
      OUTPUT_LOAD='(1.0,-1.0)';
      PINUSE='BI';
    'DQ22_B':
      PIN_NUMBER='(274,0,0)';
      BIDIRECTIONAL='TRUE';
      INPUT_LOAD='(-0.01,0.01)';
      OUTPUT_LOAD='(1.0,-1.0)';
      PINUSE='BI';
    'DQ23_B':
      PIN_NUMBER='(276,0,0)';
      BIDIRECTIONAL='TRUE';
      INPUT_LOAD='(-0.01,0.01)';
      OUTPUT_LOAD='(1.0,-1.0)';
      PINUSE='BI';
    'DQ24_B':
      PIN_NUMBER='(133,0,0)';
      BIDIRECTIONAL='TRUE';
      INPUT_LOAD='(-0.01,0.01)';
      OUTPUT_LOAD='(1.0,-1.0)';
      PINUSE='BI';
    'DQ25_B':
      PIN_NUMBER='(135,0,0)';
      BIDIRECTIONAL='TRUE';
      INPUT_LOAD='(-0.01,0.01)';
      OUTPUT_LOAD='(1.0,-1.0)';
      PINUSE='BI';
    'DQ26_B':
      PIN_NUMBER='(278,0,0)';
      BIDIRECTIONAL='TRUE';
      INPUT_LOAD='(-0.01,0.01)';
      OUTPUT_LOAD='(1.0,-1.0)';
      PINUSE='BI';
    'DQ27_B':
      PIN_NUMBER='(280,0,0)';
      BIDIRECTIONAL='TRUE';
      INPUT_LOAD='(-0.01,0.01)';
      OUTPUT_LOAD='(1.0,-1.0)';
      PINUSE='BI';
    'DQ28_B':
      PIN_NUMBER='(140,0,0)';
      BIDIRECTIONAL='TRUE';
      INPUT_LOAD='(-0.01,0.01)';
      OUTPUT_LOAD='(1.0,-1.0)';
      PINUSE='BI';
    'DQ29_B':
      PIN_NUMBER='(142,0,0)';
      BIDIRECTIONAL='TRUE';
      INPUT_LOAD='(-0.01,0.01)';
      OUTPUT_LOAD='(1.0,-1.0)';
      PINUSE='BI';
    'DQ30_B':
      PIN_NUMBER='(285,0,0)';
      BIDIRECTIONAL='TRUE';
      INPUT_LOAD='(-0.01,0.01)';
      OUTPUT_LOAD='(1.0,-1.0)';
      PINUSE='BI';
    'DQ31_B':
      PIN_NUMBER='(287,0,0)';
      BIDIRECTIONAL='TRUE';
      INPUT_LOAD='(-0.01,0.01)';
      OUTPUT_LOAD='(1.0,-1.0)';
      PINUSE='BI';
    'DQ0_A':
      PIN_NUMBER='(7,0,0)';
      BIDIRECTIONAL='TRUE';
      INPUT_LOAD='(-0.01,0.01)';
      OUTPUT_LOAD='(1.0,-1.0)';
      PINUSE='BI';
    'DQ1_A':
      PIN_NUMBER='(9,0,0)';
      BIDIRECTIONAL='TRUE';
      INPUT_LOAD='(-0.01,0.01)';
      OUTPUT_LOAD='(1.0,-1.0)';
      PINUSE='BI';
    'DQ2_A':
      PIN_NUMBER='(152,0,0)';
      BIDIRECTIONAL='TRUE';
      INPUT_LOAD='(-0.01,0.01)';
      OUTPUT_LOAD='(1.0,-1.0)';
      PINUSE='BI';
    'DQ3_A':
      PIN_NUMBER='(154,0,0)';
      BIDIRECTIONAL='TRUE';
      INPUT_LOAD='(-0.01,0.01)';
      OUTPUT_LOAD='(1.0,-1.0)';
      PINUSE='BI';
    'DQ4_A':
      PIN_NUMBER='(14,0,0)';
      BIDIRECTIONAL='TRUE';
      INPUT_LOAD='(-0.01,0.01)';
      OUTPUT_LOAD='(1.0,-1.0)';
      PINUSE='BI';
    'DQ5_A':
      PIN_NUMBER='(16,0,0)';
      BIDIRECTIONAL='TRUE';
      INPUT_LOAD='(-0.01,0.01)';
      OUTPUT_LOAD='(1.0,-1.0)';
      PINUSE='BI';
    'DQ6_A':
      PIN_NUMBER='(159,0,0)';
      BIDIRECTIONAL='TRUE';
      INPUT_LOAD='(-0.01,0.01)';
      OUTPUT_LOAD='(1.0,-1.0)';
      PINUSE='BI';
    'DQ7_A':
      PIN_NUMBER='(161,0,0)';
      BIDIRECTIONAL='TRUE';
      INPUT_LOAD='(-0.01,0.01)';
      OUTPUT_LOAD='(1.0,-1.0)';
      PINUSE='BI';
    'DQ8_A':
      PIN_NUMBER='(18,0,0)';
      BIDIRECTIONAL='TRUE';
      INPUT_LOAD='(-0.01,0.01)';
      OUTPUT_LOAD='(1.0,-1.0)';
      PINUSE='BI';
    'DQ9_A':
      PIN_NUMBER='(20,0,0)';
      BIDIRECTIONAL='TRUE';
      INPUT_LOAD='(-0.01,0.01)';
      OUTPUT_LOAD='(1.0,-1.0)';
      PINUSE='BI';
    'DQ10_A':
      PIN_NUMBER='(163,0,0)';
      BIDIRECTIONAL='TRUE';
      INPUT_LOAD='(-0.01,0.01)';
      OUTPUT_LOAD='(1.0,-1.0)';
      PINUSE='BI';
    'DQ11_A':
      PIN_NUMBER='(165,0,0)';
      BIDIRECTIONAL='TRUE';
      INPUT_LOAD='(-0.01,0.01)';
      OUTPUT_LOAD='(1.0,-1.0)';
      PINUSE='BI';
    'DQ12_A':
      PIN_NUMBER='(25,0,0)';
      BIDIRECTIONAL='TRUE';
      INPUT_LOAD='(-0.01,0.01)';
      OUTPUT_LOAD='(1.0,-1.0)';
      PINUSE='BI';
    'DQ13_A':
      PIN_NUMBER='(27,0,0)';
      BIDIRECTIONAL='TRUE';
      INPUT_LOAD='(-0.01,0.01)';
      OUTPUT_LOAD='(1.0,-1.0)';
      PINUSE='BI';
    'DQ14_A':
      PIN_NUMBER='(170,0,0)';
      BIDIRECTIONAL='TRUE';
      INPUT_LOAD='(-0.01,0.01)';
      OUTPUT_LOAD='(1.0,-1.0)';
      PINUSE='BI';
    'DQ15_A':
      PIN_NUMBER='(172,0,0)';
      BIDIRECTIONAL='TRUE';
      INPUT_LOAD='(-0.01,0.01)';
      OUTPUT_LOAD='(1.0,-1.0)';
      PINUSE='BI';
    'DQ16_A':
      PIN_NUMBER='(29,0,0)';
      BIDIRECTIONAL='TRUE';
      INPUT_LOAD='(-0.01,0.01)';
      OUTPUT_LOAD='(1.0,-1.0)';
      PINUSE='BI';
    'DQ17_A':
      PIN_NUMBER='(31,0,0)';
      BIDIRECTIONAL='TRUE';
      INPUT_LOAD='(-0.01,0.01)';
      OUTPUT_LOAD='(1.0,-1.0)';
      PINUSE='BI';
    'DQ18_A':
      PIN_NUMBER='(174,0,0)';
      BIDIRECTIONAL='TRUE';
      INPUT_LOAD='(-0.01,0.01)';
      OUTPUT_LOAD='(1.0,-1.0)';
      PINUSE='BI';
    'DQ19_A':
      PIN_NUMBER='(176,0,0)';
      BIDIRECTIONAL='TRUE';
      INPUT_LOAD='(-0.01,0.01)';
      OUTPUT_LOAD='(1.0,-1.0)';
      PINUSE='BI';
    'DQ20_A':
      PIN_NUMBER='(36,0,0)';
      BIDIRECTIONAL='TRUE';
      INPUT_LOAD='(-0.01,0.01)';
      OUTPUT_LOAD='(1.0,-1.0)';
      PINUSE='BI';
    'DQ21_A':
      PIN_NUMBER='(38,0,0)';
      BIDIRECTIONAL='TRUE';
      INPUT_LOAD='(-0.01,0.01)';
      OUTPUT_LOAD='(1.0,-1.0)';
      PINUSE='BI';
    'DQ22_A':
      PIN_NUMBER='(181,0,0)';
      BIDIRECTIONAL='TRUE';
      INPUT_LOAD='(-0.01,0.01)';
      OUTPUT_LOAD='(1.0,-1.0)';
      PINUSE='BI';
    'DQ23_A':
      PIN_NUMBER='(183,0,0)';
      BIDIRECTIONAL='TRUE';
      INPUT_LOAD='(-0.01,0.01)';
      OUTPUT_LOAD='(1.0,-1.0)';
      PINUSE='BI';
    'DQ24_A':
      PIN_NUMBER='(40,0,0)';
      BIDIRECTIONAL='TRUE';
      INPUT_LOAD='(-0.01,0.01)';
      OUTPUT_LOAD='(1.0,-1.0)';
      PINUSE='BI';
    'DQ25_A':
      PIN_NUMBER='(42,0,0)';
      BIDIRECTIONAL='TRUE';
      INPUT_LOAD='(-0.01,0.01)';
      OUTPUT_LOAD='(1.0,-1.0)';
      PINUSE='BI';
    'DQ26_A':
      PIN_NUMBER='(185,0,0)';
      BIDIRECTIONAL='TRUE';
      INPUT_LOAD='(-0.01,0.01)';
      OUTPUT_LOAD='(1.0,-1.0)';
      PINUSE='BI';
    'DQ27_A':
      PIN_NUMBER='(187,0,0)';
      BIDIRECTIONAL='TRUE';
      INPUT_LOAD='(-0.01,0.01)';
      OUTPUT_LOAD='(1.0,-1.0)';
      PINUSE='BI';
    'DQ28_A':
      PIN_NUMBER='(47,0,0)';
      BIDIRECTIONAL='TRUE';
      INPUT_LOAD='(-0.01,0.01)';
      OUTPUT_LOAD='(1.0,-1.0)';
      PINUSE='BI';
    'DQ29_A':
      PIN_NUMBER='(49,0,0)';
      BIDIRECTIONAL='TRUE';
      INPUT_LOAD='(-0.01,0.01)';
      OUTPUT_LOAD='(1.0,-1.0)';
      PINUSE='BI';
    'DQ30_A':
      PIN_NUMBER='(192,0,0)';
      BIDIRECTIONAL='TRUE';
      INPUT_LOAD='(-0.01,0.01)';
      OUTPUT_LOAD='(1.0,-1.0)';
      PINUSE='BI';
    'CS1_B_N':
      PIN_NUMBER='(229,0,0)';
      INPUT_LOAD='(-0.01,0.01)';
      PINUSE='IN';
    'CS1_A_N':
      PIN_NUMBER='(209,0,0)';
      INPUT_LOAD='(-0.01,0.01)';
      PINUSE='IN';
    'CS0_B_N':
      PIN_NUMBER='(84,0,0)';
      INPUT_LOAD='(-0.01,0.01)';
      PINUSE='IN';
    'CS0_A_N':
      PIN_NUMBER='(64,0,0)';
      INPUT_LOAD='(-0.01,0.01)';
      PINUSE='IN';
    'CK_T':
      PIN_NUMBER='(217,0,0)';
      INPUT_LOAD='(-0.01,0.01)';
      PINUSE='IN';
    'CK_C':
      PIN_NUMBER='(218,0,0)';
      INPUT_LOAD='(-0.01,0.01)';
      PINUSE='IN';
    'CB0_B':
      PIN_NUMBER='(96,0,0)';
      BIDIRECTIONAL='TRUE';
      INPUT_LOAD='(-0.01,0.01)';
      OUTPUT_LOAD='(1.0,-1.0)';
      PINUSE='BI';
    'CB1_B':
      PIN_NUMBER='(98,0,0)';
      BIDIRECTIONAL='TRUE';
      INPUT_LOAD='(-0.01,0.01)';
      OUTPUT_LOAD='(1.0,-1.0)';
      PINUSE='BI';
    'CB2_B':
      PIN_NUMBER='(241,0,0)';
      BIDIRECTIONAL='TRUE';
      INPUT_LOAD='(-0.01,0.01)';
      OUTPUT_LOAD='(1.0,-1.0)';
      PINUSE='BI';
    'CB3_B':
      PIN_NUMBER='(243,0,0)';
      BIDIRECTIONAL='TRUE';
      INPUT_LOAD='(-0.01,0.01)';
      OUTPUT_LOAD='(1.0,-1.0)';
      PINUSE='BI';
    'CB4_B':
      PIN_NUMBER='(89,0,0)';
      BIDIRECTIONAL='TRUE';
      INPUT_LOAD='(-0.01,0.01)';
      OUTPUT_LOAD='(1.0,-1.0)';
      PINUSE='BI';
    'CB5_B':
      PIN_NUMBER='(91,0,0)';
      BIDIRECTIONAL='TRUE';
      INPUT_LOAD='(-0.01,0.01)';
      OUTPUT_LOAD='(1.0,-1.0)';
      PINUSE='BI';
    'CB6_B':
      PIN_NUMBER='(234,0,0)';
      BIDIRECTIONAL='TRUE';
      INPUT_LOAD='(-0.01,0.01)';
      OUTPUT_LOAD='(1.0,-1.0)';
      PINUSE='BI';
    'CB0_A':
      PIN_NUMBER='(51,0,0)';
      BIDIRECTIONAL='TRUE';
      INPUT_LOAD='(-0.01,0.01)';
      OUTPUT_LOAD='(1.0,-1.0)';
      PINUSE='BI';
    'CB2_A':
      PIN_NUMBER='(196,0,0)';
      BIDIRECTIONAL='TRUE';
      INPUT_LOAD='(-0.01,0.01)';
      OUTPUT_LOAD='(1.0,-1.0)';
      PINUSE='BI';
    'CB3_A':
      PIN_NUMBER='(198,0,0)';
      BIDIRECTIONAL='TRUE';
      INPUT_LOAD='(-0.01,0.01)';
      OUTPUT_LOAD='(1.0,-1.0)';
      PINUSE='BI';
    'CB5_A':
      PIN_NUMBER='(60,0,0)';
      BIDIRECTIONAL='TRUE';
      INPUT_LOAD='(-0.01,0.01)';
      OUTPUT_LOAD='(1.0,-1.0)';
      PINUSE='BI';
    'CB6_A':
      PIN_NUMBER='(203,0,0)';
      BIDIRECTIONAL='TRUE';
      INPUT_LOAD='(-0.01,0.01)';
      OUTPUT_LOAD='(1.0,-1.0)';
      PINUSE='BI';
    'CA6_B':
      PIN_NUMBER='(82,0,0)';
      INPUT_LOAD='(-0.01,0.01)';
      PINUSE='IN';
    'CA6_A':
      PIN_NUMBER='(72,0,0)';
      INPUT_LOAD='(-0.01,0.01)';
      PINUSE='IN';
    'CA5_B':
      PIN_NUMBER='(225,0,0)';
      INPUT_LOAD='(-0.01,0.01)';
      PINUSE='IN';
    'CA5_A':
      PIN_NUMBER='(215,0,0)';
      INPUT_LOAD='(-0.01,0.01)';
      PINUSE='IN';
    'CA4_B':
      PIN_NUMBER='(80,0,0)';
      INPUT_LOAD='(-0.01,0.01)';
      PINUSE='IN';
    'CA4_A':
      PIN_NUMBER='(70,0,0)';
      INPUT_LOAD='(-0.01,0.01)';
      PINUSE='IN';
    'CA3_B':
      PIN_NUMBER='(223,0,0)';
      INPUT_LOAD='(-0.01,0.01)';
      PINUSE='IN';
    'CA3_A':
      PIN_NUMBER='(213,0,0)';
      INPUT_LOAD='(-0.01,0.01)';
      PINUSE='IN';
    'CA2_B':
      PIN_NUMBER='(78,0,0)';
      INPUT_LOAD='(-0.01,0.01)';
      PINUSE='IN';
    'CA2_A':
      PIN_NUMBER='(68,0,0)';
      INPUT_LOAD='(-0.01,0.01)';
      PINUSE='IN';
    'CA1_B':
      PIN_NUMBER='(221,0,0)';
      INPUT_LOAD='(-0.01,0.01)';
      PINUSE='IN';
    'CA1_A':
      PIN_NUMBER='(211,0,0)';
      INPUT_LOAD='(-0.01,0.01)';
      PINUSE='IN';
    'CA0_B':
      PIN_NUMBER='(76,0,0)';
      INPUT_LOAD='(-0.01,0.01)';
      PINUSE='IN';
    'CA0_A':
      PIN_NUMBER='(66,0,0)';
      INPUT_LOAD='(-0.01,0.01)';
      PINUSE='IN';
    'ALERT_N':
      PIN_NUMBER='(62,0,0)';
      OUTPUT_LOAD='(1.0,-1.0)';
      PINUSE='OUT';
    'CB7_B':
      PIN_NUMBER='(236,0,0)';
      BIDIRECTIONAL='TRUE';
      INPUT_LOAD='(-0.01,0.01)';
      OUTPUT_LOAD='(1.0,-1.0)';
      PINUSE='BI';
    'CB1_A':
      PIN_NUMBER='(53,0,0)';
      BIDIRECTIONAL='TRUE';
      INPUT_LOAD='(-0.01,0.01)';
      OUTPUT_LOAD='(1.0,-1.0)';
      PINUSE='BI';
    'CB4_A':
      PIN_NUMBER='(58,0,0)';
      BIDIRECTIONAL='TRUE';
      INPUT_LOAD='(-0.01,0.01)';
      OUTPUT_LOAD='(1.0,-1.0)';
      PINUSE='BI';
    'CB7_A':
      PIN_NUMBER='(205,0,0)';
      BIDIRECTIONAL='TRUE';
      INPUT_LOAD='(-0.01,0.01)';
      OUTPUT_LOAD='(1.0,-1.0)';
      PINUSE='BI';
    'DQ31_A':
      PIN_NUMBER='(194,0,0)';
      BIDIRECTIONAL='TRUE';
      INPUT_LOAD='(-0.01,0.01)';
      OUTPUT_LOAD='(1.0,-1.0)';
      PINUSE='BI';
    'DQS9_B_T||TDQS9_B_T||DBI4_B_N':
      PIN_NUMBER='(0,93,0)';
      BIDIRECTIONAL='TRUE';
      INPUT_LOAD='(-0.01,0.01)';
      OUTPUT_LOAD='(1.0,-1.0)';
      PINUSE='BI';
    'DQS9_B_C||TDQS9_B_C':
      PIN_NUMBER='(0,94,0)';
      BIDIRECTIONAL='TRUE';
      INPUT_LOAD='(-0.01,0.01)';
      OUTPUT_LOAD='(1.0,-1.0)';
      PINUSE='BI';
    'DQS9_A_T||TDQS9_A_T':
      PIN_NUMBER='(0,201,0)';
      BIDIRECTIONAL='TRUE';
      INPUT_LOAD='(-0.01,0.01)';
      OUTPUT_LOAD='(1.0,-1.0)';
      PINUSE='BI';
    'DQS9_A_C||TDQS9_A_C':
      PIN_NUMBER='(0,200,0)';
      BIDIRECTIONAL='TRUE';
      INPUT_LOAD='(-0.01,0.01)';
      OUTPUT_LOAD='(1.0,-1.0)';
      PINUSE='BI';
    'DQS8_A_T||TDQS8_A_T':
      PIN_NUMBER='(0,190,0)';
      BIDIRECTIONAL='TRUE';
      INPUT_LOAD='(-0.01,0.01)';
      OUTPUT_LOAD='(1.0,-1.0)';
      PINUSE='BI';
    'DQS8_A_C||TDQS8_A_C':
      PIN_NUMBER='(0,189,0)';
      BIDIRECTIONAL='TRUE';
      INPUT_LOAD='(-0.01,0.01)';
      OUTPUT_LOAD='(1.0,-1.0)';
      PINUSE='BI';
    'DQS7_B_C||TDQS7_B_C':
      PIN_NUMBER='(0,271,0)';
      BIDIRECTIONAL='TRUE';
      INPUT_LOAD='(-0.01,0.01)';
      OUTPUT_LOAD='(1.0,-1.0)';
      PINUSE='BI';
    'DQS7_A_T||TDQS7_A_T':
      PIN_NUMBER='(0,179,0)';
      BIDIRECTIONAL='TRUE';
      INPUT_LOAD='(-0.01,0.01)';
      OUTPUT_LOAD='(1.0,-1.0)';
      PINUSE='BI';
    'DQS6_B_T||TDQS6_B_T':
      PIN_NUMBER='(0,261,0)';
      BIDIRECTIONAL='TRUE';
      INPUT_LOAD='(-0.01,0.01)';
      OUTPUT_LOAD='(1.0,-1.0)';
      PINUSE='BI';
    'DQS6_B_C||TDQS6_B_C':
      PIN_NUMBER='(0,260,0)';
      BIDIRECTIONAL='TRUE';
      INPUT_LOAD='(-0.01,0.01)';
      OUTPUT_LOAD='(1.0,-1.0)';
      PINUSE='BI';
    'DQS6_A_C||TDQS6_A_C||DQS6_A_T||TDQS6_A_T':
      PIN_NUMBER='(0,167,0)';
      BIDIRECTIONAL='TRUE';
      INPUT_LOAD='(-0.01,0.01)';
      OUTPUT_LOAD='(1.0,-1.0)';
      PINUSE='BI';
    'DQS5_B_T||TDQS5_B_T':
      PIN_NUMBER='(0,250,0)';
      BIDIRECTIONAL='TRUE';
      INPUT_LOAD='(-0.01,0.01)';
      OUTPUT_LOAD='(1.0,-1.0)';
      PINUSE='BI';
    'DQS5_B_C||TDQS5_B_C':
      PIN_NUMBER='(0,249,0)';
      BIDIRECTIONAL='TRUE';
      INPUT_LOAD='(-0.01,0.01)';
      OUTPUT_LOAD='(1.0,-1.0)';
      PINUSE='BI';
    'DQS5_A_T||TDQS5_A_T':
      PIN_NUMBER='(0,157,0)';
      BIDIRECTIONAL='TRUE';
      INPUT_LOAD='(-0.01,0.01)';
      OUTPUT_LOAD='(1.0,-1.0)';
      PINUSE='BI';
    'DQS5_A_C||TDQS5_A_C||DQS5_A_T||TDQS5_A_T':
      PIN_NUMBER='(0,156,0)';
      BIDIRECTIONAL='TRUE';
      INPUT_LOAD='(-0.01,0.01)';
      OUTPUT_LOAD='(1.0,-1.0)';
      PINUSE='BI';
    'DQS4_B_T':
      PIN_NUMBER='(0,239,0)';
      BIDIRECTIONAL='TRUE';
      INPUT_LOAD='(-0.01,0.01)';
      OUTPUT_LOAD='(1.0,-1.0)';
      PINUSE='BI';
    'DQS4_B_C':
      PIN_NUMBER='(0,238,0)';
      BIDIRECTIONAL='TRUE';
      INPUT_LOAD='(-0.01,0.01)';
      OUTPUT_LOAD='(1.0,-1.0)';
      PINUSE='BI';
    'DQS4_A_T':
      PIN_NUMBER='(0,55,0)';
      BIDIRECTIONAL='TRUE';
      INPUT_LOAD='(-0.01,0.01)';
      OUTPUT_LOAD='(1.0,-1.0)';
      PINUSE='BI';
    'DQS4_A_C':
      PIN_NUMBER='(0,56,0)';
      BIDIRECTIONAL='TRUE';
      INPUT_LOAD='(-0.01,0.01)';
      OUTPUT_LOAD='(1.0,-1.0)';
      PINUSE='BI';
    'DQS3_B_T':
      PIN_NUMBER='(0,137,0)';
      BIDIRECTIONAL='TRUE';
      INPUT_LOAD='(-0.01,0.01)';
      OUTPUT_LOAD='(1.0,-1.0)';
      PINUSE='BI';
    'DQS3_B_C':
      PIN_NUMBER='(0,138,0)';
      BIDIRECTIONAL='TRUE';
      INPUT_LOAD='(-0.01,0.01)';
      OUTPUT_LOAD='(1.0,-1.0)';
      PINUSE='BI';
    'DQS3_A_T':
      PIN_NUMBER='(0,44,0)';
      BIDIRECTIONAL='TRUE';
      INPUT_LOAD='(-0.01,0.01)';
      OUTPUT_LOAD='(1.0,-1.0)';
      PINUSE='BI';
    'DQS3_A_C':
      PIN_NUMBER='(0,45,0)';
      BIDIRECTIONAL='TRUE';
      INPUT_LOAD='(-0.01,0.01)';
      OUTPUT_LOAD='(1.0,-1.0)';
      PINUSE='BI';
    'DQS2_B_T':
      PIN_NUMBER='(0,126,0)';
      BIDIRECTIONAL='TRUE';
      INPUT_LOAD='(-0.01,0.01)';
      OUTPUT_LOAD='(1.0,-1.0)';
      PINUSE='BI';
    'DQS2_B_C':
      PIN_NUMBER='(0,127,0)';
      BIDIRECTIONAL='TRUE';
      INPUT_LOAD='(-0.01,0.01)';
      OUTPUT_LOAD='(1.0,-1.0)';
      PINUSE='BI';
    'DQS2_A_T':
      PIN_NUMBER='(0,33,0)';
      BIDIRECTIONAL='TRUE';
      INPUT_LOAD='(-0.01,0.01)';
      OUTPUT_LOAD='(1.0,-1.0)';
      PINUSE='BI';
    'DQS2_A_C':
      PIN_NUMBER='(0,34,0)';
      BIDIRECTIONAL='TRUE';
      INPUT_LOAD='(-0.01,0.01)';
      OUTPUT_LOAD='(1.0,-1.0)';
      PINUSE='BI';
    'DQS1_B_T':
      PIN_NUMBER='(0,115,0)';
      BIDIRECTIONAL='TRUE';
      INPUT_LOAD='(-0.01,0.01)';
      OUTPUT_LOAD='(1.0,-1.0)';
      PINUSE='BI';
    'DQS1_B_C':
      PIN_NUMBER='(0,116,0)';
      BIDIRECTIONAL='TRUE';
      INPUT_LOAD='(-0.01,0.01)';
      OUTPUT_LOAD='(1.0,-1.0)';
      PINUSE='BI';
    'DQS1_A_T':
      PIN_NUMBER='(0,22,0)';
      BIDIRECTIONAL='TRUE';
      INPUT_LOAD='(-0.01,0.01)';
      OUTPUT_LOAD='(1.0,-1.0)';
      PINUSE='BI';
    'DQS1_A_C':
      PIN_NUMBER='(0,23,0)';
      BIDIRECTIONAL='TRUE';
      INPUT_LOAD='(-0.01,0.01)';
      OUTPUT_LOAD='(1.0,-1.0)';
      PINUSE='BI';
    'DQS0_B_T':
      PIN_NUMBER='(0,104,0)';
      BIDIRECTIONAL='TRUE';
      INPUT_LOAD='(-0.01,0.01)';
      OUTPUT_LOAD='(1.0,-1.0)';
      PINUSE='BI';
    'DQS0_B_C':
      PIN_NUMBER='(0,105,0)';
      BIDIRECTIONAL='TRUE';
      INPUT_LOAD='(-0.01,0.01)';
      OUTPUT_LOAD='(1.0,-1.0)';
      PINUSE='BI';
    'DQS0_A_T':
      PIN_NUMBER='(0,11,0)';
      BIDIRECTIONAL='TRUE';
      INPUT_LOAD='(-0.01,0.01)';
      OUTPUT_LOAD='(1.0,-1.0)';
      PINUSE='BI';
    'DQS0_A_C':
      PIN_NUMBER='(0,12,0)';
      BIDIRECTIONAL='TRUE';
      INPUT_LOAD='(-0.01,0.01)';
      OUTPUT_LOAD='(1.0,-1.0)';
      PINUSE='BI';
    'DQS7_B_T||TDQS7_B_T':
      PIN_NUMBER='(0,272,0)';
      BIDIRECTIONAL='TRUE';
      INPUT_LOAD='(-0.01,0.01)';
      OUTPUT_LOAD='(1.0,-1.0)';
      PINUSE='BI';
    'DQS8_B_C||TDQS8_B_C':
      PIN_NUMBER='(0,282,0)';
      BIDIRECTIONAL='TRUE';
      INPUT_LOAD='(-0.01,0.01)';
      OUTPUT_LOAD='(1.0,-1.0)';
      PINUSE='BI';
    'DQS8_B_T||TDQS8_B_T':
      PIN_NUMBER='(0,283,0)';
      BIDIRECTIONAL='TRUE';
      INPUT_LOAD='(-0.01,0.01)';
      OUTPUT_LOAD='(1.0,-1.0)';
      PINUSE='BI';
    'DQS6_A_T||TDQS6_A_T':
      PIN_NUMBER='(0,168,0)';
      BIDIRECTIONAL='TRUE';
      INPUT_LOAD='(-0.01,0.01)';
      OUTPUT_LOAD='(1.0,-1.0)';
      PINUSE='BI';
    'DQS7_A_C||TDQS7_A_C':
      PIN_NUMBER='(0,178,0)';
      BIDIRECTIONAL='TRUE';
      INPUT_LOAD='(-0.01,0.01)';
      OUTPUT_LOAD='(1.0,-1.0)';
      PINUSE='BI';
    'VSS0':
      PIN_NUMBER='(0,0,6)';
      PINUSE='POWER';
      NO_LOAD_CHECK='Both';
      NO_IO_CHECK='Both';
      NO_ASSERT_CHECK='TRUE';
      NO_DIR_CHECK='TRUE';
      ALLOW_CONNECT='TRUE';
    'VSS1':
      PIN_NUMBER='(0,0,8)';
      PINUSE='POWER';
      NO_LOAD_CHECK='Both';
      NO_IO_CHECK='Both';
      NO_ASSERT_CHECK='TRUE';
      NO_DIR_CHECK='TRUE';
      ALLOW_CONNECT='TRUE';
    'VSS2':
      PIN_NUMBER='(0,0,10)';
      PINUSE='POWER';
      NO_LOAD_CHECK='Both';
      NO_IO_CHECK='Both';
      NO_ASSERT_CHECK='TRUE';
      NO_DIR_CHECK='TRUE';
      ALLOW_CONNECT='TRUE';
    'VSS3':
      PIN_NUMBER='(0,0,13)';
      PINUSE='POWER';
      NO_LOAD_CHECK='Both';
      NO_IO_CHECK='Both';
      NO_ASSERT_CHECK='TRUE';
      NO_DIR_CHECK='TRUE';
      ALLOW_CONNECT='TRUE';
    'VSS4':
      PIN_NUMBER='(0,0,15)';
      PINUSE='POWER';
      NO_LOAD_CHECK='Both';
      NO_IO_CHECK='Both';
      NO_ASSERT_CHECK='TRUE';
      NO_DIR_CHECK='TRUE';
      ALLOW_CONNECT='TRUE';
    'VSS5':
      PIN_NUMBER='(0,0,17)';
      PINUSE='POWER';
      NO_LOAD_CHECK='Both';
      NO_IO_CHECK='Both';
      NO_ASSERT_CHECK='TRUE';
      NO_DIR_CHECK='TRUE';
      ALLOW_CONNECT='TRUE';
    'VSS6':
      PIN_NUMBER='(0,0,19)';
      PINUSE='POWER';
      NO_LOAD_CHECK='Both';
      NO_IO_CHECK='Both';
      NO_ASSERT_CHECK='TRUE';
      NO_DIR_CHECK='TRUE';
      ALLOW_CONNECT='TRUE';
    'VSS7':
      PIN_NUMBER='(0,0,21)';
      PINUSE='POWER';
      NO_LOAD_CHECK='Both';
      NO_IO_CHECK='Both';
      NO_ASSERT_CHECK='TRUE';
      NO_DIR_CHECK='TRUE';
      ALLOW_CONNECT='TRUE';
    'VSS8':
      PIN_NUMBER='(0,0,24)';
      PINUSE='POWER';
      NO_LOAD_CHECK='Both';
      NO_IO_CHECK='Both';
      NO_ASSERT_CHECK='TRUE';
      NO_DIR_CHECK='TRUE';
      ALLOW_CONNECT='TRUE';
    'VSS9':
      PIN_NUMBER='(0,0,26)';
      PINUSE='POWER';
      NO_LOAD_CHECK='Both';
      NO_IO_CHECK='Both';
      NO_ASSERT_CHECK='TRUE';
      NO_DIR_CHECK='TRUE';
      ALLOW_CONNECT='TRUE';
    'VSS10':
      PIN_NUMBER='(0,0,28)';
      PINUSE='POWER';
      NO_LOAD_CHECK='Both';
      NO_IO_CHECK='Both';
      NO_ASSERT_CHECK='TRUE';
      NO_DIR_CHECK='TRUE';
      ALLOW_CONNECT='TRUE';
    'VSS11':
      PIN_NUMBER='(0,0,30)';
      PINUSE='POWER';
      NO_LOAD_CHECK='Both';
      NO_IO_CHECK='Both';
      NO_ASSERT_CHECK='TRUE';
      NO_DIR_CHECK='TRUE';
      ALLOW_CONNECT='TRUE';
    'VSS12':
      PIN_NUMBER='(0,0,32)';
      PINUSE='POWER';
      NO_LOAD_CHECK='Both';
      NO_IO_CHECK='Both';
      NO_ASSERT_CHECK='TRUE';
      NO_DIR_CHECK='TRUE';
      ALLOW_CONNECT='TRUE';
    'VSS13':
      PIN_NUMBER='(0,0,35)';
      PINUSE='POWER';
      NO_LOAD_CHECK='Both';
      NO_IO_CHECK='Both';
      NO_ASSERT_CHECK='TRUE';
      NO_DIR_CHECK='TRUE';
      ALLOW_CONNECT='TRUE';
    'VSS14':
      PIN_NUMBER='(0,0,37)';
      PINUSE='POWER';
      NO_LOAD_CHECK='Both';
      NO_IO_CHECK='Both';
      NO_ASSERT_CHECK='TRUE';
      NO_DIR_CHECK='TRUE';
      ALLOW_CONNECT='TRUE';
    'VSS15':
      PIN_NUMBER='(0,0,39)';
      PINUSE='POWER';
      NO_LOAD_CHECK='Both';
      NO_IO_CHECK='Both';
      NO_ASSERT_CHECK='TRUE';
      NO_DIR_CHECK='TRUE';
      ALLOW_CONNECT='TRUE';
    'VSS16':
      PIN_NUMBER='(0,0,41)';
      PINUSE='POWER';
      NO_LOAD_CHECK='Both';
      NO_IO_CHECK='Both';
      NO_ASSERT_CHECK='TRUE';
      NO_DIR_CHECK='TRUE';
      ALLOW_CONNECT='TRUE';
    'VSS17':
      PIN_NUMBER='(0,0,43)';
      PINUSE='POWER';
      NO_LOAD_CHECK='Both';
      NO_IO_CHECK='Both';
      NO_ASSERT_CHECK='TRUE';
      NO_DIR_CHECK='TRUE';
      ALLOW_CONNECT='TRUE';
    'VSS18':
      PIN_NUMBER='(0,0,46)';
      PINUSE='POWER';
      NO_LOAD_CHECK='Both';
      NO_IO_CHECK='Both';
      NO_ASSERT_CHECK='TRUE';
      NO_DIR_CHECK='TRUE';
      ALLOW_CONNECT='TRUE';
    'VSS19':
      PIN_NUMBER='(0,0,48)';
      PINUSE='POWER';
      NO_LOAD_CHECK='Both';
      NO_IO_CHECK='Both';
      NO_ASSERT_CHECK='TRUE';
      NO_DIR_CHECK='TRUE';
      ALLOW_CONNECT='TRUE';
    'VSS20':
      PIN_NUMBER='(0,0,50)';
      PINUSE='POWER';
      NO_LOAD_CHECK='Both';
      NO_IO_CHECK='Both';
      NO_ASSERT_CHECK='TRUE';
      NO_DIR_CHECK='TRUE';
      ALLOW_CONNECT='TRUE';
    'VSS21':
      PIN_NUMBER='(0,0,52)';
      PINUSE='POWER';
      NO_LOAD_CHECK='Both';
      NO_IO_CHECK='Both';
      NO_ASSERT_CHECK='TRUE';
      NO_DIR_CHECK='TRUE';
      ALLOW_CONNECT='TRUE';
    'VSS22':
      PIN_NUMBER='(0,0,54)';
      PINUSE='POWER';
      NO_LOAD_CHECK='Both';
      NO_IO_CHECK='Both';
      NO_ASSERT_CHECK='TRUE';
      NO_DIR_CHECK='TRUE';
      ALLOW_CONNECT='TRUE';
    'VSS23':
      PIN_NUMBER='(0,0,57)';
      PINUSE='POWER';
      NO_LOAD_CHECK='Both';
      NO_IO_CHECK='Both';
      NO_ASSERT_CHECK='TRUE';
      NO_DIR_CHECK='TRUE';
      ALLOW_CONNECT='TRUE';
    'VSS24':
      PIN_NUMBER='(0,0,59)';
      PINUSE='POWER';
      NO_LOAD_CHECK='Both';
      NO_IO_CHECK='Both';
      NO_ASSERT_CHECK='TRUE';
      NO_DIR_CHECK='TRUE';
      ALLOW_CONNECT='TRUE';
    'VSS25':
      PIN_NUMBER='(0,0,61)';
      PINUSE='POWER';
      NO_LOAD_CHECK='Both';
      NO_IO_CHECK='Both';
      NO_ASSERT_CHECK='TRUE';
      NO_DIR_CHECK='TRUE';
      ALLOW_CONNECT='TRUE';
    'VSS26':
      PIN_NUMBER='(0,0,63)';
      PINUSE='POWER';
      NO_LOAD_CHECK='Both';
      NO_IO_CHECK='Both';
      NO_ASSERT_CHECK='TRUE';
      NO_DIR_CHECK='TRUE';
      ALLOW_CONNECT='TRUE';
    'VSS27':
      PIN_NUMBER='(0,0,65)';
      PINUSE='POWER';
      NO_LOAD_CHECK='Both';
      NO_IO_CHECK='Both';
      NO_ASSERT_CHECK='TRUE';
      NO_DIR_CHECK='TRUE';
      ALLOW_CONNECT='TRUE';
    'VSS28':
      PIN_NUMBER='(0,0,67)';
      PINUSE='POWER';
      NO_LOAD_CHECK='Both';
      NO_IO_CHECK='Both';
      NO_ASSERT_CHECK='TRUE';
      NO_DIR_CHECK='TRUE';
      ALLOW_CONNECT='TRUE';
    'VSS29':
      PIN_NUMBER='(0,0,69)';
      PINUSE='POWER';
      NO_LOAD_CHECK='Both';
      NO_IO_CHECK='Both';
      NO_ASSERT_CHECK='TRUE';
      NO_DIR_CHECK='TRUE';
      ALLOW_CONNECT='TRUE';
    'VSS30':
      PIN_NUMBER='(0,0,71)';
      PINUSE='POWER';
      NO_LOAD_CHECK='Both';
      NO_IO_CHECK='Both';
      NO_ASSERT_CHECK='TRUE';
      NO_DIR_CHECK='TRUE';
      ALLOW_CONNECT='TRUE';
    'VSS31':
      PIN_NUMBER='(0,0,73)';
      PINUSE='POWER';
      NO_LOAD_CHECK='Both';
      NO_IO_CHECK='Both';
      NO_ASSERT_CHECK='TRUE';
      NO_DIR_CHECK='TRUE';
      ALLOW_CONNECT='TRUE';
    'VSS32':
      PIN_NUMBER='(0,0,75)';
      PINUSE='POWER';
      NO_LOAD_CHECK='Both';
      NO_IO_CHECK='Both';
      NO_ASSERT_CHECK='TRUE';
      NO_DIR_CHECK='TRUE';
      ALLOW_CONNECT='TRUE';
    'VSS33':
      PIN_NUMBER='(0,0,77)';
      PINUSE='POWER';
      NO_LOAD_CHECK='Both';
      NO_IO_CHECK='Both';
      NO_ASSERT_CHECK='TRUE';
      NO_DIR_CHECK='TRUE';
      ALLOW_CONNECT='TRUE';
    'VSS34':
      PIN_NUMBER='(0,0,79)';
      PINUSE='POWER';
      NO_LOAD_CHECK='Both';
      NO_IO_CHECK='Both';
      NO_ASSERT_CHECK='TRUE';
      NO_DIR_CHECK='TRUE';
      ALLOW_CONNECT='TRUE';
    'VSS35':
      PIN_NUMBER='(0,0,81)';
      PINUSE='POWER';
      NO_LOAD_CHECK='Both';
      NO_IO_CHECK='Both';
      NO_ASSERT_CHECK='TRUE';
      NO_DIR_CHECK='TRUE';
      ALLOW_CONNECT='TRUE';
    'VSS36':
      PIN_NUMBER='(0,0,83)';
      PINUSE='POWER';
      NO_LOAD_CHECK='Both';
      NO_IO_CHECK='Both';
      NO_ASSERT_CHECK='TRUE';
      NO_DIR_CHECK='TRUE';
      ALLOW_CONNECT='TRUE';
    'VSS37':
      PIN_NUMBER='(0,0,85)';
      PINUSE='POWER';
      NO_LOAD_CHECK='Both';
      NO_IO_CHECK='Both';
      NO_ASSERT_CHECK='TRUE';
      NO_DIR_CHECK='TRUE';
      ALLOW_CONNECT='TRUE';
    'VSS38':
      PIN_NUMBER='(0,0,88)';
      PINUSE='POWER';
      NO_LOAD_CHECK='Both';
      NO_IO_CHECK='Both';
      NO_ASSERT_CHECK='TRUE';
      NO_DIR_CHECK='TRUE';
      ALLOW_CONNECT='TRUE';
    'VSS39':
      PIN_NUMBER='(0,0,90)';
      PINUSE='POWER';
      NO_LOAD_CHECK='Both';
      NO_IO_CHECK='Both';
      NO_ASSERT_CHECK='TRUE';
      NO_DIR_CHECK='TRUE';
      ALLOW_CONNECT='TRUE';
    'VSS40':
      PIN_NUMBER='(0,0,92)';
      PINUSE='POWER';
      NO_LOAD_CHECK='Both';
      NO_IO_CHECK='Both';
      NO_ASSERT_CHECK='TRUE';
      NO_DIR_CHECK='TRUE';
      ALLOW_CONNECT='TRUE';
    'VSS41':
      PIN_NUMBER='(0,0,95)';
      PINUSE='POWER';
      NO_LOAD_CHECK='Both';
      NO_IO_CHECK='Both';
      NO_ASSERT_CHECK='TRUE';
      NO_DIR_CHECK='TRUE';
      ALLOW_CONNECT='TRUE';
    'VSS42':
      PIN_NUMBER='(0,0,97)';
      PINUSE='POWER';
      NO_LOAD_CHECK='Both';
      NO_IO_CHECK='Both';
      NO_ASSERT_CHECK='TRUE';
      NO_DIR_CHECK='TRUE';
      ALLOW_CONNECT='TRUE';
    'VSS43':
      PIN_NUMBER='(0,0,99)';
      PINUSE='POWER';
      NO_LOAD_CHECK='Both';
      NO_IO_CHECK='Both';
      NO_ASSERT_CHECK='TRUE';
      NO_DIR_CHECK='TRUE';
      ALLOW_CONNECT='TRUE';
    'VSS44':
      PIN_NUMBER='(0,0,101)';
      PINUSE='POWER';
      NO_LOAD_CHECK='Both';
      NO_IO_CHECK='Both';
      NO_ASSERT_CHECK='TRUE';
      NO_DIR_CHECK='TRUE';
      ALLOW_CONNECT='TRUE';
    'VSS45':
      PIN_NUMBER='(0,0,103)';
      PINUSE='POWER';
      NO_LOAD_CHECK='Both';
      NO_IO_CHECK='Both';
      NO_ASSERT_CHECK='TRUE';
      NO_DIR_CHECK='TRUE';
      ALLOW_CONNECT='TRUE';
    'VSS46':
      PIN_NUMBER='(0,0,106)';
      PINUSE='POWER';
      NO_LOAD_CHECK='Both';
      NO_IO_CHECK='Both';
      NO_ASSERT_CHECK='TRUE';
      NO_DIR_CHECK='TRUE';
      ALLOW_CONNECT='TRUE';
    'VSS47':
      PIN_NUMBER='(0,0,108)';
      PINUSE='POWER';
      NO_LOAD_CHECK='Both';
      NO_IO_CHECK='Both';
      NO_ASSERT_CHECK='TRUE';
      NO_DIR_CHECK='TRUE';
      ALLOW_CONNECT='TRUE';
    'VSS48':
      PIN_NUMBER='(0,0,110)';
      PINUSE='POWER';
      NO_LOAD_CHECK='Both';
      NO_IO_CHECK='Both';
      NO_ASSERT_CHECK='TRUE';
      NO_DIR_CHECK='TRUE';
      ALLOW_CONNECT='TRUE';
    'VSS49':
      PIN_NUMBER='(0,0,112)';
      PINUSE='POWER';
      NO_LOAD_CHECK='Both';
      NO_IO_CHECK='Both';
      NO_ASSERT_CHECK='TRUE';
      NO_DIR_CHECK='TRUE';
      ALLOW_CONNECT='TRUE';
    'VSS50':
      PIN_NUMBER='(0,0,114)';
      PINUSE='POWER';
      NO_LOAD_CHECK='Both';
      NO_IO_CHECK='Both';
      NO_ASSERT_CHECK='TRUE';
      NO_DIR_CHECK='TRUE';
      ALLOW_CONNECT='TRUE';
    'VSS51':
      PIN_NUMBER='(0,0,117)';
      PINUSE='POWER';
      NO_LOAD_CHECK='Both';
      NO_IO_CHECK='Both';
      NO_ASSERT_CHECK='TRUE';
      NO_DIR_CHECK='TRUE';
      ALLOW_CONNECT='TRUE';
    'VSS52':
      PIN_NUMBER='(0,0,119)';
      PINUSE='POWER';
      NO_LOAD_CHECK='Both';
      NO_IO_CHECK='Both';
      NO_ASSERT_CHECK='TRUE';
      NO_DIR_CHECK='TRUE';
      ALLOW_CONNECT='TRUE';
    'VSS53':
      PIN_NUMBER='(0,0,121)';
      PINUSE='POWER';
      NO_LOAD_CHECK='Both';
      NO_IO_CHECK='Both';
      NO_ASSERT_CHECK='TRUE';
      NO_DIR_CHECK='TRUE';
      ALLOW_CONNECT='TRUE';
    'VSS54':
      PIN_NUMBER='(0,0,123)';
      PINUSE='POWER';
      NO_LOAD_CHECK='Both';
      NO_IO_CHECK='Both';
      NO_ASSERT_CHECK='TRUE';
      NO_DIR_CHECK='TRUE';
      ALLOW_CONNECT='TRUE';
    'VSS55':
      PIN_NUMBER='(0,0,125)';
      PINUSE='POWER';
      NO_LOAD_CHECK='Both';
      NO_IO_CHECK='Both';
      NO_ASSERT_CHECK='TRUE';
      NO_DIR_CHECK='TRUE';
      ALLOW_CONNECT='TRUE';
    'VSS56':
      PIN_NUMBER='(0,0,128)';
      PINUSE='POWER';
      NO_LOAD_CHECK='Both';
      NO_IO_CHECK='Both';
      NO_ASSERT_CHECK='TRUE';
      NO_DIR_CHECK='TRUE';
      ALLOW_CONNECT='TRUE';
    'VSS57':
      PIN_NUMBER='(0,0,130)';
      PINUSE='POWER';
      NO_LOAD_CHECK='Both';
      NO_IO_CHECK='Both';
      NO_ASSERT_CHECK='TRUE';
      NO_DIR_CHECK='TRUE';
      ALLOW_CONNECT='TRUE';
    'VSS59':
      PIN_NUMBER='(0,0,134)';
      PINUSE='POWER';
      NO_LOAD_CHECK='Both';
      NO_IO_CHECK='Both';
      NO_ASSERT_CHECK='TRUE';
      NO_DIR_CHECK='TRUE';
      ALLOW_CONNECT='TRUE';
    'VSS63':
      PIN_NUMBER='(0,0,143)';
      PINUSE='POWER';
      NO_LOAD_CHECK='Both';
      NO_IO_CHECK='Both';
      NO_ASSERT_CHECK='TRUE';
      NO_DIR_CHECK='TRUE';
      ALLOW_CONNECT='TRUE';
    'VSS64':
      PIN_NUMBER='(0,0,151)';
      PINUSE='POWER';
      NO_LOAD_CHECK='Both';
      NO_IO_CHECK='Both';
      NO_ASSERT_CHECK='TRUE';
      NO_DIR_CHECK='TRUE';
      ALLOW_CONNECT='TRUE';
    'VSS65':
      PIN_NUMBER='(0,0,153)';
      PINUSE='POWER';
      NO_LOAD_CHECK='Both';
      NO_IO_CHECK='Both';
      NO_ASSERT_CHECK='TRUE';
      NO_DIR_CHECK='TRUE';
      ALLOW_CONNECT='TRUE';
    'VSS66':
      PIN_NUMBER='(0,0,155)';
      PINUSE='POWER';
      NO_LOAD_CHECK='Both';
      NO_IO_CHECK='Both';
      NO_ASSERT_CHECK='TRUE';
      NO_DIR_CHECK='TRUE';
      ALLOW_CONNECT='TRUE';
    'VSS67':
      PIN_NUMBER='(0,0,158)';
      PINUSE='POWER';
      NO_LOAD_CHECK='Both';
      NO_IO_CHECK='Both';
      NO_ASSERT_CHECK='TRUE';
      NO_DIR_CHECK='TRUE';
      ALLOW_CONNECT='TRUE';
    'VSS68':
      PIN_NUMBER='(0,0,160)';
      PINUSE='POWER';
      NO_LOAD_CHECK='Both';
      NO_IO_CHECK='Both';
      NO_ASSERT_CHECK='TRUE';
      NO_DIR_CHECK='TRUE';
      ALLOW_CONNECT='TRUE';
    'VSS69':
      PIN_NUMBER='(0,0,162)';
      PINUSE='POWER';
      NO_LOAD_CHECK='Both';
      NO_IO_CHECK='Both';
      NO_ASSERT_CHECK='TRUE';
      NO_DIR_CHECK='TRUE';
      ALLOW_CONNECT='TRUE';
    'VSS70':
      PIN_NUMBER='(0,0,164)';
      PINUSE='POWER';
      NO_LOAD_CHECK='Both';
      NO_IO_CHECK='Both';
      NO_ASSERT_CHECK='TRUE';
      NO_DIR_CHECK='TRUE';
      ALLOW_CONNECT='TRUE';
    'VSS71':
      PIN_NUMBER='(0,0,166)';
      PINUSE='POWER';
      NO_LOAD_CHECK='Both';
      NO_IO_CHECK='Both';
      NO_ASSERT_CHECK='TRUE';
      NO_DIR_CHECK='TRUE';
      ALLOW_CONNECT='TRUE';
    'VSS72':
      PIN_NUMBER='(0,0,169)';
      PINUSE='POWER';
      NO_LOAD_CHECK='Both';
      NO_IO_CHECK='Both';
      NO_ASSERT_CHECK='TRUE';
      NO_DIR_CHECK='TRUE';
      ALLOW_CONNECT='TRUE';
    'VSS73':
      PIN_NUMBER='(0,0,171)';
      PINUSE='POWER';
      NO_LOAD_CHECK='Both';
      NO_IO_CHECK='Both';
      NO_ASSERT_CHECK='TRUE';
      NO_DIR_CHECK='TRUE';
      ALLOW_CONNECT='TRUE';
    'VSS74':
      PIN_NUMBER='(0,0,173)';
      PINUSE='POWER';
      NO_LOAD_CHECK='Both';
      NO_IO_CHECK='Both';
      NO_ASSERT_CHECK='TRUE';
      NO_DIR_CHECK='TRUE';
      ALLOW_CONNECT='TRUE';
    'VSS75':
      PIN_NUMBER='(0,0,175)';
      PINUSE='POWER';
      NO_LOAD_CHECK='Both';
      NO_IO_CHECK='Both';
      NO_ASSERT_CHECK='TRUE';
      NO_DIR_CHECK='TRUE';
      ALLOW_CONNECT='TRUE';
    'VSS76':
      PIN_NUMBER='(0,0,177)';
      PINUSE='POWER';
      NO_LOAD_CHECK='Both';
      NO_IO_CHECK='Both';
      NO_ASSERT_CHECK='TRUE';
      NO_DIR_CHECK='TRUE';
      ALLOW_CONNECT='TRUE';
    'VSS77':
      PIN_NUMBER='(0,0,180)';
      PINUSE='POWER';
      NO_LOAD_CHECK='Both';
      NO_IO_CHECK='Both';
      NO_ASSERT_CHECK='TRUE';
      NO_DIR_CHECK='TRUE';
      ALLOW_CONNECT='TRUE';
    'VSS78':
      PIN_NUMBER='(0,0,182)';
      PINUSE='POWER';
      NO_LOAD_CHECK='Both';
      NO_IO_CHECK='Both';
      NO_ASSERT_CHECK='TRUE';
      NO_DIR_CHECK='TRUE';
      ALLOW_CONNECT='TRUE';
    'VSS79':
      PIN_NUMBER='(0,0,184)';
      PINUSE='POWER';
      NO_LOAD_CHECK='Both';
      NO_IO_CHECK='Both';
      NO_ASSERT_CHECK='TRUE';
      NO_DIR_CHECK='TRUE';
      ALLOW_CONNECT='TRUE';
    'VSS80':
      PIN_NUMBER='(0,0,186)';
      PINUSE='POWER';
      NO_LOAD_CHECK='Both';
      NO_IO_CHECK='Both';
      NO_ASSERT_CHECK='TRUE';
      NO_DIR_CHECK='TRUE';
      ALLOW_CONNECT='TRUE';
    'VSS81':
      PIN_NUMBER='(0,0,188)';
      PINUSE='POWER';
      NO_LOAD_CHECK='Both';
      NO_IO_CHECK='Both';
      NO_ASSERT_CHECK='TRUE';
      NO_DIR_CHECK='TRUE';
      ALLOW_CONNECT='TRUE';
    'VSS82':
      PIN_NUMBER='(0,0,191)';
      PINUSE='POWER';
      NO_LOAD_CHECK='Both';
      NO_IO_CHECK='Both';
      NO_ASSERT_CHECK='TRUE';
      NO_DIR_CHECK='TRUE';
      ALLOW_CONNECT='TRUE';
    'VSS83':
      PIN_NUMBER='(0,0,193)';
      PINUSE='POWER';
      NO_LOAD_CHECK='Both';
      NO_IO_CHECK='Both';
      NO_ASSERT_CHECK='TRUE';
      NO_DIR_CHECK='TRUE';
      ALLOW_CONNECT='TRUE';
    'VSS84':
      PIN_NUMBER='(0,0,195)';
      PINUSE='POWER';
      NO_LOAD_CHECK='Both';
      NO_IO_CHECK='Both';
      NO_ASSERT_CHECK='TRUE';
      NO_DIR_CHECK='TRUE';
      ALLOW_CONNECT='TRUE';
    'VSS85':
      PIN_NUMBER='(0,0,197)';
      PINUSE='POWER';
      NO_LOAD_CHECK='Both';
      NO_IO_CHECK='Both';
      NO_ASSERT_CHECK='TRUE';
      NO_DIR_CHECK='TRUE';
      ALLOW_CONNECT='TRUE';
    'VSS86':
      PIN_NUMBER='(0,0,199)';
      PINUSE='POWER';
      NO_LOAD_CHECK='Both';
      NO_IO_CHECK='Both';
      NO_ASSERT_CHECK='TRUE';
      NO_DIR_CHECK='TRUE';
      ALLOW_CONNECT='TRUE';
    'VSS87':
      PIN_NUMBER='(0,0,202)';
      PINUSE='POWER';
      NO_LOAD_CHECK='Both';
      NO_IO_CHECK='Both';
      NO_ASSERT_CHECK='TRUE';
      NO_DIR_CHECK='TRUE';
      ALLOW_CONNECT='TRUE';
    'VSS88':
      PIN_NUMBER='(0,0,204)';
      PINUSE='POWER';
      NO_LOAD_CHECK='Both';
      NO_IO_CHECK='Both';
      NO_ASSERT_CHECK='TRUE';
      NO_DIR_CHECK='TRUE';
      ALLOW_CONNECT='TRUE';
    'VSS89':
      PIN_NUMBER='(0,0,206)';
      PINUSE='POWER';
      NO_LOAD_CHECK='Both';
      NO_IO_CHECK='Both';
      NO_ASSERT_CHECK='TRUE';
      NO_DIR_CHECK='TRUE';
      ALLOW_CONNECT='TRUE';
    'VSS90':
      PIN_NUMBER='(0,0,208)';
      PINUSE='POWER';
      NO_LOAD_CHECK='Both';
      NO_IO_CHECK='Both';
      NO_ASSERT_CHECK='TRUE';
      NO_DIR_CHECK='TRUE';
      ALLOW_CONNECT='TRUE';
    'VSS91':
      PIN_NUMBER='(0,0,210)';
      PINUSE='POWER';
      NO_LOAD_CHECK='Both';
      NO_IO_CHECK='Both';
      NO_ASSERT_CHECK='TRUE';
      NO_DIR_CHECK='TRUE';
      ALLOW_CONNECT='TRUE';
    'VSS92':
      PIN_NUMBER='(0,0,212)';
      PINUSE='POWER';
      NO_LOAD_CHECK='Both';
      NO_IO_CHECK='Both';
      NO_ASSERT_CHECK='TRUE';
      NO_DIR_CHECK='TRUE';
      ALLOW_CONNECT='TRUE';
    'VSS93':
      PIN_NUMBER='(0,0,214)';
      PINUSE='POWER';
      NO_LOAD_CHECK='Both';
      NO_IO_CHECK='Both';
      NO_ASSERT_CHECK='TRUE';
      NO_DIR_CHECK='TRUE';
      ALLOW_CONNECT='TRUE';
    'VSS94':
      PIN_NUMBER='(0,0,216)';
      PINUSE='POWER';
      NO_LOAD_CHECK='Both';
      NO_IO_CHECK='Both';
      NO_ASSERT_CHECK='TRUE';
      NO_DIR_CHECK='TRUE';
      ALLOW_CONNECT='TRUE';
    'VSS95':
      PIN_NUMBER='(0,0,219)';
      PINUSE='POWER';
      NO_LOAD_CHECK='Both';
      NO_IO_CHECK='Both';
      NO_ASSERT_CHECK='TRUE';
      NO_DIR_CHECK='TRUE';
      ALLOW_CONNECT='TRUE';
    'VSS96':
      PIN_NUMBER='(0,0,222)';
      PINUSE='POWER';
      NO_LOAD_CHECK='Both';
      NO_IO_CHECK='Both';
      NO_ASSERT_CHECK='TRUE';
      NO_DIR_CHECK='TRUE';
      ALLOW_CONNECT='TRUE';
    'VSS97':
      PIN_NUMBER='(0,0,224)';
      PINUSE='POWER';
      NO_LOAD_CHECK='Both';
      NO_IO_CHECK='Both';
      NO_ASSERT_CHECK='TRUE';
      NO_DIR_CHECK='TRUE';
      ALLOW_CONNECT='TRUE';
    'VSS98':
      PIN_NUMBER='(0,0,226)';
      PINUSE='POWER';
      NO_LOAD_CHECK='Both';
      NO_IO_CHECK='Both';
      NO_ASSERT_CHECK='TRUE';
      NO_DIR_CHECK='TRUE';
      ALLOW_CONNECT='TRUE';
    'VSS99':
      PIN_NUMBER='(0,0,228)';
      PINUSE='POWER';
      NO_LOAD_CHECK='Both';
      NO_IO_CHECK='Both';
      NO_ASSERT_CHECK='TRUE';
      NO_DIR_CHECK='TRUE';
      ALLOW_CONNECT='TRUE';
    'VSS101':
      PIN_NUMBER='(0,0,233)';
      PINUSE='POWER';
      NO_LOAD_CHECK='Both';
      NO_IO_CHECK='Both';
      NO_ASSERT_CHECK='TRUE';
      NO_DIR_CHECK='TRUE';
      ALLOW_CONNECT='TRUE';
    'VSS103':
      PIN_NUMBER='(0,0,237)';
      PINUSE='POWER';
      NO_LOAD_CHECK='Both';
      NO_IO_CHECK='Both';
      NO_ASSERT_CHECK='TRUE';
      NO_DIR_CHECK='TRUE';
      ALLOW_CONNECT='TRUE';
    'VSS105':
      PIN_NUMBER='(0,0,242)';
      PINUSE='POWER';
      NO_LOAD_CHECK='Both';
      NO_IO_CHECK='Both';
      NO_ASSERT_CHECK='TRUE';
      NO_DIR_CHECK='TRUE';
      ALLOW_CONNECT='TRUE';
    'VSS106':
      PIN_NUMBER='(0,0,244)';
      PINUSE='POWER';
      NO_LOAD_CHECK='Both';
      NO_IO_CHECK='Both';
      NO_ASSERT_CHECK='TRUE';
      NO_DIR_CHECK='TRUE';
      ALLOW_CONNECT='TRUE';
    'VSS107':
      PIN_NUMBER='(0,0,246)';
      PINUSE='POWER';
      NO_LOAD_CHECK='Both';
      NO_IO_CHECK='Both';
      NO_ASSERT_CHECK='TRUE';
      NO_DIR_CHECK='TRUE';
      ALLOW_CONNECT='TRUE';
    'VSS108':
      PIN_NUMBER='(0,0,248)';
      PINUSE='POWER';
      NO_LOAD_CHECK='Both';
      NO_IO_CHECK='Both';
      NO_ASSERT_CHECK='TRUE';
      NO_DIR_CHECK='TRUE';
      ALLOW_CONNECT='TRUE';
    'VSS109':
      PIN_NUMBER='(0,0,251)';
      PINUSE='POWER';
      NO_LOAD_CHECK='Both';
      NO_IO_CHECK='Both';
      NO_ASSERT_CHECK='TRUE';
      NO_DIR_CHECK='TRUE';
      ALLOW_CONNECT='TRUE';
    'VSS110':
      PIN_NUMBER='(0,0,253)';
      PINUSE='POWER';
      NO_LOAD_CHECK='Both';
      NO_IO_CHECK='Both';
      NO_ASSERT_CHECK='TRUE';
      NO_DIR_CHECK='TRUE';
      ALLOW_CONNECT='TRUE';
    'VSS111':
      PIN_NUMBER='(0,0,255)';
      PINUSE='POWER';
      NO_LOAD_CHECK='Both';
      NO_IO_CHECK='Both';
      NO_ASSERT_CHECK='TRUE';
      NO_DIR_CHECK='TRUE';
      ALLOW_CONNECT='TRUE';
    'VSS112':
      PIN_NUMBER='(0,0,257)';
      PINUSE='POWER';
      NO_LOAD_CHECK='Both';
      NO_IO_CHECK='Both';
      NO_ASSERT_CHECK='TRUE';
      NO_DIR_CHECK='TRUE';
      ALLOW_CONNECT='TRUE';
    'VSS113':
      PIN_NUMBER='(0,0,259)';
      PINUSE='POWER';
      NO_LOAD_CHECK='Both';
      NO_IO_CHECK='Both';
      NO_ASSERT_CHECK='TRUE';
      NO_DIR_CHECK='TRUE';
      ALLOW_CONNECT='TRUE';
    'VSS114':
      PIN_NUMBER='(0,0,262)';
      PINUSE='POWER';
      NO_LOAD_CHECK='Both';
      NO_IO_CHECK='Both';
      NO_ASSERT_CHECK='TRUE';
      NO_DIR_CHECK='TRUE';
      ALLOW_CONNECT='TRUE';
    'VSS115':
      PIN_NUMBER='(0,0,264)';
      PINUSE='POWER';
      NO_LOAD_CHECK='Both';
      NO_IO_CHECK='Both';
      NO_ASSERT_CHECK='TRUE';
      NO_DIR_CHECK='TRUE';
      ALLOW_CONNECT='TRUE';
    'VSS116':
      PIN_NUMBER='(0,0,266)';
      PINUSE='POWER';
      NO_LOAD_CHECK='Both';
      NO_IO_CHECK='Both';
      NO_ASSERT_CHECK='TRUE';
      NO_DIR_CHECK='TRUE';
      ALLOW_CONNECT='TRUE';
    'VSS117':
      PIN_NUMBER='(0,0,268)';
      PINUSE='POWER';
      NO_LOAD_CHECK='Both';
      NO_IO_CHECK='Both';
      NO_ASSERT_CHECK='TRUE';
      NO_DIR_CHECK='TRUE';
      ALLOW_CONNECT='TRUE';
    'VSS118':
      PIN_NUMBER='(0,0,270)';
      PINUSE='POWER';
      NO_LOAD_CHECK='Both';
      NO_IO_CHECK='Both';
      NO_ASSERT_CHECK='TRUE';
      NO_DIR_CHECK='TRUE';
      ALLOW_CONNECT='TRUE';
    'VSS119':
      PIN_NUMBER='(0,0,273)';
      PINUSE='POWER';
      NO_LOAD_CHECK='Both';
      NO_IO_CHECK='Both';
      NO_ASSERT_CHECK='TRUE';
      NO_DIR_CHECK='TRUE';
      ALLOW_CONNECT='TRUE';
    'VSS120':
      PIN_NUMBER='(0,0,275)';
      PINUSE='POWER';
      NO_LOAD_CHECK='Both';
      NO_IO_CHECK='Both';
      NO_ASSERT_CHECK='TRUE';
      NO_DIR_CHECK='TRUE';
      ALLOW_CONNECT='TRUE';
    'VSS121':
      PIN_NUMBER='(0,0,277)';
      PINUSE='POWER';
      NO_LOAD_CHECK='Both';
      NO_IO_CHECK='Both';
      NO_ASSERT_CHECK='TRUE';
      NO_DIR_CHECK='TRUE';
      ALLOW_CONNECT='TRUE';
    'VSS122':
      PIN_NUMBER='(0,0,279)';
      PINUSE='POWER';
      NO_LOAD_CHECK='Both';
      NO_IO_CHECK='Both';
      NO_ASSERT_CHECK='TRUE';
      NO_DIR_CHECK='TRUE';
      ALLOW_CONNECT='TRUE';
    'VSS123':
      PIN_NUMBER='(0,0,281)';
      PINUSE='POWER';
      NO_LOAD_CHECK='Both';
      NO_IO_CHECK='Both';
      NO_ASSERT_CHECK='TRUE';
      NO_DIR_CHECK='TRUE';
      ALLOW_CONNECT='TRUE';
    'VSS124':
      PIN_NUMBER='(0,0,284)';
      PINUSE='POWER';
      NO_LOAD_CHECK='Both';
      NO_IO_CHECK='Both';
      NO_ASSERT_CHECK='TRUE';
      NO_DIR_CHECK='TRUE';
      ALLOW_CONNECT='TRUE';
    'VSS125':
      PIN_NUMBER='(0,0,286)';
      PINUSE='POWER';
      NO_LOAD_CHECK='Both';
      NO_IO_CHECK='Both';
      NO_ASSERT_CHECK='TRUE';
      NO_DIR_CHECK='TRUE';
      ALLOW_CONNECT='TRUE';
    'VSS126':
      PIN_NUMBER='(0,0,288)';
      PINUSE='POWER';
      NO_LOAD_CHECK='Both';
      NO_IO_CHECK='Both';
      NO_ASSERT_CHECK='TRUE';
      NO_DIR_CHECK='TRUE';
      ALLOW_CONNECT='TRUE';
    'VIN_BULK0':
      PIN_NUMBER='(0,0,1)';
      PINUSE='POWER';
      NO_LOAD_CHECK='Both';
      NO_IO_CHECK='Both';
      NO_ASSERT_CHECK='TRUE';
      NO_DIR_CHECK='TRUE';
      ALLOW_CONNECT='TRUE';
    'VIN_BULK1':
      PIN_NUMBER='(0,0,145)';
      PINUSE='POWER';
      NO_LOAD_CHECK='Both';
      NO_IO_CHECK='Both';
      NO_ASSERT_CHECK='TRUE';
      NO_DIR_CHECK='TRUE';
      ALLOW_CONNECT='TRUE';
    'VIN_BULK2':
      PIN_NUMBER='(0,0,146)';
      PINUSE='POWER';
      NO_LOAD_CHECK='Both';
      NO_IO_CHECK='Both';
      NO_ASSERT_CHECK='TRUE';
      NO_DIR_CHECK='TRUE';
      ALLOW_CONNECT='TRUE';
    'VSS100':
      PIN_NUMBER='(0,0,230)';
      PINUSE='POWER';
      NO_LOAD_CHECK='Both';
      NO_IO_CHECK='Both';
      NO_ASSERT_CHECK='TRUE';
      NO_DIR_CHECK='TRUE';
      ALLOW_CONNECT='TRUE';
    'VSS102':
      PIN_NUMBER='(0,0,235)';
      PINUSE='POWER';
      NO_LOAD_CHECK='Both';
      NO_IO_CHECK='Both';
      NO_ASSERT_CHECK='TRUE';
      NO_DIR_CHECK='TRUE';
      ALLOW_CONNECT='TRUE';
    'VSS104':
      PIN_NUMBER='(0,0,240)';
      PINUSE='POWER';
      NO_LOAD_CHECK='Both';
      NO_IO_CHECK='Both';
      NO_ASSERT_CHECK='TRUE';
      NO_DIR_CHECK='TRUE';
      ALLOW_CONNECT='TRUE';
    'VSS58':
      PIN_NUMBER='(0,0,132)';
      PINUSE='POWER';
      NO_LOAD_CHECK='Both';
      NO_IO_CHECK='Both';
      NO_ASSERT_CHECK='TRUE';
      NO_DIR_CHECK='TRUE';
      ALLOW_CONNECT='TRUE';
    'VSS60':
      PIN_NUMBER='(0,0,136)';
      PINUSE='POWER';
      NO_LOAD_CHECK='Both';
      NO_IO_CHECK='Both';
      NO_ASSERT_CHECK='TRUE';
      NO_DIR_CHECK='TRUE';
      ALLOW_CONNECT='TRUE';
    'VSS61':
      PIN_NUMBER='(0,0,139)';
      PINUSE='POWER';
      NO_LOAD_CHECK='Both';
      NO_IO_CHECK='Both';
      NO_ASSERT_CHECK='TRUE';
      NO_DIR_CHECK='TRUE';
      ALLOW_CONNECT='TRUE';
    'VSS62':
      PIN_NUMBER='(0,0,141)';
      PINUSE='POWER';
      NO_LOAD_CHECK='Both';
      NO_IO_CHECK='Both';
      NO_ASSERT_CHECK='TRUE';
      NO_DIR_CHECK='TRUE';
      ALLOW_CONNECT='TRUE';
    'G1':
      PIN_NUMBER='(0,0,G1)';
      PINUSE='POWER';
      NO_LOAD_CHECK='Both';
      NO_IO_CHECK='Both';
      NO_ASSERT_CHECK='TRUE';
      NO_DIR_CHECK='TRUE';
      ALLOW_CONNECT='TRUE';
    'G2':
      PIN_NUMBER='(0,0,G2)';
      PINUSE='POWER';
      NO_LOAD_CHECK='Both';
      NO_IO_CHECK='Both';
      NO_ASSERT_CHECK='TRUE';
      NO_DIR_CHECK='TRUE';
      ALLOW_CONNECT='TRUE';
    'G3':
      PIN_NUMBER='(0,0,G3)';
      PINUSE='POWER';
      NO_LOAD_CHECK='Both';
      NO_IO_CHECK='Both';
      NO_ASSERT_CHECK='TRUE';
      NO_DIR_CHECK='TRUE';
      ALLOW_CONNECT='TRUE';
  end_pin;
  body
      PART_NAME='SCONN288_ADR50017P087CC';
      BODY_NAME='SCONN288_ADR50017P087CC';
      PHYS_DES_PREFIX='J';
      CLASS='IO';
      STANDARD='';
      LIFECYCLE='';
      JEDEC_TYPE='DDR288S_1-1VXB';
      DESCRIPTION='CONN SMD HS DDR5 288P 2R FS(P0.85,H21.3)';
      MANUFTR='LTS';
      MANUF_PN='ADR50017-P087CC';
      RD_CMPLS_LVL='EP(V1)';
      CMPLS_LVL='';
      DIP_SMD='';
      FROM_PJ='F0C-IVES';
      DATA='LTS_ADR50017-P087CC.pdf';
      FP_ECN='ADR50017-P087CC.msg';
      EE_CHECK_LIST='';
      CREATOR='';
      CREATEDAY='20210723';
      PSL='';
      STATUS='';
      ESD_CDM='';
      ESD_HBM='';
      ESD_MM='';
      MSD='';
      PIN_LENGTH_LONG_PIN='81 MILS';
      PIN_LENGTH_SHORT_PIN='81 MILS';
      PARENT_PART_TYPE='SCONN288_ADR50017P087CC';
      PARENT_PPT='SCONN288_ADR50017P087CC';
      PARENT_PPT_PART='SCONN288_ADR50017P087CC-SCONN288_ADR50017-P087CC,SMLF,IO,DFHST8FS460';
  end_body;
end_primitive;
primitive 'SCONN288_ADR50017P130CC-SCONN2A';
  pin
    'VIN_MGMT':
      PIN_NUMBER='(3,0,0)';
      PINUSE='POWER';
      NO_LOAD_CHECK='Both';
      NO_IO_CHECK='Both';
      NO_ASSERT_CHECK='TRUE';
      NO_DIR_CHECK='TRUE';
      ALLOW_CONNECT='TRUE';
    'RFU0':
      PIN_NUMBER='(2,0,0)';
      OUTPUT_TYPE='(TS,TS)';
      INPUT_LOAD='(-0.01,0.01)';
      OUTPUT_LOAD='(1.0,-1.0)';
      PINUSE='TRI';
    'RFU1':
      PIN_NUMBER='(144,0,0)';
      OUTPUT_TYPE='(TS,TS)';
      INPUT_LOAD='(-0.01,0.01)';
      OUTPUT_LOAD='(1.0,-1.0)';
      PINUSE='TRI';
    'RFU2':
      PIN_NUMBER='(149,0,0)';
      OUTPUT_TYPE='(TS,TS)';
      INPUT_LOAD='(-0.01,0.01)';
      OUTPUT_LOAD='(1.0,-1.0)';
      PINUSE='TRI';
    'RFU3':
      PIN_NUMBER='(150,0,0)';
      OUTPUT_TYPE='(TS,TS)';
      INPUT_LOAD='(-0.01,0.01)';
      OUTPUT_LOAD='(1.0,-1.0)';
      PINUSE='TRI';
    'RFU4':
      PIN_NUMBER='(220,0,0)';
      OUTPUT_TYPE='(TS,TS)';
      INPUT_LOAD='(-0.01,0.01)';
      OUTPUT_LOAD='(1.0,-1.0)';
      PINUSE='TRI';
    'RFU5':
      PIN_NUMBER='(231,0,0)';
      OUTPUT_TYPE='(TS,TS)';
      INPUT_LOAD='(-0.01,0.01)';
      OUTPUT_LOAD='(1.0,-1.0)';
      PINUSE='TRI';
    'RFU6':
      PIN_NUMBER='(232,0,0)';
      OUTPUT_TYPE='(TS,TS)';
      INPUT_LOAD='(-0.01,0.01)';
      OUTPUT_LOAD='(1.0,-1.0)';
      PINUSE='TRI';
    'RESET_N':
      PIN_NUMBER='(207,0,0)';
      INPUT_LOAD='(-0.01,0.01)';
      PINUSE='IN';
    'PWR_GOOD||FAIL_N':
      PIN_NUMBER='(147,0,0)';
      BIDIRECTIONAL='TRUE';
      INPUT_LOAD='(-0.01,0.01)';
      OUTPUT_LOAD='(1.0,-1.0)';
      PINUSE='BI';
    'PAR_B':
      PIN_NUMBER='(227,0,0)';
      INPUT_LOAD='(-0.01,0.01)';
      PINUSE='IN';
    'PAR_A':
      PIN_NUMBER='(74,0,0)';
      INPUT_LOAD='(-0.01,0.01)';
      PINUSE='IN';
    'LBS||RSP_B_N':
      PIN_NUMBER='(87,0,0)';
      OUTPUT_LOAD='(1.0,-1.0)';
      PINUSE='OUT';
    'LBD||RSP_A_N':
      PIN_NUMBER='(86,0,0)';
      OUTPUT_LOAD='(1.0,-1.0)';
      PINUSE='OUT';
    'HSDA':
      PIN_NUMBER='(5,0,0)';
      BIDIRECTIONAL='TRUE';
      INPUT_LOAD='(-0.01,0.01)';
      OUTPUT_LOAD='(1.0,-1.0)';
      PINUSE='BI';
    'HSCL':
      PIN_NUMBER='(4,0,0)';
      INPUT_LOAD='(-0.01,0.01)';
      PINUSE='IN';
    'HSA':
      PIN_NUMBER='(148,0,0)';
      INPUT_LOAD='(-0.01,0.01)';
      PINUSE='IN';
    'DQ0_B':
      PIN_NUMBER='(100,0,0)';
      BIDIRECTIONAL='TRUE';
      INPUT_LOAD='(-0.01,0.01)';
      OUTPUT_LOAD='(1.0,-1.0)';
      PINUSE='BI';
    'DQ1_B':
      PIN_NUMBER='(102,0,0)';
      BIDIRECTIONAL='TRUE';
      INPUT_LOAD='(-0.01,0.01)';
      OUTPUT_LOAD='(1.0,-1.0)';
      PINUSE='BI';
    'DQ2_B':
      PIN_NUMBER='(245,0,0)';
      BIDIRECTIONAL='TRUE';
      INPUT_LOAD='(-0.01,0.01)';
      OUTPUT_LOAD='(1.0,-1.0)';
      PINUSE='BI';
    'DQ3_B':
      PIN_NUMBER='(247,0,0)';
      BIDIRECTIONAL='TRUE';
      INPUT_LOAD='(-0.01,0.01)';
      OUTPUT_LOAD='(1.0,-1.0)';
      PINUSE='BI';
    'DQ4_B':
      PIN_NUMBER='(107,0,0)';
      BIDIRECTIONAL='TRUE';
      INPUT_LOAD='(-0.01,0.01)';
      OUTPUT_LOAD='(1.0,-1.0)';
      PINUSE='BI';
    'DQ5_B':
      PIN_NUMBER='(109,0,0)';
      BIDIRECTIONAL='TRUE';
      INPUT_LOAD='(-0.01,0.01)';
      OUTPUT_LOAD='(1.0,-1.0)';
      PINUSE='BI';
    'DQ6_B':
      PIN_NUMBER='(252,0,0)';
      BIDIRECTIONAL='TRUE';
      INPUT_LOAD='(-0.01,0.01)';
      OUTPUT_LOAD='(1.0,-1.0)';
      PINUSE='BI';
    'DQ7_B':
      PIN_NUMBER='(254,0,0)';
      BIDIRECTIONAL='TRUE';
      INPUT_LOAD='(-0.01,0.01)';
      OUTPUT_LOAD='(1.0,-1.0)';
      PINUSE='BI';
    'DQ8_B':
      PIN_NUMBER='(111,0,0)';
      BIDIRECTIONAL='TRUE';
      INPUT_LOAD='(-0.01,0.01)';
      OUTPUT_LOAD='(1.0,-1.0)';
      PINUSE='BI';
    'DQ9_B':
      PIN_NUMBER='(113,0,0)';
      BIDIRECTIONAL='TRUE';
      INPUT_LOAD='(-0.01,0.01)';
      OUTPUT_LOAD='(1.0,-1.0)';
      PINUSE='BI';
    'DQ10_B':
      PIN_NUMBER='(256,0,0)';
      BIDIRECTIONAL='TRUE';
      INPUT_LOAD='(-0.01,0.01)';
      OUTPUT_LOAD='(1.0,-1.0)';
      PINUSE='BI';
    'DQ11_B':
      PIN_NUMBER='(258,0,0)';
      BIDIRECTIONAL='TRUE';
      INPUT_LOAD='(-0.01,0.01)';
      OUTPUT_LOAD='(1.0,-1.0)';
      PINUSE='BI';
    'DQ12_B':
      PIN_NUMBER='(118,0,0)';
      BIDIRECTIONAL='TRUE';
      INPUT_LOAD='(-0.01,0.01)';
      OUTPUT_LOAD='(1.0,-1.0)';
      PINUSE='BI';
    'DQ13_B':
      PIN_NUMBER='(120,0,0)';
      BIDIRECTIONAL='TRUE';
      INPUT_LOAD='(-0.01,0.01)';
      OUTPUT_LOAD='(1.0,-1.0)';
      PINUSE='BI';
    'DQ14_B':
      PIN_NUMBER='(263,0,0)';
      BIDIRECTIONAL='TRUE';
      INPUT_LOAD='(-0.01,0.01)';
      OUTPUT_LOAD='(1.0,-1.0)';
      PINUSE='BI';
    'DQ15_B':
      PIN_NUMBER='(265,0,0)';
      BIDIRECTIONAL='TRUE';
      INPUT_LOAD='(-0.01,0.01)';
      OUTPUT_LOAD='(1.0,-1.0)';
      PINUSE='BI';
    'DQ16_B':
      PIN_NUMBER='(122,0,0)';
      BIDIRECTIONAL='TRUE';
      INPUT_LOAD='(-0.01,0.01)';
      OUTPUT_LOAD='(1.0,-1.0)';
      PINUSE='BI';
    'DQ17_B':
      PIN_NUMBER='(124,0,0)';
      BIDIRECTIONAL='TRUE';
      INPUT_LOAD='(-0.01,0.01)';
      OUTPUT_LOAD='(1.0,-1.0)';
      PINUSE='BI';
    'DQ18_B':
      PIN_NUMBER='(267,0,0)';
      BIDIRECTIONAL='TRUE';
      INPUT_LOAD='(-0.01,0.01)';
      OUTPUT_LOAD='(1.0,-1.0)';
      PINUSE='BI';
    'DQ19_B':
      PIN_NUMBER='(269,0,0)';
      BIDIRECTIONAL='TRUE';
      INPUT_LOAD='(-0.01,0.01)';
      OUTPUT_LOAD='(1.0,-1.0)';
      PINUSE='BI';
    'DQ20_B':
      PIN_NUMBER='(129,0,0)';
      BIDIRECTIONAL='TRUE';
      INPUT_LOAD='(-0.01,0.01)';
      OUTPUT_LOAD='(1.0,-1.0)';
      PINUSE='BI';
    'DQ21_B':
      PIN_NUMBER='(131,0,0)';
      BIDIRECTIONAL='TRUE';
      INPUT_LOAD='(-0.01,0.01)';
      OUTPUT_LOAD='(1.0,-1.0)';
      PINUSE='BI';
    'DQ22_B':
      PIN_NUMBER='(274,0,0)';
      BIDIRECTIONAL='TRUE';
      INPUT_LOAD='(-0.01,0.01)';
      OUTPUT_LOAD='(1.0,-1.0)';
      PINUSE='BI';
    'DQ23_B':
      PIN_NUMBER='(276,0,0)';
      BIDIRECTIONAL='TRUE';
      INPUT_LOAD='(-0.01,0.01)';
      OUTPUT_LOAD='(1.0,-1.0)';
      PINUSE='BI';
    'DQ24_B':
      PIN_NUMBER='(133,0,0)';
      BIDIRECTIONAL='TRUE';
      INPUT_LOAD='(-0.01,0.01)';
      OUTPUT_LOAD='(1.0,-1.0)';
      PINUSE='BI';
    'DQ25_B':
      PIN_NUMBER='(135,0,0)';
      BIDIRECTIONAL='TRUE';
      INPUT_LOAD='(-0.01,0.01)';
      OUTPUT_LOAD='(1.0,-1.0)';
      PINUSE='BI';
    'DQ26_B':
      PIN_NUMBER='(278,0,0)';
      BIDIRECTIONAL='TRUE';
      INPUT_LOAD='(-0.01,0.01)';
      OUTPUT_LOAD='(1.0,-1.0)';
      PINUSE='BI';
    'DQ27_B':
      PIN_NUMBER='(280,0,0)';
      BIDIRECTIONAL='TRUE';
      INPUT_LOAD='(-0.01,0.01)';
      OUTPUT_LOAD='(1.0,-1.0)';
      PINUSE='BI';
    'DQ28_B':
      PIN_NUMBER='(140,0,0)';
      BIDIRECTIONAL='TRUE';
      INPUT_LOAD='(-0.01,0.01)';
      OUTPUT_LOAD='(1.0,-1.0)';
      PINUSE='BI';
    'DQ29_B':
      PIN_NUMBER='(142,0,0)';
      BIDIRECTIONAL='TRUE';
      INPUT_LOAD='(-0.01,0.01)';
      OUTPUT_LOAD='(1.0,-1.0)';
      PINUSE='BI';
    'DQ30_B':
      PIN_NUMBER='(285,0,0)';
      BIDIRECTIONAL='TRUE';
      INPUT_LOAD='(-0.01,0.01)';
      OUTPUT_LOAD='(1.0,-1.0)';
      PINUSE='BI';
    'DQ31_B':
      PIN_NUMBER='(287,0,0)';
      BIDIRECTIONAL='TRUE';
      INPUT_LOAD='(-0.01,0.01)';
      OUTPUT_LOAD='(1.0,-1.0)';
      PINUSE='BI';
    'DQ0_A':
      PIN_NUMBER='(7,0,0)';
      BIDIRECTIONAL='TRUE';
      INPUT_LOAD='(-0.01,0.01)';
      OUTPUT_LOAD='(1.0,-1.0)';
      PINUSE='BI';
    'DQ1_A':
      PIN_NUMBER='(9,0,0)';
      BIDIRECTIONAL='TRUE';
      INPUT_LOAD='(-0.01,0.01)';
      OUTPUT_LOAD='(1.0,-1.0)';
      PINUSE='BI';
    'DQ2_A':
      PIN_NUMBER='(152,0,0)';
      BIDIRECTIONAL='TRUE';
      INPUT_LOAD='(-0.01,0.01)';
      OUTPUT_LOAD='(1.0,-1.0)';
      PINUSE='BI';
    'DQ3_A':
      PIN_NUMBER='(154,0,0)';
      BIDIRECTIONAL='TRUE';
      INPUT_LOAD='(-0.01,0.01)';
      OUTPUT_LOAD='(1.0,-1.0)';
      PINUSE='BI';
    'DQ4_A':
      PIN_NUMBER='(14,0,0)';
      BIDIRECTIONAL='TRUE';
      INPUT_LOAD='(-0.01,0.01)';
      OUTPUT_LOAD='(1.0,-1.0)';
      PINUSE='BI';
    'DQ5_A':
      PIN_NUMBER='(16,0,0)';
      BIDIRECTIONAL='TRUE';
      INPUT_LOAD='(-0.01,0.01)';
      OUTPUT_LOAD='(1.0,-1.0)';
      PINUSE='BI';
    'DQ6_A':
      PIN_NUMBER='(159,0,0)';
      BIDIRECTIONAL='TRUE';
      INPUT_LOAD='(-0.01,0.01)';
      OUTPUT_LOAD='(1.0,-1.0)';
      PINUSE='BI';
    'DQ7_A':
      PIN_NUMBER='(161,0,0)';
      BIDIRECTIONAL='TRUE';
      INPUT_LOAD='(-0.01,0.01)';
      OUTPUT_LOAD='(1.0,-1.0)';
      PINUSE='BI';
    'DQ8_A':
      PIN_NUMBER='(18,0,0)';
      BIDIRECTIONAL='TRUE';
      INPUT_LOAD='(-0.01,0.01)';
      OUTPUT_LOAD='(1.0,-1.0)';
      PINUSE='BI';
    'DQ9_A':
      PIN_NUMBER='(20,0,0)';
      BIDIRECTIONAL='TRUE';
      INPUT_LOAD='(-0.01,0.01)';
      OUTPUT_LOAD='(1.0,-1.0)';
      PINUSE='BI';
    'DQ10_A':
      PIN_NUMBER='(163,0,0)';
      BIDIRECTIONAL='TRUE';
      INPUT_LOAD='(-0.01,0.01)';
      OUTPUT_LOAD='(1.0,-1.0)';
      PINUSE='BI';
    'DQ11_A':
      PIN_NUMBER='(165,0,0)';
      BIDIRECTIONAL='TRUE';
      INPUT_LOAD='(-0.01,0.01)';
      OUTPUT_LOAD='(1.0,-1.0)';
      PINUSE='BI';
    'DQ12_A':
      PIN_NUMBER='(25,0,0)';
      BIDIRECTIONAL='TRUE';
      INPUT_LOAD='(-0.01,0.01)';
      OUTPUT_LOAD='(1.0,-1.0)';
      PINUSE='BI';
    'DQ13_A':
      PIN_NUMBER='(27,0,0)';
      BIDIRECTIONAL='TRUE';
      INPUT_LOAD='(-0.01,0.01)';
      OUTPUT_LOAD='(1.0,-1.0)';
      PINUSE='BI';
    'DQ14_A':
      PIN_NUMBER='(170,0,0)';
      BIDIRECTIONAL='TRUE';
      INPUT_LOAD='(-0.01,0.01)';
      OUTPUT_LOAD='(1.0,-1.0)';
      PINUSE='BI';
    'DQ15_A':
      PIN_NUMBER='(172,0,0)';
      BIDIRECTIONAL='TRUE';
      INPUT_LOAD='(-0.01,0.01)';
      OUTPUT_LOAD='(1.0,-1.0)';
      PINUSE='BI';
    'DQ16_A':
      PIN_NUMBER='(29,0,0)';
      BIDIRECTIONAL='TRUE';
      INPUT_LOAD='(-0.01,0.01)';
      OUTPUT_LOAD='(1.0,-1.0)';
      PINUSE='BI';
    'DQ17_A':
      PIN_NUMBER='(31,0,0)';
      BIDIRECTIONAL='TRUE';
      INPUT_LOAD='(-0.01,0.01)';
      OUTPUT_LOAD='(1.0,-1.0)';
      PINUSE='BI';
    'DQ18_A':
      PIN_NUMBER='(174,0,0)';
      BIDIRECTIONAL='TRUE';
      INPUT_LOAD='(-0.01,0.01)';
      OUTPUT_LOAD='(1.0,-1.0)';
      PINUSE='BI';
    'DQ19_A':
      PIN_NUMBER='(176,0,0)';
      BIDIRECTIONAL='TRUE';
      INPUT_LOAD='(-0.01,0.01)';
      OUTPUT_LOAD='(1.0,-1.0)';
      PINUSE='BI';
    'DQ20_A':
      PIN_NUMBER='(36,0,0)';
      BIDIRECTIONAL='TRUE';
      INPUT_LOAD='(-0.01,0.01)';
      OUTPUT_LOAD='(1.0,-1.0)';
      PINUSE='BI';
    'DQ21_A':
      PIN_NUMBER='(38,0,0)';
      BIDIRECTIONAL='TRUE';
      INPUT_LOAD='(-0.01,0.01)';
      OUTPUT_LOAD='(1.0,-1.0)';
      PINUSE='BI';
    'DQ22_A':
      PIN_NUMBER='(181,0,0)';
      BIDIRECTIONAL='TRUE';
      INPUT_LOAD='(-0.01,0.01)';
      OUTPUT_LOAD='(1.0,-1.0)';
      PINUSE='BI';
    'DQ23_A':
      PIN_NUMBER='(183,0,0)';
      BIDIRECTIONAL='TRUE';
      INPUT_LOAD='(-0.01,0.01)';
      OUTPUT_LOAD='(1.0,-1.0)';
      PINUSE='BI';
    'DQ24_A':
      PIN_NUMBER='(40,0,0)';
      BIDIRECTIONAL='TRUE';
      INPUT_LOAD='(-0.01,0.01)';
      OUTPUT_LOAD='(1.0,-1.0)';
      PINUSE='BI';
    'DQ25_A':
      PIN_NUMBER='(42,0,0)';
      BIDIRECTIONAL='TRUE';
      INPUT_LOAD='(-0.01,0.01)';
      OUTPUT_LOAD='(1.0,-1.0)';
      PINUSE='BI';
    'DQ26_A':
      PIN_NUMBER='(185,0,0)';
      BIDIRECTIONAL='TRUE';
      INPUT_LOAD='(-0.01,0.01)';
      OUTPUT_LOAD='(1.0,-1.0)';
      PINUSE='BI';
    'DQ27_A':
      PIN_NUMBER='(187,0,0)';
      BIDIRECTIONAL='TRUE';
      INPUT_LOAD='(-0.01,0.01)';
      OUTPUT_LOAD='(1.0,-1.0)';
      PINUSE='BI';
    'DQ28_A':
      PIN_NUMBER='(47,0,0)';
      BIDIRECTIONAL='TRUE';
      INPUT_LOAD='(-0.01,0.01)';
      OUTPUT_LOAD='(1.0,-1.0)';
      PINUSE='BI';
    'DQ29_A':
      PIN_NUMBER='(49,0,0)';
      BIDIRECTIONAL='TRUE';
      INPUT_LOAD='(-0.01,0.01)';
      OUTPUT_LOAD='(1.0,-1.0)';
      PINUSE='BI';
    'DQ30_A':
      PIN_NUMBER='(192,0,0)';
      BIDIRECTIONAL='TRUE';
      INPUT_LOAD='(-0.01,0.01)';
      OUTPUT_LOAD='(1.0,-1.0)';
      PINUSE='BI';
    'CS1_B_N':
      PIN_NUMBER='(229,0,0)';
      INPUT_LOAD='(-0.01,0.01)';
      PINUSE='IN';
    'CS1_A_N':
      PIN_NUMBER='(209,0,0)';
      INPUT_LOAD='(-0.01,0.01)';
      PINUSE='IN';
    'CS0_B_N':
      PIN_NUMBER='(84,0,0)';
      INPUT_LOAD='(-0.01,0.01)';
      PINUSE='IN';
    'CS0_A_N':
      PIN_NUMBER='(64,0,0)';
      INPUT_LOAD='(-0.01,0.01)';
      PINUSE='IN';
    'CK_T':
      PIN_NUMBER='(217,0,0)';
      INPUT_LOAD='(-0.01,0.01)';
      PINUSE='IN';
    'CK_C':
      PIN_NUMBER='(218,0,0)';
      INPUT_LOAD='(-0.01,0.01)';
      PINUSE='IN';
    'CB0_B':
      PIN_NUMBER='(96,0,0)';
      BIDIRECTIONAL='TRUE';
      INPUT_LOAD='(-0.01,0.01)';
      OUTPUT_LOAD='(1.0,-1.0)';
      PINUSE='BI';
    'CB1_B':
      PIN_NUMBER='(98,0,0)';
      BIDIRECTIONAL='TRUE';
      INPUT_LOAD='(-0.01,0.01)';
      OUTPUT_LOAD='(1.0,-1.0)';
      PINUSE='BI';
    'CB2_B':
      PIN_NUMBER='(241,0,0)';
      BIDIRECTIONAL='TRUE';
      INPUT_LOAD='(-0.01,0.01)';
      OUTPUT_LOAD='(1.0,-1.0)';
      PINUSE='BI';
    'CB3_B':
      PIN_NUMBER='(243,0,0)';
      BIDIRECTIONAL='TRUE';
      INPUT_LOAD='(-0.01,0.01)';
      OUTPUT_LOAD='(1.0,-1.0)';
      PINUSE='BI';
    'CB4_B':
      PIN_NUMBER='(89,0,0)';
      BIDIRECTIONAL='TRUE';
      INPUT_LOAD='(-0.01,0.01)';
      OUTPUT_LOAD='(1.0,-1.0)';
      PINUSE='BI';
    'CB5_B':
      PIN_NUMBER='(91,0,0)';
      BIDIRECTIONAL='TRUE';
      INPUT_LOAD='(-0.01,0.01)';
      OUTPUT_LOAD='(1.0,-1.0)';
      PINUSE='BI';
    'CB6_B':
      PIN_NUMBER='(234,0,0)';
      BIDIRECTIONAL='TRUE';
      INPUT_LOAD='(-0.01,0.01)';
      OUTPUT_LOAD='(1.0,-1.0)';
      PINUSE='BI';
    'CB0_A':
      PIN_NUMBER='(51,0,0)';
      BIDIRECTIONAL='TRUE';
      INPUT_LOAD='(-0.01,0.01)';
      OUTPUT_LOAD='(1.0,-1.0)';
      PINUSE='BI';
    'CB2_A':
      PIN_NUMBER='(196,0,0)';
      BIDIRECTIONAL='TRUE';
      INPUT_LOAD='(-0.01,0.01)';
      OUTPUT_LOAD='(1.0,-1.0)';
      PINUSE='BI';
    'CB3_A':
      PIN_NUMBER='(198,0,0)';
      BIDIRECTIONAL='TRUE';
      INPUT_LOAD='(-0.01,0.01)';
      OUTPUT_LOAD='(1.0,-1.0)';
      PINUSE='BI';
    'CB5_A':
      PIN_NUMBER='(60,0,0)';
      BIDIRECTIONAL='TRUE';
      INPUT_LOAD='(-0.01,0.01)';
      OUTPUT_LOAD='(1.0,-1.0)';
      PINUSE='BI';
    'CB6_A':
      PIN_NUMBER='(203,0,0)';
      BIDIRECTIONAL='TRUE';
      INPUT_LOAD='(-0.01,0.01)';
      OUTPUT_LOAD='(1.0,-1.0)';
      PINUSE='BI';
    'CA6_B':
      PIN_NUMBER='(82,0,0)';
      INPUT_LOAD='(-0.01,0.01)';
      PINUSE='IN';
    'CA6_A':
      PIN_NUMBER='(72,0,0)';
      INPUT_LOAD='(-0.01,0.01)';
      PINUSE='IN';
    'CA5_B':
      PIN_NUMBER='(225,0,0)';
      INPUT_LOAD='(-0.01,0.01)';
      PINUSE='IN';
    'CA5_A':
      PIN_NUMBER='(215,0,0)';
      INPUT_LOAD='(-0.01,0.01)';
      PINUSE='IN';
    'CA4_B':
      PIN_NUMBER='(80,0,0)';
      INPUT_LOAD='(-0.01,0.01)';
      PINUSE='IN';
    'CA4_A':
      PIN_NUMBER='(70,0,0)';
      INPUT_LOAD='(-0.01,0.01)';
      PINUSE='IN';
    'CA3_B':
      PIN_NUMBER='(223,0,0)';
      INPUT_LOAD='(-0.01,0.01)';
      PINUSE='IN';
    'CA3_A':
      PIN_NUMBER='(213,0,0)';
      INPUT_LOAD='(-0.01,0.01)';
      PINUSE='IN';
    'CA2_B':
      PIN_NUMBER='(78,0,0)';
      INPUT_LOAD='(-0.01,0.01)';
      PINUSE='IN';
    'CA2_A':
      PIN_NUMBER='(68,0,0)';
      INPUT_LOAD='(-0.01,0.01)';
      PINUSE='IN';
    'CA1_B':
      PIN_NUMBER='(221,0,0)';
      INPUT_LOAD='(-0.01,0.01)';
      PINUSE='IN';
    'CA1_A':
      PIN_NUMBER='(211,0,0)';
      INPUT_LOAD='(-0.01,0.01)';
      PINUSE='IN';
    'CA0_B':
      PIN_NUMBER='(76,0,0)';
      INPUT_LOAD='(-0.01,0.01)';
      PINUSE='IN';
    'CA0_A':
      PIN_NUMBER='(66,0,0)';
      INPUT_LOAD='(-0.01,0.01)';
      PINUSE='IN';
    'ALERT_N':
      PIN_NUMBER='(62,0,0)';
      OUTPUT_LOAD='(1.0,-1.0)';
      PINUSE='OUT';
    'CB7_B':
      PIN_NUMBER='(236,0,0)';
      BIDIRECTIONAL='TRUE';
      INPUT_LOAD='(-0.01,0.01)';
      OUTPUT_LOAD='(1.0,-1.0)';
      PINUSE='BI';
    'CB1_A':
      PIN_NUMBER='(53,0,0)';
      BIDIRECTIONAL='TRUE';
      INPUT_LOAD='(-0.01,0.01)';
      OUTPUT_LOAD='(1.0,-1.0)';
      PINUSE='BI';
    'CB4_A':
      PIN_NUMBER='(58,0,0)';
      BIDIRECTIONAL='TRUE';
      INPUT_LOAD='(-0.01,0.01)';
      OUTPUT_LOAD='(1.0,-1.0)';
      PINUSE='BI';
    'CB7_A':
      PIN_NUMBER='(205,0,0)';
      BIDIRECTIONAL='TRUE';
      INPUT_LOAD='(-0.01,0.01)';
      OUTPUT_LOAD='(1.0,-1.0)';
      PINUSE='BI';
    'DQ31_A':
      PIN_NUMBER='(194,0,0)';
      BIDIRECTIONAL='TRUE';
      INPUT_LOAD='(-0.01,0.01)';
      OUTPUT_LOAD='(1.0,-1.0)';
      PINUSE='BI';
    'DQS9_B_T||TDQS9_B_T||DBI4_B_N':
      PIN_NUMBER='(0,93,0)';
      BIDIRECTIONAL='TRUE';
      INPUT_LOAD='(-0.01,0.01)';
      OUTPUT_LOAD='(1.0,-1.0)';
      PINUSE='BI';
    'DQS9_B_C||TDQS9_B_C':
      PIN_NUMBER='(0,94,0)';
      BIDIRECTIONAL='TRUE';
      INPUT_LOAD='(-0.01,0.01)';
      OUTPUT_LOAD='(1.0,-1.0)';
      PINUSE='BI';
    'DQS9_A_T||TDQS9_A_T':
      PIN_NUMBER='(0,201,0)';
      BIDIRECTIONAL='TRUE';
      INPUT_LOAD='(-0.01,0.01)';
      OUTPUT_LOAD='(1.0,-1.0)';
      PINUSE='BI';
    'DQS9_A_C||TDQS9_A_C':
      PIN_NUMBER='(0,200,0)';
      BIDIRECTIONAL='TRUE';
      INPUT_LOAD='(-0.01,0.01)';
      OUTPUT_LOAD='(1.0,-1.0)';
      PINUSE='BI';
    'DQS8_A_T||TDQS8_A_T':
      PIN_NUMBER='(0,190,0)';
      BIDIRECTIONAL='TRUE';
      INPUT_LOAD='(-0.01,0.01)';
      OUTPUT_LOAD='(1.0,-1.0)';
      PINUSE='BI';
    'DQS8_A_C||TDQS8_A_C':
      PIN_NUMBER='(0,189,0)';
      BIDIRECTIONAL='TRUE';
      INPUT_LOAD='(-0.01,0.01)';
      OUTPUT_LOAD='(1.0,-1.0)';
      PINUSE='BI';
    'DQS7_B_C||TDQS7_B_C':
      PIN_NUMBER='(0,271,0)';
      BIDIRECTIONAL='TRUE';
      INPUT_LOAD='(-0.01,0.01)';
      OUTPUT_LOAD='(1.0,-1.0)';
      PINUSE='BI';
    'DQS7_A_T||TDQS7_A_T':
      PIN_NUMBER='(0,179,0)';
      BIDIRECTIONAL='TRUE';
      INPUT_LOAD='(-0.01,0.01)';
      OUTPUT_LOAD='(1.0,-1.0)';
      PINUSE='BI';
    'DQS6_B_T||TDQS6_B_T':
      PIN_NUMBER='(0,261,0)';
      BIDIRECTIONAL='TRUE';
      INPUT_LOAD='(-0.01,0.01)';
      OUTPUT_LOAD='(1.0,-1.0)';
      PINUSE='BI';
    'DQS6_B_C||TDQS6_B_C':
      PIN_NUMBER='(0,260,0)';
      BIDIRECTIONAL='TRUE';
      INPUT_LOAD='(-0.01,0.01)';
      OUTPUT_LOAD='(1.0,-1.0)';
      PINUSE='BI';
    'DQS6_A_C||TDQS6_A_C||DQS6_A_T||TDQS6_A_T':
      PIN_NUMBER='(0,167,0)';
      BIDIRECTIONAL='TRUE';
      INPUT_LOAD='(-0.01,0.01)';
      OUTPUT_LOAD='(1.0,-1.0)';
      PINUSE='BI';
    'DQS5_B_T||TDQS5_B_T':
      PIN_NUMBER='(0,250,0)';
      BIDIRECTIONAL='TRUE';
      INPUT_LOAD='(-0.01,0.01)';
      OUTPUT_LOAD='(1.0,-1.0)';
      PINUSE='BI';
    'DQS5_B_C||TDQS5_B_C':
      PIN_NUMBER='(0,249,0)';
      BIDIRECTIONAL='TRUE';
      INPUT_LOAD='(-0.01,0.01)';
      OUTPUT_LOAD='(1.0,-1.0)';
      PINUSE='BI';
    'DQS5_A_T||TDQS5_A_T':
      PIN_NUMBER='(0,157,0)';
      BIDIRECTIONAL='TRUE';
      INPUT_LOAD='(-0.01,0.01)';
      OUTPUT_LOAD='(1.0,-1.0)';
      PINUSE='BI';
    'DQS5_A_C||TDQS5_A_C||DQS5_A_T||TDQS5_A_T':
      PIN_NUMBER='(0,156,0)';
      BIDIRECTIONAL='TRUE';
      INPUT_LOAD='(-0.01,0.01)';
      OUTPUT_LOAD='(1.0,-1.0)';
      PINUSE='BI';
    'DQS4_B_T':
      PIN_NUMBER='(0,239,0)';
      BIDIRECTIONAL='TRUE';
      INPUT_LOAD='(-0.01,0.01)';
      OUTPUT_LOAD='(1.0,-1.0)';
      PINUSE='BI';
    'DQS4_B_C':
      PIN_NUMBER='(0,238,0)';
      BIDIRECTIONAL='TRUE';
      INPUT_LOAD='(-0.01,0.01)';
      OUTPUT_LOAD='(1.0,-1.0)';
      PINUSE='BI';
    'DQS4_A_T':
      PIN_NUMBER='(0,55,0)';
      BIDIRECTIONAL='TRUE';
      INPUT_LOAD='(-0.01,0.01)';
      OUTPUT_LOAD='(1.0,-1.0)';
      PINUSE='BI';
    'DQS4_A_C':
      PIN_NUMBER='(0,56,0)';
      BIDIRECTIONAL='TRUE';
      INPUT_LOAD='(-0.01,0.01)';
      OUTPUT_LOAD='(1.0,-1.0)';
      PINUSE='BI';
    'DQS3_B_T':
      PIN_NUMBER='(0,137,0)';
      BIDIRECTIONAL='TRUE';
      INPUT_LOAD='(-0.01,0.01)';
      OUTPUT_LOAD='(1.0,-1.0)';
      PINUSE='BI';
    'DQS3_B_C':
      PIN_NUMBER='(0,138,0)';
      BIDIRECTIONAL='TRUE';
      INPUT_LOAD='(-0.01,0.01)';
      OUTPUT_LOAD='(1.0,-1.0)';
      PINUSE='BI';
    'DQS3_A_T':
      PIN_NUMBER='(0,44,0)';
      BIDIRECTIONAL='TRUE';
      INPUT_LOAD='(-0.01,0.01)';
      OUTPUT_LOAD='(1.0,-1.0)';
      PINUSE='BI';
    'DQS3_A_C':
      PIN_NUMBER='(0,45,0)';
      BIDIRECTIONAL='TRUE';
      INPUT_LOAD='(-0.01,0.01)';
      OUTPUT_LOAD='(1.0,-1.0)';
      PINUSE='BI';
    'DQS2_B_T':
      PIN_NUMBER='(0,126,0)';
      BIDIRECTIONAL='TRUE';
      INPUT_LOAD='(-0.01,0.01)';
      OUTPUT_LOAD='(1.0,-1.0)';
      PINUSE='BI';
    'DQS2_B_C':
      PIN_NUMBER='(0,127,0)';
      BIDIRECTIONAL='TRUE';
      INPUT_LOAD='(-0.01,0.01)';
      OUTPUT_LOAD='(1.0,-1.0)';
      PINUSE='BI';
    'DQS2_A_T':
      PIN_NUMBER='(0,33,0)';
      BIDIRECTIONAL='TRUE';
      INPUT_LOAD='(-0.01,0.01)';
      OUTPUT_LOAD='(1.0,-1.0)';
      PINUSE='BI';
    'DQS2_A_C':
      PIN_NUMBER='(0,34,0)';
      BIDIRECTIONAL='TRUE';
      INPUT_LOAD='(-0.01,0.01)';
      OUTPUT_LOAD='(1.0,-1.0)';
      PINUSE='BI';
    'DQS1_B_T':
      PIN_NUMBER='(0,115,0)';
      BIDIRECTIONAL='TRUE';
      INPUT_LOAD='(-0.01,0.01)';
      OUTPUT_LOAD='(1.0,-1.0)';
      PINUSE='BI';
    'DQS1_B_C':
      PIN_NUMBER='(0,116,0)';
      BIDIRECTIONAL='TRUE';
      INPUT_LOAD='(-0.01,0.01)';
      OUTPUT_LOAD='(1.0,-1.0)';
      PINUSE='BI';
    'DQS1_A_T':
      PIN_NUMBER='(0,22,0)';
      BIDIRECTIONAL='TRUE';
      INPUT_LOAD='(-0.01,0.01)';
      OUTPUT_LOAD='(1.0,-1.0)';
      PINUSE='BI';
    'DQS1_A_C':
      PIN_NUMBER='(0,23,0)';
      BIDIRECTIONAL='TRUE';
      INPUT_LOAD='(-0.01,0.01)';
      OUTPUT_LOAD='(1.0,-1.0)';
      PINUSE='BI';
    'DQS0_B_T':
      PIN_NUMBER='(0,104,0)';
      BIDIRECTIONAL='TRUE';
      INPUT_LOAD='(-0.01,0.01)';
      OUTPUT_LOAD='(1.0,-1.0)';
      PINUSE='BI';
    'DQS0_B_C':
      PIN_NUMBER='(0,105,0)';
      BIDIRECTIONAL='TRUE';
      INPUT_LOAD='(-0.01,0.01)';
      OUTPUT_LOAD='(1.0,-1.0)';
      PINUSE='BI';
    'DQS0_A_T':
      PIN_NUMBER='(0,11,0)';
      BIDIRECTIONAL='TRUE';
      INPUT_LOAD='(-0.01,0.01)';
      OUTPUT_LOAD='(1.0,-1.0)';
      PINUSE='BI';
    'DQS0_A_C':
      PIN_NUMBER='(0,12,0)';
      BIDIRECTIONAL='TRUE';
      INPUT_LOAD='(-0.01,0.01)';
      OUTPUT_LOAD='(1.0,-1.0)';
      PINUSE='BI';
    'DQS7_B_T||TDQS7_B_T':
      PIN_NUMBER='(0,272,0)';
      BIDIRECTIONAL='TRUE';
      INPUT_LOAD='(-0.01,0.01)';
      OUTPUT_LOAD='(1.0,-1.0)';
      PINUSE='BI';
    'DQS8_B_C||TDQS8_B_C':
      PIN_NUMBER='(0,282,0)';
      BIDIRECTIONAL='TRUE';
      INPUT_LOAD='(-0.01,0.01)';
      OUTPUT_LOAD='(1.0,-1.0)';
      PINUSE='BI';
    'DQS8_B_T||TDQS8_B_T':
      PIN_NUMBER='(0,283,0)';
      BIDIRECTIONAL='TRUE';
      INPUT_LOAD='(-0.01,0.01)';
      OUTPUT_LOAD='(1.0,-1.0)';
      PINUSE='BI';
    'DQS6_A_T||TDQS6_A_T':
      PIN_NUMBER='(0,168,0)';
      BIDIRECTIONAL='TRUE';
      INPUT_LOAD='(-0.01,0.01)';
      OUTPUT_LOAD='(1.0,-1.0)';
      PINUSE='BI';
    'DQS7_A_C||TDQS7_A_C':
      PIN_NUMBER='(0,178,0)';
      BIDIRECTIONAL='TRUE';
      INPUT_LOAD='(-0.01,0.01)';
      OUTPUT_LOAD='(1.0,-1.0)';
      PINUSE='BI';
    'VSS0':
      PIN_NUMBER='(0,0,6)';
      PINUSE='POWER';
      NO_LOAD_CHECK='Both';
      NO_IO_CHECK='Both';
      NO_ASSERT_CHECK='TRUE';
      NO_DIR_CHECK='TRUE';
      ALLOW_CONNECT='TRUE';
    'VSS1':
      PIN_NUMBER='(0,0,8)';
      PINUSE='POWER';
      NO_LOAD_CHECK='Both';
      NO_IO_CHECK='Both';
      NO_ASSERT_CHECK='TRUE';
      NO_DIR_CHECK='TRUE';
      ALLOW_CONNECT='TRUE';
    'VSS2':
      PIN_NUMBER='(0,0,10)';
      PINUSE='POWER';
      NO_LOAD_CHECK='Both';
      NO_IO_CHECK='Both';
      NO_ASSERT_CHECK='TRUE';
      NO_DIR_CHECK='TRUE';
      ALLOW_CONNECT='TRUE';
    'VSS3':
      PIN_NUMBER='(0,0,13)';
      PINUSE='POWER';
      NO_LOAD_CHECK='Both';
      NO_IO_CHECK='Both';
      NO_ASSERT_CHECK='TRUE';
      NO_DIR_CHECK='TRUE';
      ALLOW_CONNECT='TRUE';
    'VSS4':
      PIN_NUMBER='(0,0,15)';
      PINUSE='POWER';
      NO_LOAD_CHECK='Both';
      NO_IO_CHECK='Both';
      NO_ASSERT_CHECK='TRUE';
      NO_DIR_CHECK='TRUE';
      ALLOW_CONNECT='TRUE';
    'VSS5':
      PIN_NUMBER='(0,0,17)';
      PINUSE='POWER';
      NO_LOAD_CHECK='Both';
      NO_IO_CHECK='Both';
      NO_ASSERT_CHECK='TRUE';
      NO_DIR_CHECK='TRUE';
      ALLOW_CONNECT='TRUE';
    'VSS6':
      PIN_NUMBER='(0,0,19)';
      PINUSE='POWER';
      NO_LOAD_CHECK='Both';
      NO_IO_CHECK='Both';
      NO_ASSERT_CHECK='TRUE';
      NO_DIR_CHECK='TRUE';
      ALLOW_CONNECT='TRUE';
    'VSS7':
      PIN_NUMBER='(0,0,21)';
      PINUSE='POWER';
      NO_LOAD_CHECK='Both';
      NO_IO_CHECK='Both';
      NO_ASSERT_CHECK='TRUE';
      NO_DIR_CHECK='TRUE';
      ALLOW_CONNECT='TRUE';
    'VSS8':
      PIN_NUMBER='(0,0,24)';
      PINUSE='POWER';
      NO_LOAD_CHECK='Both';
      NO_IO_CHECK='Both';
      NO_ASSERT_CHECK='TRUE';
      NO_DIR_CHECK='TRUE';
      ALLOW_CONNECT='TRUE';
    'VSS9':
      PIN_NUMBER='(0,0,26)';
      PINUSE='POWER';
      NO_LOAD_CHECK='Both';
      NO_IO_CHECK='Both';
      NO_ASSERT_CHECK='TRUE';
      NO_DIR_CHECK='TRUE';
      ALLOW_CONNECT='TRUE';
    'VSS10':
      PIN_NUMBER='(0,0,28)';
      PINUSE='POWER';
      NO_LOAD_CHECK='Both';
      NO_IO_CHECK='Both';
      NO_ASSERT_CHECK='TRUE';
      NO_DIR_CHECK='TRUE';
      ALLOW_CONNECT='TRUE';
    'VSS11':
      PIN_NUMBER='(0,0,30)';
      PINUSE='POWER';
      NO_LOAD_CHECK='Both';
      NO_IO_CHECK='Both';
      NO_ASSERT_CHECK='TRUE';
      NO_DIR_CHECK='TRUE';
      ALLOW_CONNECT='TRUE';
    'VSS12':
      PIN_NUMBER='(0,0,32)';
      PINUSE='POWER';
      NO_LOAD_CHECK='Both';
      NO_IO_CHECK='Both';
      NO_ASSERT_CHECK='TRUE';
      NO_DIR_CHECK='TRUE';
      ALLOW_CONNECT='TRUE';
    'VSS13':
      PIN_NUMBER='(0,0,35)';
      PINUSE='POWER';
      NO_LOAD_CHECK='Both';
      NO_IO_CHECK='Both';
      NO_ASSERT_CHECK='TRUE';
      NO_DIR_CHECK='TRUE';
      ALLOW_CONNECT='TRUE';
    'VSS14':
      PIN_NUMBER='(0,0,37)';
      PINUSE='POWER';
      NO_LOAD_CHECK='Both';
      NO_IO_CHECK='Both';
      NO_ASSERT_CHECK='TRUE';
      NO_DIR_CHECK='TRUE';
      ALLOW_CONNECT='TRUE';
    'VSS15':
      PIN_NUMBER='(0,0,39)';
      PINUSE='POWER';
      NO_LOAD_CHECK='Both';
      NO_IO_CHECK='Both';
      NO_ASSERT_CHECK='TRUE';
      NO_DIR_CHECK='TRUE';
      ALLOW_CONNECT='TRUE';
    'VSS16':
      PIN_NUMBER='(0,0,41)';
      PINUSE='POWER';
      NO_LOAD_CHECK='Both';
      NO_IO_CHECK='Both';
      NO_ASSERT_CHECK='TRUE';
      NO_DIR_CHECK='TRUE';
      ALLOW_CONNECT='TRUE';
    'VSS17':
      PIN_NUMBER='(0,0,43)';
      PINUSE='POWER';
      NO_LOAD_CHECK='Both';
      NO_IO_CHECK='Both';
      NO_ASSERT_CHECK='TRUE';
      NO_DIR_CHECK='TRUE';
      ALLOW_CONNECT='TRUE';
    'VSS18':
      PIN_NUMBER='(0,0,46)';
      PINUSE='POWER';
      NO_LOAD_CHECK='Both';
      NO_IO_CHECK='Both';
      NO_ASSERT_CHECK='TRUE';
      NO_DIR_CHECK='TRUE';
      ALLOW_CONNECT='TRUE';
    'VSS19':
      PIN_NUMBER='(0,0,48)';
      PINUSE='POWER';
      NO_LOAD_CHECK='Both';
      NO_IO_CHECK='Both';
      NO_ASSERT_CHECK='TRUE';
      NO_DIR_CHECK='TRUE';
      ALLOW_CONNECT='TRUE';
    'VSS20':
      PIN_NUMBER='(0,0,50)';
      PINUSE='POWER';
      NO_LOAD_CHECK='Both';
      NO_IO_CHECK='Both';
      NO_ASSERT_CHECK='TRUE';
      NO_DIR_CHECK='TRUE';
      ALLOW_CONNECT='TRUE';
    'VSS21':
      PIN_NUMBER='(0,0,52)';
      PINUSE='POWER';
      NO_LOAD_CHECK='Both';
      NO_IO_CHECK='Both';
      NO_ASSERT_CHECK='TRUE';
      NO_DIR_CHECK='TRUE';
      ALLOW_CONNECT='TRUE';
    'VSS22':
      PIN_NUMBER='(0,0,54)';
      PINUSE='POWER';
      NO_LOAD_CHECK='Both';
      NO_IO_CHECK='Both';
      NO_ASSERT_CHECK='TRUE';
      NO_DIR_CHECK='TRUE';
      ALLOW_CONNECT='TRUE';
    'VSS23':
      PIN_NUMBER='(0,0,57)';
      PINUSE='POWER';
      NO_LOAD_CHECK='Both';
      NO_IO_CHECK='Both';
      NO_ASSERT_CHECK='TRUE';
      NO_DIR_CHECK='TRUE';
      ALLOW_CONNECT='TRUE';
    'VSS24':
      PIN_NUMBER='(0,0,59)';
      PINUSE='POWER';
      NO_LOAD_CHECK='Both';
      NO_IO_CHECK='Both';
      NO_ASSERT_CHECK='TRUE';
      NO_DIR_CHECK='TRUE';
      ALLOW_CONNECT='TRUE';
    'VSS25':
      PIN_NUMBER='(0,0,61)';
      PINUSE='POWER';
      NO_LOAD_CHECK='Both';
      NO_IO_CHECK='Both';
      NO_ASSERT_CHECK='TRUE';
      NO_DIR_CHECK='TRUE';
      ALLOW_CONNECT='TRUE';
    'VSS26':
      PIN_NUMBER='(0,0,63)';
      PINUSE='POWER';
      NO_LOAD_CHECK='Both';
      NO_IO_CHECK='Both';
      NO_ASSERT_CHECK='TRUE';
      NO_DIR_CHECK='TRUE';
      ALLOW_CONNECT='TRUE';
    'VSS27':
      PIN_NUMBER='(0,0,65)';
      PINUSE='POWER';
      NO_LOAD_CHECK='Both';
      NO_IO_CHECK='Both';
      NO_ASSERT_CHECK='TRUE';
      NO_DIR_CHECK='TRUE';
      ALLOW_CONNECT='TRUE';
    'VSS28':
      PIN_NUMBER='(0,0,67)';
      PINUSE='POWER';
      NO_LOAD_CHECK='Both';
      NO_IO_CHECK='Both';
      NO_ASSERT_CHECK='TRUE';
      NO_DIR_CHECK='TRUE';
      ALLOW_CONNECT='TRUE';
    'VSS29':
      PIN_NUMBER='(0,0,69)';
      PINUSE='POWER';
      NO_LOAD_CHECK='Both';
      NO_IO_CHECK='Both';
      NO_ASSERT_CHECK='TRUE';
      NO_DIR_CHECK='TRUE';
      ALLOW_CONNECT='TRUE';
    'VSS30':
      PIN_NUMBER='(0,0,71)';
      PINUSE='POWER';
      NO_LOAD_CHECK='Both';
      NO_IO_CHECK='Both';
      NO_ASSERT_CHECK='TRUE';
      NO_DIR_CHECK='TRUE';
      ALLOW_CONNECT='TRUE';
    'VSS31':
      PIN_NUMBER='(0,0,73)';
      PINUSE='POWER';
      NO_LOAD_CHECK='Both';
      NO_IO_CHECK='Both';
      NO_ASSERT_CHECK='TRUE';
      NO_DIR_CHECK='TRUE';
      ALLOW_CONNECT='TRUE';
    'VSS32':
      PIN_NUMBER='(0,0,75)';
      PINUSE='POWER';
      NO_LOAD_CHECK='Both';
      NO_IO_CHECK='Both';
      NO_ASSERT_CHECK='TRUE';
      NO_DIR_CHECK='TRUE';
      ALLOW_CONNECT='TRUE';
    'VSS33':
      PIN_NUMBER='(0,0,77)';
      PINUSE='POWER';
      NO_LOAD_CHECK='Both';
      NO_IO_CHECK='Both';
      NO_ASSERT_CHECK='TRUE';
      NO_DIR_CHECK='TRUE';
      ALLOW_CONNECT='TRUE';
    'VSS34':
      PIN_NUMBER='(0,0,79)';
      PINUSE='POWER';
      NO_LOAD_CHECK='Both';
      NO_IO_CHECK='Both';
      NO_ASSERT_CHECK='TRUE';
      NO_DIR_CHECK='TRUE';
      ALLOW_CONNECT='TRUE';
    'VSS35':
      PIN_NUMBER='(0,0,81)';
      PINUSE='POWER';
      NO_LOAD_CHECK='Both';
      NO_IO_CHECK='Both';
      NO_ASSERT_CHECK='TRUE';
      NO_DIR_CHECK='TRUE';
      ALLOW_CONNECT='TRUE';
    'VSS36':
      PIN_NUMBER='(0,0,83)';
      PINUSE='POWER';
      NO_LOAD_CHECK='Both';
      NO_IO_CHECK='Both';
      NO_ASSERT_CHECK='TRUE';
      NO_DIR_CHECK='TRUE';
      ALLOW_CONNECT='TRUE';
    'VSS37':
      PIN_NUMBER='(0,0,85)';
      PINUSE='POWER';
      NO_LOAD_CHECK='Both';
      NO_IO_CHECK='Both';
      NO_ASSERT_CHECK='TRUE';
      NO_DIR_CHECK='TRUE';
      ALLOW_CONNECT='TRUE';
    'VSS38':
      PIN_NUMBER='(0,0,88)';
      PINUSE='POWER';
      NO_LOAD_CHECK='Both';
      NO_IO_CHECK='Both';
      NO_ASSERT_CHECK='TRUE';
      NO_DIR_CHECK='TRUE';
      ALLOW_CONNECT='TRUE';
    'VSS39':
      PIN_NUMBER='(0,0,90)';
      PINUSE='POWER';
      NO_LOAD_CHECK='Both';
      NO_IO_CHECK='Both';
      NO_ASSERT_CHECK='TRUE';
      NO_DIR_CHECK='TRUE';
      ALLOW_CONNECT='TRUE';
    'VSS40':
      PIN_NUMBER='(0,0,92)';
      PINUSE='POWER';
      NO_LOAD_CHECK='Both';
      NO_IO_CHECK='Both';
      NO_ASSERT_CHECK='TRUE';
      NO_DIR_CHECK='TRUE';
      ALLOW_CONNECT='TRUE';
    'VSS41':
      PIN_NUMBER='(0,0,95)';
      PINUSE='POWER';
      NO_LOAD_CHECK='Both';
      NO_IO_CHECK='Both';
      NO_ASSERT_CHECK='TRUE';
      NO_DIR_CHECK='TRUE';
      ALLOW_CONNECT='TRUE';
    'VSS42':
      PIN_NUMBER='(0,0,97)';
      PINUSE='POWER';
      NO_LOAD_CHECK='Both';
      NO_IO_CHECK='Both';
      NO_ASSERT_CHECK='TRUE';
      NO_DIR_CHECK='TRUE';
      ALLOW_CONNECT='TRUE';
    'VSS43':
      PIN_NUMBER='(0,0,99)';
      PINUSE='POWER';
      NO_LOAD_CHECK='Both';
      NO_IO_CHECK='Both';
      NO_ASSERT_CHECK='TRUE';
      NO_DIR_CHECK='TRUE';
      ALLOW_CONNECT='TRUE';
    'VSS44':
      PIN_NUMBER='(0,0,101)';
      PINUSE='POWER';
      NO_LOAD_CHECK='Both';
      NO_IO_CHECK='Both';
      NO_ASSERT_CHECK='TRUE';
      NO_DIR_CHECK='TRUE';
      ALLOW_CONNECT='TRUE';
    'VSS45':
      PIN_NUMBER='(0,0,103)';
      PINUSE='POWER';
      NO_LOAD_CHECK='Both';
      NO_IO_CHECK='Both';
      NO_ASSERT_CHECK='TRUE';
      NO_DIR_CHECK='TRUE';
      ALLOW_CONNECT='TRUE';
    'VSS46':
      PIN_NUMBER='(0,0,106)';
      PINUSE='POWER';
      NO_LOAD_CHECK='Both';
      NO_IO_CHECK='Both';
      NO_ASSERT_CHECK='TRUE';
      NO_DIR_CHECK='TRUE';
      ALLOW_CONNECT='TRUE';
    'VSS47':
      PIN_NUMBER='(0,0,108)';
      PINUSE='POWER';
      NO_LOAD_CHECK='Both';
      NO_IO_CHECK='Both';
      NO_ASSERT_CHECK='TRUE';
      NO_DIR_CHECK='TRUE';
      ALLOW_CONNECT='TRUE';
    'VSS48':
      PIN_NUMBER='(0,0,110)';
      PINUSE='POWER';
      NO_LOAD_CHECK='Both';
      NO_IO_CHECK='Both';
      NO_ASSERT_CHECK='TRUE';
      NO_DIR_CHECK='TRUE';
      ALLOW_CONNECT='TRUE';
    'VSS49':
      PIN_NUMBER='(0,0,112)';
      PINUSE='POWER';
      NO_LOAD_CHECK='Both';
      NO_IO_CHECK='Both';
      NO_ASSERT_CHECK='TRUE';
      NO_DIR_CHECK='TRUE';
      ALLOW_CONNECT='TRUE';
    'VSS50':
      PIN_NUMBER='(0,0,114)';
      PINUSE='POWER';
      NO_LOAD_CHECK='Both';
      NO_IO_CHECK='Both';
      NO_ASSERT_CHECK='TRUE';
      NO_DIR_CHECK='TRUE';
      ALLOW_CONNECT='TRUE';
    'VSS51':
      PIN_NUMBER='(0,0,117)';
      PINUSE='POWER';
      NO_LOAD_CHECK='Both';
      NO_IO_CHECK='Both';
      NO_ASSERT_CHECK='TRUE';
      NO_DIR_CHECK='TRUE';
      ALLOW_CONNECT='TRUE';
    'VSS52':
      PIN_NUMBER='(0,0,119)';
      PINUSE='POWER';
      NO_LOAD_CHECK='Both';
      NO_IO_CHECK='Both';
      NO_ASSERT_CHECK='TRUE';
      NO_DIR_CHECK='TRUE';
      ALLOW_CONNECT='TRUE';
    'VSS53':
      PIN_NUMBER='(0,0,121)';
      PINUSE='POWER';
      NO_LOAD_CHECK='Both';
      NO_IO_CHECK='Both';
      NO_ASSERT_CHECK='TRUE';
      NO_DIR_CHECK='TRUE';
      ALLOW_CONNECT='TRUE';
    'VSS54':
      PIN_NUMBER='(0,0,123)';
      PINUSE='POWER';
      NO_LOAD_CHECK='Both';
      NO_IO_CHECK='Both';
      NO_ASSERT_CHECK='TRUE';
      NO_DIR_CHECK='TRUE';
      ALLOW_CONNECT='TRUE';
    'VSS55':
      PIN_NUMBER='(0,0,125)';
      PINUSE='POWER';
      NO_LOAD_CHECK='Both';
      NO_IO_CHECK='Both';
      NO_ASSERT_CHECK='TRUE';
      NO_DIR_CHECK='TRUE';
      ALLOW_CONNECT='TRUE';
    'VSS56':
      PIN_NUMBER='(0,0,128)';
      PINUSE='POWER';
      NO_LOAD_CHECK='Both';
      NO_IO_CHECK='Both';
      NO_ASSERT_CHECK='TRUE';
      NO_DIR_CHECK='TRUE';
      ALLOW_CONNECT='TRUE';
    'VSS57':
      PIN_NUMBER='(0,0,130)';
      PINUSE='POWER';
      NO_LOAD_CHECK='Both';
      NO_IO_CHECK='Both';
      NO_ASSERT_CHECK='TRUE';
      NO_DIR_CHECK='TRUE';
      ALLOW_CONNECT='TRUE';
    'VSS59':
      PIN_NUMBER='(0,0,134)';
      PINUSE='POWER';
      NO_LOAD_CHECK='Both';
      NO_IO_CHECK='Both';
      NO_ASSERT_CHECK='TRUE';
      NO_DIR_CHECK='TRUE';
      ALLOW_CONNECT='TRUE';
    'VSS63':
      PIN_NUMBER='(0,0,143)';
      PINUSE='POWER';
      NO_LOAD_CHECK='Both';
      NO_IO_CHECK='Both';
      NO_ASSERT_CHECK='TRUE';
      NO_DIR_CHECK='TRUE';
      ALLOW_CONNECT='TRUE';
    'VSS64':
      PIN_NUMBER='(0,0,151)';
      PINUSE='POWER';
      NO_LOAD_CHECK='Both';
      NO_IO_CHECK='Both';
      NO_ASSERT_CHECK='TRUE';
      NO_DIR_CHECK='TRUE';
      ALLOW_CONNECT='TRUE';
    'VSS65':
      PIN_NUMBER='(0,0,153)';
      PINUSE='POWER';
      NO_LOAD_CHECK='Both';
      NO_IO_CHECK='Both';
      NO_ASSERT_CHECK='TRUE';
      NO_DIR_CHECK='TRUE';
      ALLOW_CONNECT='TRUE';
    'VSS66':
      PIN_NUMBER='(0,0,155)';
      PINUSE='POWER';
      NO_LOAD_CHECK='Both';
      NO_IO_CHECK='Both';
      NO_ASSERT_CHECK='TRUE';
      NO_DIR_CHECK='TRUE';
      ALLOW_CONNECT='TRUE';
    'VSS67':
      PIN_NUMBER='(0,0,158)';
      PINUSE='POWER';
      NO_LOAD_CHECK='Both';
      NO_IO_CHECK='Both';
      NO_ASSERT_CHECK='TRUE';
      NO_DIR_CHECK='TRUE';
      ALLOW_CONNECT='TRUE';
    'VSS68':
      PIN_NUMBER='(0,0,160)';
      PINUSE='POWER';
      NO_LOAD_CHECK='Both';
      NO_IO_CHECK='Both';
      NO_ASSERT_CHECK='TRUE';
      NO_DIR_CHECK='TRUE';
      ALLOW_CONNECT='TRUE';
    'VSS69':
      PIN_NUMBER='(0,0,162)';
      PINUSE='POWER';
      NO_LOAD_CHECK='Both';
      NO_IO_CHECK='Both';
      NO_ASSERT_CHECK='TRUE';
      NO_DIR_CHECK='TRUE';
      ALLOW_CONNECT='TRUE';
    'VSS70':
      PIN_NUMBER='(0,0,164)';
      PINUSE='POWER';
      NO_LOAD_CHECK='Both';
      NO_IO_CHECK='Both';
      NO_ASSERT_CHECK='TRUE';
      NO_DIR_CHECK='TRUE';
      ALLOW_CONNECT='TRUE';
    'VSS71':
      PIN_NUMBER='(0,0,166)';
      PINUSE='POWER';
      NO_LOAD_CHECK='Both';
      NO_IO_CHECK='Both';
      NO_ASSERT_CHECK='TRUE';
      NO_DIR_CHECK='TRUE';
      ALLOW_CONNECT='TRUE';
    'VSS72':
      PIN_NUMBER='(0,0,169)';
      PINUSE='POWER';
      NO_LOAD_CHECK='Both';
      NO_IO_CHECK='Both';
      NO_ASSERT_CHECK='TRUE';
      NO_DIR_CHECK='TRUE';
      ALLOW_CONNECT='TRUE';
    'VSS73':
      PIN_NUMBER='(0,0,171)';
      PINUSE='POWER';
      NO_LOAD_CHECK='Both';
      NO_IO_CHECK='Both';
      NO_ASSERT_CHECK='TRUE';
      NO_DIR_CHECK='TRUE';
      ALLOW_CONNECT='TRUE';
    'VSS74':
      PIN_NUMBER='(0,0,173)';
      PINUSE='POWER';
      NO_LOAD_CHECK='Both';
      NO_IO_CHECK='Both';
      NO_ASSERT_CHECK='TRUE';
      NO_DIR_CHECK='TRUE';
      ALLOW_CONNECT='TRUE';
    'VSS75':
      PIN_NUMBER='(0,0,175)';
      PINUSE='POWER';
      NO_LOAD_CHECK='Both';
      NO_IO_CHECK='Both';
      NO_ASSERT_CHECK='TRUE';
      NO_DIR_CHECK='TRUE';
      ALLOW_CONNECT='TRUE';
    'VSS76':
      PIN_NUMBER='(0,0,177)';
      PINUSE='POWER';
      NO_LOAD_CHECK='Both';
      NO_IO_CHECK='Both';
      NO_ASSERT_CHECK='TRUE';
      NO_DIR_CHECK='TRUE';
      ALLOW_CONNECT='TRUE';
    'VSS77':
      PIN_NUMBER='(0,0,180)';
      PINUSE='POWER';
      NO_LOAD_CHECK='Both';
      NO_IO_CHECK='Both';
      NO_ASSERT_CHECK='TRUE';
      NO_DIR_CHECK='TRUE';
      ALLOW_CONNECT='TRUE';
    'VSS78':
      PIN_NUMBER='(0,0,182)';
      PINUSE='POWER';
      NO_LOAD_CHECK='Both';
      NO_IO_CHECK='Both';
      NO_ASSERT_CHECK='TRUE';
      NO_DIR_CHECK='TRUE';
      ALLOW_CONNECT='TRUE';
    'VSS79':
      PIN_NUMBER='(0,0,184)';
      PINUSE='POWER';
      NO_LOAD_CHECK='Both';
      NO_IO_CHECK='Both';
      NO_ASSERT_CHECK='TRUE';
      NO_DIR_CHECK='TRUE';
      ALLOW_CONNECT='TRUE';
    'VSS80':
      PIN_NUMBER='(0,0,186)';
      PINUSE='POWER';
      NO_LOAD_CHECK='Both';
      NO_IO_CHECK='Both';
      NO_ASSERT_CHECK='TRUE';
      NO_DIR_CHECK='TRUE';
      ALLOW_CONNECT='TRUE';
    'VSS81':
      PIN_NUMBER='(0,0,188)';
      PINUSE='POWER';
      NO_LOAD_CHECK='Both';
      NO_IO_CHECK='Both';
      NO_ASSERT_CHECK='TRUE';
      NO_DIR_CHECK='TRUE';
      ALLOW_CONNECT='TRUE';
    'VSS82':
      PIN_NUMBER='(0,0,191)';
      PINUSE='POWER';
      NO_LOAD_CHECK='Both';
      NO_IO_CHECK='Both';
      NO_ASSERT_CHECK='TRUE';
      NO_DIR_CHECK='TRUE';
      ALLOW_CONNECT='TRUE';
    'VSS83':
      PIN_NUMBER='(0,0,193)';
      PINUSE='POWER';
      NO_LOAD_CHECK='Both';
      NO_IO_CHECK='Both';
      NO_ASSERT_CHECK='TRUE';
      NO_DIR_CHECK='TRUE';
      ALLOW_CONNECT='TRUE';
    'VSS84':
      PIN_NUMBER='(0,0,195)';
      PINUSE='POWER';
      NO_LOAD_CHECK='Both';
      NO_IO_CHECK='Both';
      NO_ASSERT_CHECK='TRUE';
      NO_DIR_CHECK='TRUE';
      ALLOW_CONNECT='TRUE';
    'VSS85':
      PIN_NUMBER='(0,0,197)';
      PINUSE='POWER';
      NO_LOAD_CHECK='Both';
      NO_IO_CHECK='Both';
      NO_ASSERT_CHECK='TRUE';
      NO_DIR_CHECK='TRUE';
      ALLOW_CONNECT='TRUE';
    'VSS86':
      PIN_NUMBER='(0,0,199)';
      PINUSE='POWER';
      NO_LOAD_CHECK='Both';
      NO_IO_CHECK='Both';
      NO_ASSERT_CHECK='TRUE';
      NO_DIR_CHECK='TRUE';
      ALLOW_CONNECT='TRUE';
    'VSS87':
      PIN_NUMBER='(0,0,202)';
      PINUSE='POWER';
      NO_LOAD_CHECK='Both';
      NO_IO_CHECK='Both';
      NO_ASSERT_CHECK='TRUE';
      NO_DIR_CHECK='TRUE';
      ALLOW_CONNECT='TRUE';
    'VSS88':
      PIN_NUMBER='(0,0,204)';
      PINUSE='POWER';
      NO_LOAD_CHECK='Both';
      NO_IO_CHECK='Both';
      NO_ASSERT_CHECK='TRUE';
      NO_DIR_CHECK='TRUE';
      ALLOW_CONNECT='TRUE';
    'VSS89':
      PIN_NUMBER='(0,0,206)';
      PINUSE='POWER';
      NO_LOAD_CHECK='Both';
      NO_IO_CHECK='Both';
      NO_ASSERT_CHECK='TRUE';
      NO_DIR_CHECK='TRUE';
      ALLOW_CONNECT='TRUE';
    'VSS90':
      PIN_NUMBER='(0,0,208)';
      PINUSE='POWER';
      NO_LOAD_CHECK='Both';
      NO_IO_CHECK='Both';
      NO_ASSERT_CHECK='TRUE';
      NO_DIR_CHECK='TRUE';
      ALLOW_CONNECT='TRUE';
    'VSS91':
      PIN_NUMBER='(0,0,210)';
      PINUSE='POWER';
      NO_LOAD_CHECK='Both';
      NO_IO_CHECK='Both';
      NO_ASSERT_CHECK='TRUE';
      NO_DIR_CHECK='TRUE';
      ALLOW_CONNECT='TRUE';
    'VSS92':
      PIN_NUMBER='(0,0,212)';
      PINUSE='POWER';
      NO_LOAD_CHECK='Both';
      NO_IO_CHECK='Both';
      NO_ASSERT_CHECK='TRUE';
      NO_DIR_CHECK='TRUE';
      ALLOW_CONNECT='TRUE';
    'VSS93':
      PIN_NUMBER='(0,0,214)';
      PINUSE='POWER';
      NO_LOAD_CHECK='Both';
      NO_IO_CHECK='Both';
      NO_ASSERT_CHECK='TRUE';
      NO_DIR_CHECK='TRUE';
      ALLOW_CONNECT='TRUE';
    'VSS94':
      PIN_NUMBER='(0,0,216)';
      PINUSE='POWER';
      NO_LOAD_CHECK='Both';
      NO_IO_CHECK='Both';
      NO_ASSERT_CHECK='TRUE';
      NO_DIR_CHECK='TRUE';
      ALLOW_CONNECT='TRUE';
    'VSS95':
      PIN_NUMBER='(0,0,219)';
      PINUSE='POWER';
      NO_LOAD_CHECK='Both';
      NO_IO_CHECK='Both';
      NO_ASSERT_CHECK='TRUE';
      NO_DIR_CHECK='TRUE';
      ALLOW_CONNECT='TRUE';
    'VSS96':
      PIN_NUMBER='(0,0,222)';
      PINUSE='POWER';
      NO_LOAD_CHECK='Both';
      NO_IO_CHECK='Both';
      NO_ASSERT_CHECK='TRUE';
      NO_DIR_CHECK='TRUE';
      ALLOW_CONNECT='TRUE';
    'VSS97':
      PIN_NUMBER='(0,0,224)';
      PINUSE='POWER';
      NO_LOAD_CHECK='Both';
      NO_IO_CHECK='Both';
      NO_ASSERT_CHECK='TRUE';
      NO_DIR_CHECK='TRUE';
      ALLOW_CONNECT='TRUE';
    'VSS98':
      PIN_NUMBER='(0,0,226)';
      PINUSE='POWER';
      NO_LOAD_CHECK='Both';
      NO_IO_CHECK='Both';
      NO_ASSERT_CHECK='TRUE';
      NO_DIR_CHECK='TRUE';
      ALLOW_CONNECT='TRUE';
    'VSS99':
      PIN_NUMBER='(0,0,228)';
      PINUSE='POWER';
      NO_LOAD_CHECK='Both';
      NO_IO_CHECK='Both';
      NO_ASSERT_CHECK='TRUE';
      NO_DIR_CHECK='TRUE';
      ALLOW_CONNECT='TRUE';
    'VSS101':
      PIN_NUMBER='(0,0,233)';
      PINUSE='POWER';
      NO_LOAD_CHECK='Both';
      NO_IO_CHECK='Both';
      NO_ASSERT_CHECK='TRUE';
      NO_DIR_CHECK='TRUE';
      ALLOW_CONNECT='TRUE';
    'VSS103':
      PIN_NUMBER='(0,0,237)';
      PINUSE='POWER';
      NO_LOAD_CHECK='Both';
      NO_IO_CHECK='Both';
      NO_ASSERT_CHECK='TRUE';
      NO_DIR_CHECK='TRUE';
      ALLOW_CONNECT='TRUE';
    'VSS105':
      PIN_NUMBER='(0,0,242)';
      PINUSE='POWER';
      NO_LOAD_CHECK='Both';
      NO_IO_CHECK='Both';
      NO_ASSERT_CHECK='TRUE';
      NO_DIR_CHECK='TRUE';
      ALLOW_CONNECT='TRUE';
    'VSS106':
      PIN_NUMBER='(0,0,244)';
      PINUSE='POWER';
      NO_LOAD_CHECK='Both';
      NO_IO_CHECK='Both';
      NO_ASSERT_CHECK='TRUE';
      NO_DIR_CHECK='TRUE';
      ALLOW_CONNECT='TRUE';
    'VSS107':
      PIN_NUMBER='(0,0,246)';
      PINUSE='POWER';
      NO_LOAD_CHECK='Both';
      NO_IO_CHECK='Both';
      NO_ASSERT_CHECK='TRUE';
      NO_DIR_CHECK='TRUE';
      ALLOW_CONNECT='TRUE';
    'VSS108':
      PIN_NUMBER='(0,0,248)';
      PINUSE='POWER';
      NO_LOAD_CHECK='Both';
      NO_IO_CHECK='Both';
      NO_ASSERT_CHECK='TRUE';
      NO_DIR_CHECK='TRUE';
      ALLOW_CONNECT='TRUE';
    'VSS109':
      PIN_NUMBER='(0,0,251)';
      PINUSE='POWER';
      NO_LOAD_CHECK='Both';
      NO_IO_CHECK='Both';
      NO_ASSERT_CHECK='TRUE';
      NO_DIR_CHECK='TRUE';
      ALLOW_CONNECT='TRUE';
    'VSS110':
      PIN_NUMBER='(0,0,253)';
      PINUSE='POWER';
      NO_LOAD_CHECK='Both';
      NO_IO_CHECK='Both';
      NO_ASSERT_CHECK='TRUE';
      NO_DIR_CHECK='TRUE';
      ALLOW_CONNECT='TRUE';
    'VSS111':
      PIN_NUMBER='(0,0,255)';
      PINUSE='POWER';
      NO_LOAD_CHECK='Both';
      NO_IO_CHECK='Both';
      NO_ASSERT_CHECK='TRUE';
      NO_DIR_CHECK='TRUE';
      ALLOW_CONNECT='TRUE';
    'VSS112':
      PIN_NUMBER='(0,0,257)';
      PINUSE='POWER';
      NO_LOAD_CHECK='Both';
      NO_IO_CHECK='Both';
      NO_ASSERT_CHECK='TRUE';
      NO_DIR_CHECK='TRUE';
      ALLOW_CONNECT='TRUE';
    'VSS113':
      PIN_NUMBER='(0,0,259)';
      PINUSE='POWER';
      NO_LOAD_CHECK='Both';
      NO_IO_CHECK='Both';
      NO_ASSERT_CHECK='TRUE';
      NO_DIR_CHECK='TRUE';
      ALLOW_CONNECT='TRUE';
    'VSS114':
      PIN_NUMBER='(0,0,262)';
      PINUSE='POWER';
      NO_LOAD_CHECK='Both';
      NO_IO_CHECK='Both';
      NO_ASSERT_CHECK='TRUE';
      NO_DIR_CHECK='TRUE';
      ALLOW_CONNECT='TRUE';
    'VSS115':
      PIN_NUMBER='(0,0,264)';
      PINUSE='POWER';
      NO_LOAD_CHECK='Both';
      NO_IO_CHECK='Both';
      NO_ASSERT_CHECK='TRUE';
      NO_DIR_CHECK='TRUE';
      ALLOW_CONNECT='TRUE';
    'VSS116':
      PIN_NUMBER='(0,0,266)';
      PINUSE='POWER';
      NO_LOAD_CHECK='Both';
      NO_IO_CHECK='Both';
      NO_ASSERT_CHECK='TRUE';
      NO_DIR_CHECK='TRUE';
      ALLOW_CONNECT='TRUE';
    'VSS117':
      PIN_NUMBER='(0,0,268)';
      PINUSE='POWER';
      NO_LOAD_CHECK='Both';
      NO_IO_CHECK='Both';
      NO_ASSERT_CHECK='TRUE';
      NO_DIR_CHECK='TRUE';
      ALLOW_CONNECT='TRUE';
    'VSS118':
      PIN_NUMBER='(0,0,270)';
      PINUSE='POWER';
      NO_LOAD_CHECK='Both';
      NO_IO_CHECK='Both';
      NO_ASSERT_CHECK='TRUE';
      NO_DIR_CHECK='TRUE';
      ALLOW_CONNECT='TRUE';
    'VSS119':
      PIN_NUMBER='(0,0,273)';
      PINUSE='POWER';
      NO_LOAD_CHECK='Both';
      NO_IO_CHECK='Both';
      NO_ASSERT_CHECK='TRUE';
      NO_DIR_CHECK='TRUE';
      ALLOW_CONNECT='TRUE';
    'VSS120':
      PIN_NUMBER='(0,0,275)';
      PINUSE='POWER';
      NO_LOAD_CHECK='Both';
      NO_IO_CHECK='Both';
      NO_ASSERT_CHECK='TRUE';
      NO_DIR_CHECK='TRUE';
      ALLOW_CONNECT='TRUE';
    'VSS121':
      PIN_NUMBER='(0,0,277)';
      PINUSE='POWER';
      NO_LOAD_CHECK='Both';
      NO_IO_CHECK='Both';
      NO_ASSERT_CHECK='TRUE';
      NO_DIR_CHECK='TRUE';
      ALLOW_CONNECT='TRUE';
    'VSS122':
      PIN_NUMBER='(0,0,279)';
      PINUSE='POWER';
      NO_LOAD_CHECK='Both';
      NO_IO_CHECK='Both';
      NO_ASSERT_CHECK='TRUE';
      NO_DIR_CHECK='TRUE';
      ALLOW_CONNECT='TRUE';
    'VSS123':
      PIN_NUMBER='(0,0,281)';
      PINUSE='POWER';
      NO_LOAD_CHECK='Both';
      NO_IO_CHECK='Both';
      NO_ASSERT_CHECK='TRUE';
      NO_DIR_CHECK='TRUE';
      ALLOW_CONNECT='TRUE';
    'VSS124':
      PIN_NUMBER='(0,0,284)';
      PINUSE='POWER';
      NO_LOAD_CHECK='Both';
      NO_IO_CHECK='Both';
      NO_ASSERT_CHECK='TRUE';
      NO_DIR_CHECK='TRUE';
      ALLOW_CONNECT='TRUE';
    'VSS125':
      PIN_NUMBER='(0,0,286)';
      PINUSE='POWER';
      NO_LOAD_CHECK='Both';
      NO_IO_CHECK='Both';
      NO_ASSERT_CHECK='TRUE';
      NO_DIR_CHECK='TRUE';
      ALLOW_CONNECT='TRUE';
    'VSS126':
      PIN_NUMBER='(0,0,288)';
      PINUSE='POWER';
      NO_LOAD_CHECK='Both';
      NO_IO_CHECK='Both';
      NO_ASSERT_CHECK='TRUE';
      NO_DIR_CHECK='TRUE';
      ALLOW_CONNECT='TRUE';
    'VIN_BULK0':
      PIN_NUMBER='(0,0,1)';
      PINUSE='POWER';
      NO_LOAD_CHECK='Both';
      NO_IO_CHECK='Both';
      NO_ASSERT_CHECK='TRUE';
      NO_DIR_CHECK='TRUE';
      ALLOW_CONNECT='TRUE';
    'VIN_BULK1':
      PIN_NUMBER='(0,0,145)';
      PINUSE='POWER';
      NO_LOAD_CHECK='Both';
      NO_IO_CHECK='Both';
      NO_ASSERT_CHECK='TRUE';
      NO_DIR_CHECK='TRUE';
      ALLOW_CONNECT='TRUE';
    'VIN_BULK2':
      PIN_NUMBER='(0,0,146)';
      PINUSE='POWER';
      NO_LOAD_CHECK='Both';
      NO_IO_CHECK='Both';
      NO_ASSERT_CHECK='TRUE';
      NO_DIR_CHECK='TRUE';
      ALLOW_CONNECT='TRUE';
    'VSS100':
      PIN_NUMBER='(0,0,230)';
      PINUSE='POWER';
      NO_LOAD_CHECK='Both';
      NO_IO_CHECK='Both';
      NO_ASSERT_CHECK='TRUE';
      NO_DIR_CHECK='TRUE';
      ALLOW_CONNECT='TRUE';
    'VSS102':
      PIN_NUMBER='(0,0,235)';
      PINUSE='POWER';
      NO_LOAD_CHECK='Both';
      NO_IO_CHECK='Both';
      NO_ASSERT_CHECK='TRUE';
      NO_DIR_CHECK='TRUE';
      ALLOW_CONNECT='TRUE';
    'VSS104':
      PIN_NUMBER='(0,0,240)';
      PINUSE='POWER';
      NO_LOAD_CHECK='Both';
      NO_IO_CHECK='Both';
      NO_ASSERT_CHECK='TRUE';
      NO_DIR_CHECK='TRUE';
      ALLOW_CONNECT='TRUE';
    'VSS58':
      PIN_NUMBER='(0,0,132)';
      PINUSE='POWER';
      NO_LOAD_CHECK='Both';
      NO_IO_CHECK='Both';
      NO_ASSERT_CHECK='TRUE';
      NO_DIR_CHECK='TRUE';
      ALLOW_CONNECT='TRUE';
    'VSS60':
      PIN_NUMBER='(0,0,136)';
      PINUSE='POWER';
      NO_LOAD_CHECK='Both';
      NO_IO_CHECK='Both';
      NO_ASSERT_CHECK='TRUE';
      NO_DIR_CHECK='TRUE';
      ALLOW_CONNECT='TRUE';
    'VSS61':
      PIN_NUMBER='(0,0,139)';
      PINUSE='POWER';
      NO_LOAD_CHECK='Both';
      NO_IO_CHECK='Both';
      NO_ASSERT_CHECK='TRUE';
      NO_DIR_CHECK='TRUE';
      ALLOW_CONNECT='TRUE';
    'VSS62':
      PIN_NUMBER='(0,0,141)';
      PINUSE='POWER';
      NO_LOAD_CHECK='Both';
      NO_IO_CHECK='Both';
      NO_ASSERT_CHECK='TRUE';
      NO_DIR_CHECK='TRUE';
      ALLOW_CONNECT='TRUE';
    'G1':
      PIN_NUMBER='(0,0,G1)';
      PINUSE='POWER';
      NO_LOAD_CHECK='Both';
      NO_IO_CHECK='Both';
      NO_ASSERT_CHECK='TRUE';
      NO_DIR_CHECK='TRUE';
      ALLOW_CONNECT='TRUE';
    'G2':
      PIN_NUMBER='(0,0,G2)';
      PINUSE='POWER';
      NO_LOAD_CHECK='Both';
      NO_IO_CHECK='Both';
      NO_ASSERT_CHECK='TRUE';
      NO_DIR_CHECK='TRUE';
      ALLOW_CONNECT='TRUE';
    'G3':
      PIN_NUMBER='(0,0,G3)';
      PINUSE='POWER';
      NO_LOAD_CHECK='Both';
      NO_IO_CHECK='Both';
      NO_ASSERT_CHECK='TRUE';
      NO_DIR_CHECK='TRUE';
      ALLOW_CONNECT='TRUE';
  end_pin;
  body
      PART_NAME='SCONN288_ADR50017P130CC';
      BODY_NAME='SCONN288_ADR50017P130CC';
      PHYS_DES_PREFIX='J';
      CLASS='IO';
      STANDARD='';
      LIFECYCLE='';
      JEDEC_TYPE='DDR288S_1-1VXB';
      DESCRIPTION='CONN SMD HS DDR5 288P 2R FS(P0.85,H21.3)';
      MANUFTR='LTS';
      MANUF_PN='ADR50017-P130CC';
      RD_CMPLS_LVL='EP(V1)';
      CMPLS_LVL='';
      DIP_SMD='';
      FROM_PJ='F0C-IVES';
      DATA='LTS_ADR50017-P130CC.pdf';
      FP_ECN='ADR50017-P130CC.msg';
      EE_CHECK_LIST='';
      CREATOR='';
      CREATEDAY='20210723';
      PSL='';
      STATUS='';
      ESD_CDM='';
      ESD_HBM='';
      ESD_MM='';
      MSD='';
      PIN_LENGTH_LONG_PIN='81 MILS';
      PIN_LENGTH_SHORT_PIN='81 MILS';
      PARENT_PART_TYPE='SCONN288_ADR50017P130CC';
      PARENT_PPT='SCONN288_ADR50017P130CC';
      PARENT_PPT_PART='SCONN288_ADR50017P130CC-SCONN288_ADR50017-P130CC,SMLF,IO,DFHST8FS461';
  end_body;
end_primitive;
primitive 'SCONN56_123276793-SCONN56_1-23A';
  pin
    'P12V_B1':
      PIN_NUMBER='(B1)';
      PINUSE='POWER';
      NO_LOAD_CHECK='Both';
      NO_IO_CHECK='Both';
      NO_ASSERT_CHECK='TRUE';
      NO_DIR_CHECK='TRUE';
      ALLOW_CONNECT='TRUE';
    'P12V_B2':
      PIN_NUMBER='(B2)';
      PINUSE='POWER';
      NO_LOAD_CHECK='Both';
      NO_IO_CHECK='Both';
      NO_ASSERT_CHECK='TRUE';
      NO_DIR_CHECK='TRUE';
      ALLOW_CONNECT='TRUE';
    'P12V_B3':
      PIN_NUMBER='(B3)';
      PINUSE='POWER';
      NO_LOAD_CHECK='Both';
      NO_IO_CHECK='Both';
      NO_ASSERT_CHECK='TRUE';
      NO_DIR_CHECK='TRUE';
      ALLOW_CONNECT='TRUE';
    'P12V_B4':
      PIN_NUMBER='(B4)';
      PINUSE='POWER';
      NO_LOAD_CHECK='Both';
      NO_IO_CHECK='Both';
      NO_ASSERT_CHECK='TRUE';
      NO_DIR_CHECK='TRUE';
      ALLOW_CONNECT='TRUE';
    'P12V_B5':
      PIN_NUMBER='(B5)';
      PINUSE='POWER';
      NO_LOAD_CHECK='Both';
      NO_IO_CHECK='Both';
      NO_ASSERT_CHECK='TRUE';
      NO_DIR_CHECK='TRUE';
      ALLOW_CONNECT='TRUE';
    'P12V_B6':
      PIN_NUMBER='(B6)';
      PINUSE='POWER';
      NO_LOAD_CHECK='Both';
      NO_IO_CHECK='Both';
      NO_ASSERT_CHECK='TRUE';
      NO_DIR_CHECK='TRUE';
      ALLOW_CONNECT='TRUE';
    'GND_A1':
      PIN_NUMBER='(A1)';
      PINUSE='POWER';
      NO_LOAD_CHECK='Both';
      NO_IO_CHECK='Both';
      NO_ASSERT_CHECK='TRUE';
      NO_DIR_CHECK='TRUE';
      ALLOW_CONNECT='TRUE';
    'GND_A2':
      PIN_NUMBER='(A2)';
      PINUSE='POWER';
      NO_LOAD_CHECK='Both';
      NO_IO_CHECK='Both';
      NO_ASSERT_CHECK='TRUE';
      NO_DIR_CHECK='TRUE';
      ALLOW_CONNECT='TRUE';
    'GND_A3':
      PIN_NUMBER='(A3)';
      PINUSE='POWER';
      NO_LOAD_CHECK='Both';
      NO_IO_CHECK='Both';
      NO_ASSERT_CHECK='TRUE';
      NO_DIR_CHECK='TRUE';
      ALLOW_CONNECT='TRUE';
    'GND_A4':
      PIN_NUMBER='(A4)';
      PINUSE='POWER';
      NO_LOAD_CHECK='Both';
      NO_IO_CHECK='Both';
      NO_ASSERT_CHECK='TRUE';
      NO_DIR_CHECK='TRUE';
      ALLOW_CONNECT='TRUE';
    'GND_A5':
      PIN_NUMBER='(A5)';
      PINUSE='POWER';
      NO_LOAD_CHECK='Both';
      NO_IO_CHECK='Both';
      NO_ASSERT_CHECK='TRUE';
      NO_DIR_CHECK='TRUE';
      ALLOW_CONNECT='TRUE';
    'GND_A6':
      PIN_NUMBER='(A6)';
      PINUSE='POWER';
      NO_LOAD_CHECK='Both';
      NO_IO_CHECK='Both';
      NO_ASSERT_CHECK='TRUE';
      NO_DIR_CHECK='TRUE';
      ALLOW_CONNECT='TRUE';
    'MFG':
      PIN_NUMBER='(B7)';
      BIDIRECTIONAL='TRUE';
      INPUT_LOAD='(-0.01,0.01)';
      OUTPUT_LOAD='(1.0,-1.0)';
      PINUSE='BI';
    'RFU':
      PIN_NUMBER='(B8)';
      BIDIRECTIONAL='TRUE';
      INPUT_LOAD='(-0.01,0.01)';
      OUTPUT_LOAD='(1.0,-1.0)';
      PINUSE='BI';
    'DUALPORTEN#':
      PIN_NUMBER='(B9)';
      BIDIRECTIONAL='TRUE';
      INPUT_LOAD='(-0.01,0.01)';
      OUTPUT_LOAD='(1.0,-1.0)';
      PINUSE='BI';
    'P3V3_AUX':
      PIN_NUMBER='(B11)';
      PINUSE='POWER';
      NO_LOAD_CHECK='Both';
      NO_IO_CHECK='Both';
      NO_ASSERT_CHECK='TRUE';
      NO_DIR_CHECK='TRUE';
      ALLOW_CONNECT='TRUE';
    'PWRDIS':
      PIN_NUMBER='(B12)';
      BIDIRECTIONAL='TRUE';
      INPUT_LOAD='(-0.01,0.01)';
      OUTPUT_LOAD='(1.0,-1.0)';
      PINUSE='BI';
    'GND_B13':
      PIN_NUMBER='(B13)';
      PINUSE='POWER';
      NO_LOAD_CHECK='Both';
      NO_IO_CHECK='Both';
      NO_ASSERT_CHECK='TRUE';
      NO_DIR_CHECK='TRUE';
      ALLOW_CONNECT='TRUE';
    'GND_B16':
      PIN_NUMBER='(B16)';
      PINUSE='POWER';
      NO_LOAD_CHECK='Both';
      NO_IO_CHECK='Both';
      NO_ASSERT_CHECK='TRUE';
      NO_DIR_CHECK='TRUE';
      ALLOW_CONNECT='TRUE';
    'GND_B19':
      PIN_NUMBER='(B19)';
      PINUSE='POWER';
      NO_LOAD_CHECK='Both';
      NO_IO_CHECK='Both';
      NO_ASSERT_CHECK='TRUE';
      NO_DIR_CHECK='TRUE';
      ALLOW_CONNECT='TRUE';
    'GND_B22':
      PIN_NUMBER='(B22)';
      PINUSE='POWER';
      NO_LOAD_CHECK='Both';
      NO_IO_CHECK='Both';
      NO_ASSERT_CHECK='TRUE';
      NO_DIR_CHECK='TRUE';
      ALLOW_CONNECT='TRUE';
    'GND_B25':
      PIN_NUMBER='(B25)';
      PINUSE='POWER';
      NO_LOAD_CHECK='Both';
      NO_IO_CHECK='Both';
      NO_ASSERT_CHECK='TRUE';
      NO_DIR_CHECK='TRUE';
      ALLOW_CONNECT='TRUE';
    'GND_B28':
      PIN_NUMBER='(B28)';
      PINUSE='POWER';
      NO_LOAD_CHECK='Both';
      NO_IO_CHECK='Both';
      NO_ASSERT_CHECK='TRUE';
      NO_DIR_CHECK='TRUE';
      ALLOW_CONNECT='TRUE';
    'REFCLK_N0':
      PIN_NUMBER='(B14)';
      BIDIRECTIONAL='TRUE';
      INPUT_LOAD='(-0.01,0.01)';
      OUTPUT_LOAD='(1.0,-1.0)';
      PINUSE='BI';
    'REFCLK_P0':
      PIN_NUMBER='(B15)';
      BIDIRECTIONAL='TRUE';
      INPUT_LOAD='(-0.01,0.01)';
      OUTPUT_LOAD='(1.0,-1.0)';
      PINUSE='BI';
    'PET_N0':
      PIN_NUMBER='(B17)';
      BIDIRECTIONAL='TRUE';
      INPUT_LOAD='(-0.01,0.01)';
      OUTPUT_LOAD='(1.0,-1.0)';
      PINUSE='BI';
    'PET_P0':
      PIN_NUMBER='(B18)';
      BIDIRECTIONAL='TRUE';
      INPUT_LOAD='(-0.01,0.01)';
      OUTPUT_LOAD='(1.0,-1.0)';
      PINUSE='BI';
    'PET_N1':
      PIN_NUMBER='(B20)';
      BIDIRECTIONAL='TRUE';
      INPUT_LOAD='(-0.01,0.01)';
      OUTPUT_LOAD='(1.0,-1.0)';
      PINUSE='BI';
    'PET_P1':
      PIN_NUMBER='(B21)';
      BIDIRECTIONAL='TRUE';
      INPUT_LOAD='(-0.01,0.01)';
      OUTPUT_LOAD='(1.0,-1.0)';
      PINUSE='BI';
    'PET_N2':
      PIN_NUMBER='(B23)';
      BIDIRECTIONAL='TRUE';
      INPUT_LOAD='(-0.01,0.01)';
      OUTPUT_LOAD='(1.0,-1.0)';
      PINUSE='BI';
    'PET_P2':
      PIN_NUMBER='(B24)';
      BIDIRECTIONAL='TRUE';
      INPUT_LOAD='(-0.01,0.01)';
      OUTPUT_LOAD='(1.0,-1.0)';
      PINUSE='BI';
    'PET_N3':
      PIN_NUMBER='(B26)';
      BIDIRECTIONAL='TRUE';
      INPUT_LOAD='(-0.01,0.01)';
      OUTPUT_LOAD='(1.0,-1.0)';
      PINUSE='BI';
    'PET_P3':
      PIN_NUMBER='(B27)';
      BIDIRECTIONAL='TRUE';
      INPUT_LOAD='(-0.01,0.01)';
      OUTPUT_LOAD='(1.0,-1.0)';
      PINUSE='BI';
    'SMBCLK':
      PIN_NUMBER='(A7)';
      BIDIRECTIONAL='TRUE';
      INPUT_LOAD='(-0.01,0.01)';
      OUTPUT_LOAD='(1.0,-1.0)';
      PINUSE='BI';
    'SMBDAT':
      PIN_NUMBER='(A8)';
      BIDIRECTIONAL='TRUE';
      INPUT_LOAD='(-0.01,0.01)';
      OUTPUT_LOAD='(1.0,-1.0)';
      PINUSE='BI';
    'SMBRST#':
      PIN_NUMBER='(A9)';
      BIDIRECTIONAL='TRUE';
      INPUT_LOAD='(-0.01,0.01)';
      OUTPUT_LOAD='(1.0,-1.0)';
      PINUSE='BI';
    'LED#_ACTIVITY':
      PIN_NUMBER='(A10)';
      BIDIRECTIONAL='TRUE';
      INPUT_LOAD='(-0.01,0.01)';
      OUTPUT_LOAD='(1.0,-1.0)';
      PINUSE='BI';
    'PERST0#':
      PIN_NUMBER='(B10)';
      BIDIRECTIONAL='TRUE';
      INPUT_LOAD='(-0.01,0.01)';
      OUTPUT_LOAD='(1.0,-1.0)';
      PINUSE='BI';
    'PERST1#_CLKREQ#':
      PIN_NUMBER='(A11)';
      BIDIRECTIONAL='TRUE';
      INPUT_LOAD='(-0.01,0.01)';
      OUTPUT_LOAD='(1.0,-1.0)';
      PINUSE='BI';
    'PRSNT0#':
      PIN_NUMBER='(A12)';
      BIDIRECTIONAL='TRUE';
      INPUT_LOAD='(-0.01,0.01)';
      OUTPUT_LOAD='(1.0,-1.0)';
      PINUSE='BI';
    'GND_A13':
      PIN_NUMBER='(A13)';
      PINUSE='POWER';
      NO_LOAD_CHECK='Both';
      NO_IO_CHECK='Both';
      NO_ASSERT_CHECK='TRUE';
      NO_DIR_CHECK='TRUE';
      ALLOW_CONNECT='TRUE';
    'GND_A16':
      PIN_NUMBER='(A16)';
      PINUSE='POWER';
      NO_LOAD_CHECK='Both';
      NO_IO_CHECK='Both';
      NO_ASSERT_CHECK='TRUE';
      NO_DIR_CHECK='TRUE';
      ALLOW_CONNECT='TRUE';
    'GND_A19':
      PIN_NUMBER='(A19)';
      PINUSE='POWER';
      NO_LOAD_CHECK='Both';
      NO_IO_CHECK='Both';
      NO_ASSERT_CHECK='TRUE';
      NO_DIR_CHECK='TRUE';
      ALLOW_CONNECT='TRUE';
    'GND_A22':
      PIN_NUMBER='(A22)';
      PINUSE='POWER';
      NO_LOAD_CHECK='Both';
      NO_IO_CHECK='Both';
      NO_ASSERT_CHECK='TRUE';
      NO_DIR_CHECK='TRUE';
      ALLOW_CONNECT='TRUE';
    'GND_A25':
      PIN_NUMBER='(A25)';
      PINUSE='POWER';
      NO_LOAD_CHECK='Both';
      NO_IO_CHECK='Both';
      NO_ASSERT_CHECK='TRUE';
      NO_DIR_CHECK='TRUE';
      ALLOW_CONNECT='TRUE';
    'GND_A28':
      PIN_NUMBER='(A28)';
      PINUSE='POWER';
      NO_LOAD_CHECK='Both';
      NO_IO_CHECK='Both';
      NO_ASSERT_CHECK='TRUE';
      NO_DIR_CHECK='TRUE';
      ALLOW_CONNECT='TRUE';
    'REFCLK_N1':
      PIN_NUMBER='(A14)';
      BIDIRECTIONAL='TRUE';
      INPUT_LOAD='(-0.01,0.01)';
      OUTPUT_LOAD='(1.0,-1.0)';
      PINUSE='BI';
    'REFCLK_P1':
      PIN_NUMBER='(A15)';
      BIDIRECTIONAL='TRUE';
      INPUT_LOAD='(-0.01,0.01)';
      OUTPUT_LOAD='(1.0,-1.0)';
      PINUSE='BI';
    'PER_N0':
      PIN_NUMBER='(A17)';
      BIDIRECTIONAL='TRUE';
      INPUT_LOAD='(-0.01,0.01)';
      OUTPUT_LOAD='(1.0,-1.0)';
      PINUSE='BI';
    'PER_P0':
      PIN_NUMBER='(A18)';
      BIDIRECTIONAL='TRUE';
      INPUT_LOAD='(-0.01,0.01)';
      OUTPUT_LOAD='(1.0,-1.0)';
      PINUSE='BI';
    'PER_N1':
      PIN_NUMBER='(A20)';
      BIDIRECTIONAL='TRUE';
      INPUT_LOAD='(-0.01,0.01)';
      OUTPUT_LOAD='(1.0,-1.0)';
      PINUSE='BI';
    'PER_P1':
      PIN_NUMBER='(A21)';
      BIDIRECTIONAL='TRUE';
      INPUT_LOAD='(-0.01,0.01)';
      OUTPUT_LOAD='(1.0,-1.0)';
      PINUSE='BI';
    'PER_N2':
      PIN_NUMBER='(A23)';
      BIDIRECTIONAL='TRUE';
      INPUT_LOAD='(-0.01,0.01)';
      OUTPUT_LOAD='(1.0,-1.0)';
      PINUSE='BI';
    'PER_P2':
      PIN_NUMBER='(A24)';
      BIDIRECTIONAL='TRUE';
      INPUT_LOAD='(-0.01,0.01)';
      OUTPUT_LOAD='(1.0,-1.0)';
      PINUSE='BI';
    'PER_N3':
      PIN_NUMBER='(A26)';
      BIDIRECTIONAL='TRUE';
      INPUT_LOAD='(-0.01,0.01)';
      OUTPUT_LOAD='(1.0,-1.0)';
      PINUSE='BI';
    'PER_P3':
      PIN_NUMBER='(A27)';
      BIDIRECTIONAL='TRUE';
      INPUT_LOAD='(-0.01,0.01)';
      OUTPUT_LOAD='(1.0,-1.0)';
      PINUSE='BI';
    'G2':
      PIN_NUMBER='(G2)';
      PINUSE='POWER';
      NO_LOAD_CHECK='Both';
      NO_IO_CHECK='Both';
      NO_ASSERT_CHECK='TRUE';
      NO_DIR_CHECK='TRUE';
      ALLOW_CONNECT='TRUE';
    'G1':
      PIN_NUMBER='(G1)';
      PINUSE='POWER';
      NO_LOAD_CHECK='Both';
      NO_IO_CHECK='Both';
      NO_ASSERT_CHECK='TRUE';
      NO_DIR_CHECK='TRUE';
      ALLOW_CONNECT='TRUE';
  end_pin;
  body
      PART_NAME='SCONN56_123276793';
      BODY_NAME='SCONN56_123276793';
      PHYS_DES_PREFIX='J';
      CLASS='IO';
      NC_PINS='(H1,H2)';
      STANDARD='';
      LIFECYCLE='';
      JEDEC_TYPE='CON_F56S2H4D_P0-6W4-6_LUHXA';
      DESCRIPTION='CONN SMD HOUSING 56P 2R FS(P0.6, H9.25)';
      MANUFTR='TYC';
      MANUF_PN='1-2327679-3';
      RD_CMPLS_LVL='EP(V1)';
      CMPLS_LVL='';
      DIP_SMD='';
      FROM_PJ='S9NS-NICK';
      DATA='TYC_1-2327679-3.pdf';
      FP_ECN='';
      EE_CHECK_LIST='';
      CREATOR='';
      CREATEDAY='20190104';
      PSL='';
      STATUS='';
      ESD_CDM='NA';
      ESD_HBM='NA';
      ESD_MM='NA';
      MSD='NA';
      PIN_LENGTH_LONG_PIN='67 MILS';
      PIN_LENGTH_SHORT_PIN='56 MILS';
      PARENT_PART_TYPE='SCONN56_123276793';
      PARENT_PPT='SCONN56_123276793';
      PARENT_PPT_PART='SCONN56_123276793-SCONN56_1-2327679-3,SMLF,IO,DFHS56FS022';
  end_body;
end_primitive;
primitive 'SCONN60_ASP21410801-SCONN60_ASA';
  pin
    '1':
      PIN_NUMBER='(1)';
      BIDIRECTIONAL='TRUE';
      INPUT_LOAD='(-0.01,0.01)';
      OUTPUT_LOAD='(1.0,-1.0)';
      PINUSE='BI';
    '2':
      PIN_NUMBER='(2)';
      BIDIRECTIONAL='TRUE';
      INPUT_LOAD='(-0.01,0.01)';
      OUTPUT_LOAD='(1.0,-1.0)';
      PINUSE='BI';
    '3':
      PIN_NUMBER='(3)';
      BIDIRECTIONAL='TRUE';
      INPUT_LOAD='(-0.01,0.01)';
      OUTPUT_LOAD='(1.0,-1.0)';
      PINUSE='BI';
    '4':
      PIN_NUMBER='(4)';
      BIDIRECTIONAL='TRUE';
      INPUT_LOAD='(-0.01,0.01)';
      OUTPUT_LOAD='(1.0,-1.0)';
      PINUSE='BI';
    '5':
      PIN_NUMBER='(5)';
      BIDIRECTIONAL='TRUE';
      INPUT_LOAD='(-0.01,0.01)';
      OUTPUT_LOAD='(1.0,-1.0)';
      PINUSE='BI';
    '6':
      PIN_NUMBER='(6)';
      BIDIRECTIONAL='TRUE';
      INPUT_LOAD='(-0.01,0.01)';
      OUTPUT_LOAD='(1.0,-1.0)';
      PINUSE='BI';
    '7':
      PIN_NUMBER='(7)';
      BIDIRECTIONAL='TRUE';
      INPUT_LOAD='(-0.01,0.01)';
      OUTPUT_LOAD='(1.0,-1.0)';
      PINUSE='BI';
    '8':
      PIN_NUMBER='(8)';
      BIDIRECTIONAL='TRUE';
      INPUT_LOAD='(-0.01,0.01)';
      OUTPUT_LOAD='(1.0,-1.0)';
      PINUSE='BI';
    '9':
      PIN_NUMBER='(9)';
      BIDIRECTIONAL='TRUE';
      INPUT_LOAD='(-0.01,0.01)';
      OUTPUT_LOAD='(1.0,-1.0)';
      PINUSE='BI';
    '10':
      PIN_NUMBER='(10)';
      BIDIRECTIONAL='TRUE';
      INPUT_LOAD='(-0.01,0.01)';
      OUTPUT_LOAD='(1.0,-1.0)';
      PINUSE='BI';
    '11':
      PIN_NUMBER='(11)';
      BIDIRECTIONAL='TRUE';
      INPUT_LOAD='(-0.01,0.01)';
      OUTPUT_LOAD='(1.0,-1.0)';
      PINUSE='BI';
    '12':
      PIN_NUMBER='(12)';
      BIDIRECTIONAL='TRUE';
      INPUT_LOAD='(-0.01,0.01)';
      OUTPUT_LOAD='(1.0,-1.0)';
      PINUSE='BI';
    '13':
      PIN_NUMBER='(13)';
      BIDIRECTIONAL='TRUE';
      INPUT_LOAD='(-0.01,0.01)';
      OUTPUT_LOAD='(1.0,-1.0)';
      PINUSE='BI';
    '14':
      PIN_NUMBER='(14)';
      BIDIRECTIONAL='TRUE';
      INPUT_LOAD='(-0.01,0.01)';
      OUTPUT_LOAD='(1.0,-1.0)';
      PINUSE='BI';
    '15':
      PIN_NUMBER='(15)';
      BIDIRECTIONAL='TRUE';
      INPUT_LOAD='(-0.01,0.01)';
      OUTPUT_LOAD='(1.0,-1.0)';
      PINUSE='BI';
    '16':
      PIN_NUMBER='(16)';
      BIDIRECTIONAL='TRUE';
      INPUT_LOAD='(-0.01,0.01)';
      OUTPUT_LOAD='(1.0,-1.0)';
      PINUSE='BI';
    '17':
      PIN_NUMBER='(17)';
      BIDIRECTIONAL='TRUE';
      INPUT_LOAD='(-0.01,0.01)';
      OUTPUT_LOAD='(1.0,-1.0)';
      PINUSE='BI';
    '18':
      PIN_NUMBER='(18)';
      BIDIRECTIONAL='TRUE';
      INPUT_LOAD='(-0.01,0.01)';
      OUTPUT_LOAD='(1.0,-1.0)';
      PINUSE='BI';
    '19':
      PIN_NUMBER='(19)';
      BIDIRECTIONAL='TRUE';
      INPUT_LOAD='(-0.01,0.01)';
      OUTPUT_LOAD='(1.0,-1.0)';
      PINUSE='BI';
    '20':
      PIN_NUMBER='(20)';
      BIDIRECTIONAL='TRUE';
      INPUT_LOAD='(-0.01,0.01)';
      OUTPUT_LOAD='(1.0,-1.0)';
      PINUSE='BI';
    '21':
      PIN_NUMBER='(21)';
      BIDIRECTIONAL='TRUE';
      INPUT_LOAD='(-0.01,0.01)';
      OUTPUT_LOAD='(1.0,-1.0)';
      PINUSE='BI';
    '22':
      PIN_NUMBER='(22)';
      BIDIRECTIONAL='TRUE';
      INPUT_LOAD='(-0.01,0.01)';
      OUTPUT_LOAD='(1.0,-1.0)';
      PINUSE='BI';
    '23':
      PIN_NUMBER='(23)';
      BIDIRECTIONAL='TRUE';
      INPUT_LOAD='(-0.01,0.01)';
      OUTPUT_LOAD='(1.0,-1.0)';
      PINUSE='BI';
    '24':
      PIN_NUMBER='(24)';
      BIDIRECTIONAL='TRUE';
      INPUT_LOAD='(-0.01,0.01)';
      OUTPUT_LOAD='(1.0,-1.0)';
      PINUSE='BI';
    '25':
      PIN_NUMBER='(25)';
      BIDIRECTIONAL='TRUE';
      INPUT_LOAD='(-0.01,0.01)';
      OUTPUT_LOAD='(1.0,-1.0)';
      PINUSE='BI';
    '26':
      PIN_NUMBER='(26)';
      BIDIRECTIONAL='TRUE';
      INPUT_LOAD='(-0.01,0.01)';
      OUTPUT_LOAD='(1.0,-1.0)';
      PINUSE='BI';
    '27':
      PIN_NUMBER='(27)';
      BIDIRECTIONAL='TRUE';
      INPUT_LOAD='(-0.01,0.01)';
      OUTPUT_LOAD='(1.0,-1.0)';
      PINUSE='BI';
    '28':
      PIN_NUMBER='(28)';
      BIDIRECTIONAL='TRUE';
      INPUT_LOAD='(-0.01,0.01)';
      OUTPUT_LOAD='(1.0,-1.0)';
      PINUSE='BI';
    '30':
      PIN_NUMBER='(30)';
      BIDIRECTIONAL='TRUE';
      INPUT_LOAD='(-0.01,0.01)';
      OUTPUT_LOAD='(1.0,-1.0)';
      PINUSE='BI';
    '29':
      PIN_NUMBER='(29)';
      BIDIRECTIONAL='TRUE';
      INPUT_LOAD='(-0.01,0.01)';
      OUTPUT_LOAD='(1.0,-1.0)';
      PINUSE='BI';
    '31':
      PIN_NUMBER='(31)';
      BIDIRECTIONAL='TRUE';
      INPUT_LOAD='(-0.01,0.01)';
      OUTPUT_LOAD='(1.0,-1.0)';
      PINUSE='BI';
    '32':
      PIN_NUMBER='(32)';
      BIDIRECTIONAL='TRUE';
      INPUT_LOAD='(-0.01,0.01)';
      OUTPUT_LOAD='(1.0,-1.0)';
      PINUSE='BI';
    '33':
      PIN_NUMBER='(33)';
      BIDIRECTIONAL='TRUE';
      INPUT_LOAD='(-0.01,0.01)';
      OUTPUT_LOAD='(1.0,-1.0)';
      PINUSE='BI';
    '34':
      PIN_NUMBER='(34)';
      BIDIRECTIONAL='TRUE';
      INPUT_LOAD='(-0.01,0.01)';
      OUTPUT_LOAD='(1.0,-1.0)';
      PINUSE='BI';
    '35':
      PIN_NUMBER='(35)';
      BIDIRECTIONAL='TRUE';
      INPUT_LOAD='(-0.01,0.01)';
      OUTPUT_LOAD='(1.0,-1.0)';
      PINUSE='BI';
    '36':
      PIN_NUMBER='(36)';
      BIDIRECTIONAL='TRUE';
      INPUT_LOAD='(-0.01,0.01)';
      OUTPUT_LOAD='(1.0,-1.0)';
      PINUSE='BI';
    '37':
      PIN_NUMBER='(37)';
      BIDIRECTIONAL='TRUE';
      INPUT_LOAD='(-0.01,0.01)';
      OUTPUT_LOAD='(1.0,-1.0)';
      PINUSE='BI';
    '38':
      PIN_NUMBER='(38)';
      BIDIRECTIONAL='TRUE';
      INPUT_LOAD='(-0.01,0.01)';
      OUTPUT_LOAD='(1.0,-1.0)';
      PINUSE='BI';
    '39':
      PIN_NUMBER='(39)';
      BIDIRECTIONAL='TRUE';
      INPUT_LOAD='(-0.01,0.01)';
      OUTPUT_LOAD='(1.0,-1.0)';
      PINUSE='BI';
    '40':
      PIN_NUMBER='(40)';
      BIDIRECTIONAL='TRUE';
      INPUT_LOAD='(-0.01,0.01)';
      OUTPUT_LOAD='(1.0,-1.0)';
      PINUSE='BI';
    '41':
      PIN_NUMBER='(41)';
      BIDIRECTIONAL='TRUE';
      INPUT_LOAD='(-0.01,0.01)';
      OUTPUT_LOAD='(1.0,-1.0)';
      PINUSE='BI';
    '42':
      PIN_NUMBER='(42)';
      BIDIRECTIONAL='TRUE';
      INPUT_LOAD='(-0.01,0.01)';
      OUTPUT_LOAD='(1.0,-1.0)';
      PINUSE='BI';
    '43':
      PIN_NUMBER='(43)';
      BIDIRECTIONAL='TRUE';
      INPUT_LOAD='(-0.01,0.01)';
      OUTPUT_LOAD='(1.0,-1.0)';
      PINUSE='BI';
    '44':
      PIN_NUMBER='(44)';
      BIDIRECTIONAL='TRUE';
      INPUT_LOAD='(-0.01,0.01)';
      OUTPUT_LOAD='(1.0,-1.0)';
      PINUSE='BI';
    '45':
      PIN_NUMBER='(45)';
      BIDIRECTIONAL='TRUE';
      INPUT_LOAD='(-0.01,0.01)';
      OUTPUT_LOAD='(1.0,-1.0)';
      PINUSE='BI';
    '46':
      PIN_NUMBER='(46)';
      BIDIRECTIONAL='TRUE';
      INPUT_LOAD='(-0.01,0.01)';
      OUTPUT_LOAD='(1.0,-1.0)';
      PINUSE='BI';
    '47':
      PIN_NUMBER='(47)';
      BIDIRECTIONAL='TRUE';
      INPUT_LOAD='(-0.01,0.01)';
      OUTPUT_LOAD='(1.0,-1.0)';
      PINUSE='BI';
    '48':
      PIN_NUMBER='(48)';
      BIDIRECTIONAL='TRUE';
      INPUT_LOAD='(-0.01,0.01)';
      OUTPUT_LOAD='(1.0,-1.0)';
      PINUSE='BI';
    '49':
      PIN_NUMBER='(49)';
      BIDIRECTIONAL='TRUE';
      INPUT_LOAD='(-0.01,0.01)';
      OUTPUT_LOAD='(1.0,-1.0)';
      PINUSE='BI';
    '50':
      PIN_NUMBER='(50)';
      BIDIRECTIONAL='TRUE';
      INPUT_LOAD='(-0.01,0.01)';
      OUTPUT_LOAD='(1.0,-1.0)';
      PINUSE='BI';
    '51':
      PIN_NUMBER='(51)';
      BIDIRECTIONAL='TRUE';
      INPUT_LOAD='(-0.01,0.01)';
      OUTPUT_LOAD='(1.0,-1.0)';
      PINUSE='BI';
    '52':
      PIN_NUMBER='(52)';
      BIDIRECTIONAL='TRUE';
      INPUT_LOAD='(-0.01,0.01)';
      OUTPUT_LOAD='(1.0,-1.0)';
      PINUSE='BI';
    '53':
      PIN_NUMBER='(53)';
      BIDIRECTIONAL='TRUE';
      INPUT_LOAD='(-0.01,0.01)';
      OUTPUT_LOAD='(1.0,-1.0)';
      PINUSE='BI';
    '54':
      PIN_NUMBER='(54)';
      BIDIRECTIONAL='TRUE';
      INPUT_LOAD='(-0.01,0.01)';
      OUTPUT_LOAD='(1.0,-1.0)';
      PINUSE='BI';
    '55':
      PIN_NUMBER='(55)';
      BIDIRECTIONAL='TRUE';
      INPUT_LOAD='(-0.01,0.01)';
      OUTPUT_LOAD='(1.0,-1.0)';
      PINUSE='BI';
    '56':
      PIN_NUMBER='(56)';
      BIDIRECTIONAL='TRUE';
      INPUT_LOAD='(-0.01,0.01)';
      OUTPUT_LOAD='(1.0,-1.0)';
      PINUSE='BI';
    '57':
      PIN_NUMBER='(57)';
      BIDIRECTIONAL='TRUE';
      INPUT_LOAD='(-0.01,0.01)';
      OUTPUT_LOAD='(1.0,-1.0)';
      PINUSE='BI';
    '58':
      PIN_NUMBER='(58)';
      BIDIRECTIONAL='TRUE';
      INPUT_LOAD='(-0.01,0.01)';
      OUTPUT_LOAD='(1.0,-1.0)';
      PINUSE='BI';
    '59':
      PIN_NUMBER='(59)';
      BIDIRECTIONAL='TRUE';
      INPUT_LOAD='(-0.01,0.01)';
      OUTPUT_LOAD='(1.0,-1.0)';
      PINUSE='BI';
    '60':
      PIN_NUMBER='(60)';
      BIDIRECTIONAL='TRUE';
      INPUT_LOAD='(-0.01,0.01)';
      OUTPUT_LOAD='(1.0,-1.0)';
      PINUSE='BI';
    'G1':
      PIN_NUMBER='(G1)';
      PINUSE='POWER';
      NO_LOAD_CHECK='Both';
      NO_IO_CHECK='Both';
      NO_ASSERT_CHECK='TRUE';
      NO_DIR_CHECK='TRUE';
      ALLOW_CONNECT='TRUE';
    'G2':
      PIN_NUMBER='(G2)';
      PINUSE='POWER';
      NO_LOAD_CHECK='Both';
      NO_IO_CHECK='Both';
      NO_ASSERT_CHECK='TRUE';
      NO_DIR_CHECK='TRUE';
      ALLOW_CONNECT='TRUE';
    'G3':
      PIN_NUMBER='(G3)';
      PINUSE='POWER';
      NO_LOAD_CHECK='Both';
      NO_IO_CHECK='Both';
      NO_ASSERT_CHECK='TRUE';
      NO_DIR_CHECK='TRUE';
      ALLOW_CONNECT='TRUE';
    'G4':
      PIN_NUMBER='(G4)';
      PINUSE='POWER';
      NO_LOAD_CHECK='Both';
      NO_IO_CHECK='Both';
      NO_ASSERT_CHECK='TRUE';
      NO_DIR_CHECK='TRUE';
      ALLOW_CONNECT='TRUE';
  end_pin;
  body
      PART_NAME='SCONN60_ASP21410801';
      BODY_NAME='SCONN60_ASP21410801';
      PHYS_DES_PREFIX='J';
      CLASS='IO';
      NC_PINS='(H1,H2)';
      STANDARD='';
      LIFECYCLE='';
      JEDEC_TYPE='CON_60S2H2D4S_P0-5_LDV';
      DESCRIPTION='CONN SMD HOUSING 60P 2R FS(P0.5,H3.05)';
      MANUFTR='STC';
      MANUF_PN='ASP-214108-01';
      RD_CMPLS_LVL='EP(V1)';
      CMPLS_LVL='EP(V1)';
      DIP_SMD='';
      FROM_PJ='F0C-IVES';
      DATA='STC_ASP-214108-01.pdf';
      FP_ECN='ASP-214108-01.msg';
      EE_CHECK_LIST='';
      CREATOR='';
      CREATEDAY='20210127';
      PSL='';
      STATUS='';
      ESD_CDM='0';
      ESD_HBM='0';
      ESD_MM='0';
      MSD='NA';
      PIN_LENGTH_LONG_PIN='30 MILS';
      PIN_LENGTH_SHORT_PIN='30 MILS';
      PARENT_PART_TYPE='SCONN60_ASP21410801';
      PARENT_PPT='SCONN60_ASP21410801';
      PARENT_PPT_PART='SCONN60_ASP21410801-SCONN60_ASP-214108-01,SMLF,IO,DFHS60FS108';
  end_body;
end_primitive;
primitive 'SCONN75K_APCI0155P004A-SCONN75A';
  pin
    '3.3V_1':
      PIN_NUMBER='(2)';
      PINUSE='POWER';
      NO_LOAD_CHECK='Both';
      NO_IO_CHECK='Both';
      NO_ASSERT_CHECK='TRUE';
      NO_DIR_CHECK='TRUE';
      ALLOW_CONNECT='TRUE';
    '3.3V_2':
      PIN_NUMBER='(4)';
      PINUSE='POWER';
      NO_LOAD_CHECK='Both';
      NO_IO_CHECK='Both';
      NO_ASSERT_CHECK='TRUE';
      NO_DIR_CHECK='TRUE';
      ALLOW_CONNECT='TRUE';
    'DAS_DSS#||LED1#':
      PIN_NUMBER='(10)';
      BIDIRECTIONAL='TRUE';
      INPUT_LOAD='(-0.01,0.01)';
      OUTPUT_LOAD='(1.0,-1.0)';
      PINUSE='BI';
    '3.3V_3':
      PIN_NUMBER='(12)';
      PINUSE='POWER';
      NO_LOAD_CHECK='Both';
      NO_IO_CHECK='Both';
      NO_ASSERT_CHECK='TRUE';
      NO_DIR_CHECK='TRUE';
      ALLOW_CONNECT='TRUE';
    '3.3V_4':
      PIN_NUMBER='(14)';
      PINUSE='POWER';
      NO_LOAD_CHECK='Both';
      NO_IO_CHECK='Both';
      NO_ASSERT_CHECK='TRUE';
      NO_DIR_CHECK='TRUE';
      ALLOW_CONNECT='TRUE';
    '3.3V_5':
      PIN_NUMBER='(16)';
      PINUSE='POWER';
      NO_LOAD_CHECK='Both';
      NO_IO_CHECK='Both';
      NO_ASSERT_CHECK='TRUE';
      NO_DIR_CHECK='TRUE';
      ALLOW_CONNECT='TRUE';
    '3.3V_6':
      PIN_NUMBER='(18)';
      PINUSE='POWER';
      NO_LOAD_CHECK='Both';
      NO_IO_CHECK='Both';
      NO_ASSERT_CHECK='TRUE';
      NO_DIR_CHECK='TRUE';
      ALLOW_CONNECT='TRUE';
    'DEVSLP':
      PIN_NUMBER='(38)';
      INPUT_LOAD='(-0.01,0.01)';
      PINUSE='IN';
    'PERST#':
      PIN_NUMBER='(50)';
      INPUT_LOAD='(-0.01,0.01)';
      PINUSE='IN';
    'CLKREQ#':
      PIN_NUMBER='(52)';
      BIDIRECTIONAL='TRUE';
      INPUT_LOAD='(-0.01,0.01)';
      OUTPUT_LOAD='(1.0,-1.0)';
      PINUSE='BI';
    'PEWAKE#':
      PIN_NUMBER='(54)';
      BIDIRECTIONAL='TRUE';
      INPUT_LOAD='(-0.01,0.01)';
      OUTPUT_LOAD='(1.0,-1.0)';
      PINUSE='BI';
    'NC18':
      PIN_NUMBER='(58)';
      OUTPUT_TYPE='(TS,TS)';
      INPUT_LOAD='(-0.01,0.01)';
      OUTPUT_LOAD='(1.0,-1.0)';
      PINUSE='TRI';
    'SUSCLK':
      PIN_NUMBER='(68)';
      INPUT_LOAD='(-0.01,0.01)';
      PINUSE='IN';
    '3.3V_7':
      PIN_NUMBER='(70)';
      PINUSE='POWER';
      NO_LOAD_CHECK='Both';
      NO_IO_CHECK='Both';
      NO_ASSERT_CHECK='TRUE';
      NO_DIR_CHECK='TRUE';
      ALLOW_CONNECT='TRUE';
    '3.3V_8':
      PIN_NUMBER='(72)';
      PINUSE='POWER';
      NO_LOAD_CHECK='Both';
      NO_IO_CHECK='Both';
      NO_ASSERT_CHECK='TRUE';
      NO_DIR_CHECK='TRUE';
      ALLOW_CONNECT='TRUE';
    '3.3V_9':
      PIN_NUMBER='(74)';
      PINUSE='POWER';
      NO_LOAD_CHECK='Both';
      NO_IO_CHECK='Both';
      NO_ASSERT_CHECK='TRUE';
      NO_DIR_CHECK='TRUE';
      ALLOW_CONNECT='TRUE';
    'PERN0||SATA-B+':
      PIN_NUMBER='(41)';
      BIDIRECTIONAL='TRUE';
      INPUT_LOAD='(-0.01,0.01)';
      OUTPUT_LOAD='(1.0,-1.0)';
      PINUSE='BI';
    'PERP0||SATA-B-':
      PIN_NUMBER='(43)';
      BIDIRECTIONAL='TRUE';
      INPUT_LOAD='(-0.01,0.01)';
      OUTPUT_LOAD='(1.0,-1.0)';
      PINUSE='BI';
    'PETN0||SATA-A-':
      PIN_NUMBER='(47)';
      BIDIRECTIONAL='TRUE';
      INPUT_LOAD='(-0.01,0.01)';
      OUTPUT_LOAD='(1.0,-1.0)';
      PINUSE='BI';
    'PETP0||SATA-A+':
      PIN_NUMBER='(49)';
      BIDIRECTIONAL='TRUE';
      INPUT_LOAD='(-0.01,0.01)';
      OUTPUT_LOAD='(1.0,-1.0)';
      PINUSE='BI';
    'GND11':
      PIN_NUMBER='(57)';
      PINUSE='POWER';
      NO_LOAD_CHECK='Both';
      NO_IO_CHECK='Both';
      NO_ASSERT_CHECK='TRUE';
      NO_DIR_CHECK='TRUE';
      ALLOW_CONNECT='TRUE';
    'NC19':
      PIN_NUMBER='(67)';
      OUTPUT_TYPE='(TS,TS)';
      INPUT_LOAD='(-0.01,0.01)';
      OUTPUT_LOAD='(1.0,-1.0)';
      PINUSE='TRI';
    'PEDET':
      PIN_NUMBER='(69)';
      OUTPUT_LOAD='(1.0,-1.0)';
      PINUSE='OUT';
    'GND12':
      PIN_NUMBER='(71)';
      PINUSE='POWER';
      NO_LOAD_CHECK='Both';
      NO_IO_CHECK='Both';
      NO_ASSERT_CHECK='TRUE';
      NO_DIR_CHECK='TRUE';
      ALLOW_CONNECT='TRUE';
    'GND13':
      PIN_NUMBER='(73)';
      PINUSE='POWER';
      NO_LOAD_CHECK='Both';
      NO_IO_CHECK='Both';
      NO_ASSERT_CHECK='TRUE';
      NO_DIR_CHECK='TRUE';
      ALLOW_CONNECT='TRUE';
    'GND14':
      PIN_NUMBER='(75)';
      PINUSE='POWER';
      NO_LOAD_CHECK='Both';
      NO_IO_CHECK='Both';
      NO_ASSERT_CHECK='TRUE';
      NO_DIR_CHECK='TRUE';
      ALLOW_CONNECT='TRUE';
    'G1':
      PIN_NUMBER='(G1)';
      PINUSE='POWER';
      NO_LOAD_CHECK='Both';
      NO_IO_CHECK='Both';
      NO_ASSERT_CHECK='TRUE';
      NO_DIR_CHECK='TRUE';
      ALLOW_CONNECT='TRUE';
    'G2':
      PIN_NUMBER='(G2)';
      PINUSE='POWER';
      NO_LOAD_CHECK='Both';
      NO_IO_CHECK='Both';
      NO_ASSERT_CHECK='TRUE';
      NO_DIR_CHECK='TRUE';
      ALLOW_CONNECT='TRUE';
    'NC1':
      PIN_NUMBER='(6)';
      OUTPUT_TYPE='(TS,TS)';
      INPUT_LOAD='(-0.01,0.01)';
      OUTPUT_LOAD='(1.0,-1.0)';
      PINUSE='TRI';
    'NC2':
      PIN_NUMBER='(8)';
      OUTPUT_TYPE='(TS,TS)';
      INPUT_LOAD='(-0.01,0.01)';
      OUTPUT_LOAD='(1.0,-1.0)';
      PINUSE='TRI';
    'NC3':
      PIN_NUMBER='(20)';
      OUTPUT_TYPE='(TS,TS)';
      INPUT_LOAD='(-0.01,0.01)';
      OUTPUT_LOAD='(1.0,-1.0)';
      PINUSE='TRI';
    'NC10':
      PIN_NUMBER='(34)';
      OUTPUT_TYPE='(TS,TS)';
      INPUT_LOAD='(-0.01,0.01)';
      OUTPUT_LOAD='(1.0,-1.0)';
      PINUSE='TRI';
    'NC17':
      PIN_NUMBER='(56)';
      OUTPUT_TYPE='(TS,TS)';
      INPUT_LOAD='(-0.01,0.01)';
      OUTPUT_LOAD='(1.0,-1.0)';
      PINUSE='TRI';
    'NC16':
      PIN_NUMBER='(48)';
      OUTPUT_TYPE='(TS,TS)';
      INPUT_LOAD='(-0.01,0.01)';
      OUTPUT_LOAD='(1.0,-1.0)';
      PINUSE='TRI';
    'NC15':
      PIN_NUMBER='(46)';
      OUTPUT_TYPE='(TS,TS)';
      INPUT_LOAD='(-0.01,0.01)';
      OUTPUT_LOAD='(1.0,-1.0)';
      PINUSE='TRI';
    'NC14':
      PIN_NUMBER='(44)';
      OUTPUT_TYPE='(TS,TS)';
      INPUT_LOAD='(-0.01,0.01)';
      OUTPUT_LOAD='(1.0,-1.0)';
      PINUSE='TRI';
    'NC13':
      PIN_NUMBER='(42)';
      OUTPUT_TYPE='(TS,TS)';
      INPUT_LOAD='(-0.01,0.01)';
      OUTPUT_LOAD='(1.0,-1.0)';
      PINUSE='TRI';
    'NC12':
      PIN_NUMBER='(40)';
      OUTPUT_TYPE='(TS,TS)';
      INPUT_LOAD='(-0.01,0.01)';
      OUTPUT_LOAD='(1.0,-1.0)';
      PINUSE='TRI';
    'NC11':
      PIN_NUMBER='(36)';
      OUTPUT_TYPE='(TS,TS)';
      INPUT_LOAD='(-0.01,0.01)';
      OUTPUT_LOAD='(1.0,-1.0)';
      PINUSE='TRI';
    'NC9':
      PIN_NUMBER='(32)';
      OUTPUT_TYPE='(TS,TS)';
      INPUT_LOAD='(-0.01,0.01)';
      OUTPUT_LOAD='(1.0,-1.0)';
      PINUSE='TRI';
    'NC8':
      PIN_NUMBER='(30)';
      OUTPUT_TYPE='(TS,TS)';
      INPUT_LOAD='(-0.01,0.01)';
      OUTPUT_LOAD='(1.0,-1.0)';
      PINUSE='TRI';
    'NC7':
      PIN_NUMBER='(28)';
      OUTPUT_TYPE='(TS,TS)';
      INPUT_LOAD='(-0.01,0.01)';
      OUTPUT_LOAD='(1.0,-1.0)';
      PINUSE='TRI';
    'NC6':
      PIN_NUMBER='(26)';
      OUTPUT_TYPE='(TS,TS)';
      INPUT_LOAD='(-0.01,0.01)';
      OUTPUT_LOAD='(1.0,-1.0)';
      PINUSE='TRI';
    'NC5':
      PIN_NUMBER='(24)';
      OUTPUT_TYPE='(TS,TS)';
      INPUT_LOAD='(-0.01,0.01)';
      OUTPUT_LOAD='(1.0,-1.0)';
      PINUSE='TRI';
    'NC4':
      PIN_NUMBER='(22)';
      OUTPUT_TYPE='(TS,TS)';
      INPUT_LOAD='(-0.01,0.01)';
      OUTPUT_LOAD='(1.0,-1.0)';
      PINUSE='TRI';
    'GND1':
      PIN_NUMBER='(1)';
      PINUSE='POWER';
      NO_LOAD_CHECK='Both';
      NO_IO_CHECK='Both';
      NO_ASSERT_CHECK='TRUE';
      NO_DIR_CHECK='TRUE';
      ALLOW_CONNECT='TRUE';
    'GND2':
      PIN_NUMBER='(3)';
      PINUSE='POWER';
      NO_LOAD_CHECK='Both';
      NO_IO_CHECK='Both';
      NO_ASSERT_CHECK='TRUE';
      NO_DIR_CHECK='TRUE';
      ALLOW_CONNECT='TRUE';
    'GND3':
      PIN_NUMBER='(9)';
      PINUSE='POWER';
      NO_LOAD_CHECK='Both';
      NO_IO_CHECK='Both';
      NO_ASSERT_CHECK='TRUE';
      NO_DIR_CHECK='TRUE';
      ALLOW_CONNECT='TRUE';
    'GND4':
      PIN_NUMBER='(15)';
      PINUSE='POWER';
      NO_LOAD_CHECK='Both';
      NO_IO_CHECK='Both';
      NO_ASSERT_CHECK='TRUE';
      NO_DIR_CHECK='TRUE';
      ALLOW_CONNECT='TRUE';
    'GND5':
      PIN_NUMBER='(21)';
      PINUSE='POWER';
      NO_LOAD_CHECK='Both';
      NO_IO_CHECK='Both';
      NO_ASSERT_CHECK='TRUE';
      NO_DIR_CHECK='TRUE';
      ALLOW_CONNECT='TRUE';
    'GND6':
      PIN_NUMBER='(27)';
      PINUSE='POWER';
      NO_LOAD_CHECK='Both';
      NO_IO_CHECK='Both';
      NO_ASSERT_CHECK='TRUE';
      NO_DIR_CHECK='TRUE';
      ALLOW_CONNECT='TRUE';
    'GND7':
      PIN_NUMBER='(33)';
      PINUSE='POWER';
      NO_LOAD_CHECK='Both';
      NO_IO_CHECK='Both';
      NO_ASSERT_CHECK='TRUE';
      NO_DIR_CHECK='TRUE';
      ALLOW_CONNECT='TRUE';
    'GND8':
      PIN_NUMBER='(39)';
      PINUSE='POWER';
      NO_LOAD_CHECK='Both';
      NO_IO_CHECK='Both';
      NO_ASSERT_CHECK='TRUE';
      NO_DIR_CHECK='TRUE';
      ALLOW_CONNECT='TRUE';
    'GND9':
      PIN_NUMBER='(45)';
      PINUSE='POWER';
      NO_LOAD_CHECK='Both';
      NO_IO_CHECK='Both';
      NO_ASSERT_CHECK='TRUE';
      NO_DIR_CHECK='TRUE';
      ALLOW_CONNECT='TRUE';
    'GND10':
      PIN_NUMBER='(51)';
      PINUSE='POWER';
      NO_LOAD_CHECK='Both';
      NO_IO_CHECK='Both';
      NO_ASSERT_CHECK='TRUE';
      NO_DIR_CHECK='TRUE';
      ALLOW_CONNECT='TRUE';
    'PERN3':
      PIN_NUMBER='(5)';
      BIDIRECTIONAL='TRUE';
      INPUT_LOAD='(-0.01,0.01)';
      OUTPUT_LOAD='(1.0,-1.0)';
      PINUSE='BI';
    'PERP3':
      PIN_NUMBER='(7)';
      BIDIRECTIONAL='TRUE';
      INPUT_LOAD='(-0.01,0.01)';
      OUTPUT_LOAD='(1.0,-1.0)';
      PINUSE='BI';
    'PETN3':
      PIN_NUMBER='(11)';
      BIDIRECTIONAL='TRUE';
      INPUT_LOAD='(-0.01,0.01)';
      OUTPUT_LOAD='(1.0,-1.0)';
      PINUSE='BI';
    'PETP3':
      PIN_NUMBER='(13)';
      BIDIRECTIONAL='TRUE';
      INPUT_LOAD='(-0.01,0.01)';
      OUTPUT_LOAD='(1.0,-1.0)';
      PINUSE='BI';
    'PERN2':
      PIN_NUMBER='(17)';
      BIDIRECTIONAL='TRUE';
      INPUT_LOAD='(-0.01,0.01)';
      OUTPUT_LOAD='(1.0,-1.0)';
      PINUSE='BI';
    'PERP2':
      PIN_NUMBER='(19)';
      BIDIRECTIONAL='TRUE';
      INPUT_LOAD='(-0.01,0.01)';
      OUTPUT_LOAD='(1.0,-1.0)';
      PINUSE='BI';
    'PETN2':
      PIN_NUMBER='(23)';
      BIDIRECTIONAL='TRUE';
      INPUT_LOAD='(-0.01,0.01)';
      OUTPUT_LOAD='(1.0,-1.0)';
      PINUSE='BI';
    'PETP2':
      PIN_NUMBER='(25)';
      BIDIRECTIONAL='TRUE';
      INPUT_LOAD='(-0.01,0.01)';
      OUTPUT_LOAD='(1.0,-1.0)';
      PINUSE='BI';
    'PERN1':
      PIN_NUMBER='(29)';
      BIDIRECTIONAL='TRUE';
      INPUT_LOAD='(-0.01,0.01)';
      OUTPUT_LOAD='(1.0,-1.0)';
      PINUSE='BI';
    'PERP1':
      PIN_NUMBER='(31)';
      BIDIRECTIONAL='TRUE';
      INPUT_LOAD='(-0.01,0.01)';
      OUTPUT_LOAD='(1.0,-1.0)';
      PINUSE='BI';
    'PETN1':
      PIN_NUMBER='(35)';
      BIDIRECTIONAL='TRUE';
      INPUT_LOAD='(-0.01,0.01)';
      OUTPUT_LOAD='(1.0,-1.0)';
      PINUSE='BI';
    'PETP1':
      PIN_NUMBER='(37)';
      BIDIRECTIONAL='TRUE';
      INPUT_LOAD='(-0.01,0.01)';
      OUTPUT_LOAD='(1.0,-1.0)';
      PINUSE='BI';
    'REFCLKN':
      PIN_NUMBER='(53)';
      INPUT_LOAD='(-0.01,0.01)';
      PINUSE='IN';
    'REFCLKP':
      PIN_NUMBER='(55)';
      INPUT_LOAD='(-0.01,0.01)';
      PINUSE='IN';
  end_pin;
  body
      PART_NAME='SCONN75K_APCI0155P004A';
      BODY_NAME='SCONN75K_APCI0155P004A';
      PHYS_DES_PREFIX='J';
      CLASS='IO';
      NC_PINS='(H1,H2)';
      STANDARD='';
      LIFECYCLE='';
      JEDEC_TYPE='CON_F67S2H2D2S_P0-5W7-55_LUVXB_H270';
      DESCRIPTION='CONN SMD HOUSING 75P 2R FR(P0.5,H6.7)';
      MANUFTR='LTS';
      MANUF_PN='APCI0155-P004A';
      RD_CMPLS_LVL='EP(V1)';
      CMPLS_LVL='';
      DIP_SMD='';
      FROM_PJ='F08-MARK';
      DATA='LTS_APCI0155-P004A.pdf';
      FP_ECN='';
      EE_CHECK_LIST='';
      CREATOR='';
      CREATEDAY='20160104';
      PSL='';
      STATUS='';
      PARENT_PART_TYPE='SCONN75K_APCI0155P004A';
      PARENT_PPT='SCONN75K_APCI0155P004A';
      PARENT_PPT_PART='SCONN75K_APCI0155P004A-SCONN75K_APCI0155-P004A,SMLF,EMPTY,DFHS75FR313';
  end_body;
end_primitive;
primitive 'SN74LVC2G07DCKR_SMLF-SN74LVC2GA';
  pin
    '1A':
      PIN_NUMBER='(1)';
      INPUT_LOAD='(-0.01,0.01)';
      PINUSE='IN';
    '2A':
      PIN_NUMBER='(3)';
      INPUT_LOAD='(-0.01,0.01)';
      PINUSE='IN';
    '1Y':
      PIN_NUMBER='(6)';
      OUTPUT_LOAD='(1.0,-1.0)';
      PINUSE='OUT';
    '2Y':
      PIN_NUMBER='(4)';
      OUTPUT_LOAD='(1.0,-1.0)';
      PINUSE='OUT';
    'GND':
      PIN_NUMBER='(2)';
      PINUSE='POWER';
    'VCC':
      PIN_NUMBER='(5)';
      PINUSE='POWER';
  end_pin;
  body
      CLASS='IC';
      PART_NAME='SN74LVC2G07DCKR';
      PHYS_DES_PREFIX='U';
      STANDARD='End of Design';
      LIFECYCLE='Comp-Approve';
      ENVCOMP='NO';
      JEDEC_TYPE='SC70-6';
      DESCRIPTION='IC(6P) SN74LVC2G07DCKR(SC70-6)';
      HEIGHT='.044IN';
      COMPONENT_TYPE='';
      LEAD_LENGTH='';
      LPID='';
      STATUS='';
      RPL='';
      AML='';
      MANUF_PN='SN74LVC2G07DCKR';
      DAY='20101228';
      PARENT_PART_TYPE='SN74LVC2G07DCKR';
      PARENT_PPT='SN74LVC2G07DCKR';
      PARENT_PPT_PART='SN74LVC2G07DCKR_SMLF-SN74LVC2G07DCKR,IC,AL002G07006';
  end_body;
end_primitive;
primitive 'SOCKET4677_AZIF0045P001C01CS-SA';
  pin
    'XTAL_CLK_DP':
      PIN_NUMBER='(CY32,0,0,0,0,0,0,0,0,0,0,0,0,0,0,0,0,0,0,0,0,0,0,0,0,0,0,0,0,~
0,0,0,0,0,0,0,0,0,0,0,0,0)';
      INPUT_LOAD='(-0.01,0.01)';
      PINUSE='IN';
    'TXT_PLTEN':
      PIN_NUMBER='(CT20,0,0,0,0,0,0,0,0,0,0,0,0,0,0,0,0,0,0,0,0,0,0,0,0,0,0,0,0,~
0,0,0,0,0,0,0,0,0,0,0,0,0)';
      INPUT_LOAD='(-0.01,0.01)';
      PINUSE='IN';
    'TXT_AGENT':
      PIN_NUMBER='(BT26,0,0,0,0,0,0,0,0,0,0,0,0,0,0,0,0,0,0,0,0,0,0,0,0,0,0,0,0,~
0,0,0,0,0,0,0,0,0,0,0,0,0)';
      INPUT_LOAD='(-0.01,0.01)';
      PINUSE='IN';
    'TMS':
      PIN_NUMBER='(BR25,0,0,0,0,0,0,0,0,0,0,0,0,0,0,0,0,0,0,0,0,0,0,0,0,0,0,0,0,~
0,0,0,0,0,0,0,0,0,0,0,0,0)';
      INPUT_LOAD='(-0.01,0.01)';
      PINUSE='IN';
    'TDO':
      PIN_NUMBER='(BW25,0,0,0,0,0,0,0,0,0,0,0,0,0,0,0,0,0,0,0,0,0,0,0,0,0,0,0,0,~
0,0,0,0,0,0,0,0,0,0,0,0,0)';
      OUTPUT_LOAD='(1.0,-1.0)';
      PINUSE='OUT';
    'TDI':
      PIN_NUMBER='(BV24,0,0,0,0,0,0,0,0,0,0,0,0,0,0,0,0,0,0,0,0,0,0,0,0,0,0,0,0,~
0,0,0,0,0,0,0,0,0,0,0,0,0)';
      INPUT_LOAD='(-0.01,0.01)';
      PINUSE='IN';
    'TCK':
      PIN_NUMBER='(BT24,0,0,0,0,0,0,0,0,0,0,0,0,0,0,0,0,0,0,0,0,0,0,0,0,0,0,0,0,~
0,0,0,0,0,0,0,0,0,0,0,0,0)';
      INPUT_LOAD='(-0.01,0.01)';
      PINUSE='IN';
    'SOCKET_ID0':
      PIN_NUMBER='(CW60,0,0,0,0,0,0,0,0,0,0,0,0,0,0,0,0,0,0,0,0,0,0,0,0,0,0,0,0,~
0,0,0,0,0,0,0,0,0,0,0,0,0)';
      INPUT_LOAD='(-0.01,0.01)';
      PINUSE='IN';
    'SOCKET_ID1':
      PIN_NUMBER='(CY61,0,0,0,0,0,0,0,0,0,0,0,0,0,0,0,0,0,0,0,0,0,0,0,0,0,0,0,0,~
0,0,0,0,0,0,0,0,0,0,0,0,0)';
      INPUT_LOAD='(-0.01,0.01)';
      PINUSE='IN';
    'SOCKET_ID2':
      PIN_NUMBER='(CT61,0,0,0,0,0,0,0,0,0,0,0,0,0,0,0,0,0,0,0,0,0,0,0,0,0,0,0,0,~
0,0,0,0,0,0,0,0,0,0,0,0,0)';
      INPUT_LOAD='(-0.01,0.01)';
      PINUSE='IN';
    'SAFE_MODE_BOOT':
      PIN_NUMBER='(AU23,0,0,0,0,0,0,0,0,0,0,0,0,0,0,0,0,0,0,0,0,0,0,0,0,0,0,0,0,~
0,0,0,0,0,0,0,0,0,0,0,0,0)';
      BIDIRECTIONAL='TRUE';
      INPUT_LOAD='(-0.01,0.01)';
      OUTPUT_LOAD='(1.0,-1.0)';
      PINUSE='BI';
    'RSVD91':
      PIN_NUMBER='(CE70,0,0,0,0,0,0,0,0,0,0,0,0,0,0,0,0,0,0,0,0,0,0,0,0,0,0,0,0,~
0,0,0,0,0,0,0,0,0,0,0,0,0)';
      BIDIRECTIONAL='TRUE';
      INPUT_LOAD='(-0.01,0.01)';
      OUTPUT_LOAD='(1.0,-1.0)';
      PINUSE='BI';
    'RSVD88':
      PIN_NUMBER='(CD71,0,0,0,0,0,0,0,0,0,0,0,0,0,0,0,0,0,0,0,0,0,0,0,0,0,0,0,0,~
0,0,0,0,0,0,0,0,0,0,0,0,0)';
      BIDIRECTIONAL='TRUE';
      INPUT_LOAD='(-0.01,0.01)';
      OUTPUT_LOAD='(1.0,-1.0)';
      PINUSE='BI';
    'RSVD76':
      PIN_NUMBER='(BY24,0,0,0,0,0,0,0,0,0,0,0,0,0,0,0,0,0,0,0,0,0,0,0,0,0,0,0,0,~
0,0,0,0,0,0,0,0,0,0,0,0,0)';
      BIDIRECTIONAL='TRUE';
      INPUT_LOAD='(-0.01,0.01)';
      OUTPUT_LOAD='(1.0,-1.0)';
      PINUSE='BI';
    'RSVD161':
      PIN_NUMBER='(G5,0,0,0,0,0,0,0,0,0,0,0,0,0,0,0,0,0,0,0,0,0,0,0,0,0,0,0,0,0,~
0,0,0,0,0,0,0,0,0,0,0,0)';
      BIDIRECTIONAL='TRUE';
      INPUT_LOAD='(-0.01,0.01)';
      OUTPUT_LOAD='(1.0,-1.0)';
      PINUSE='BI';
    'RSVD108':
      PIN_NUMBER='(CJ72,0,0,0,0,0,0,0,0,0,0,0,0,0,0,0,0,0,0,0,0,0,0,0,0,0,0,0,0,~
0,0,0,0,0,0,0,0,0,0,0,0,0)';
      BIDIRECTIONAL='TRUE';
      INPUT_LOAD='(-0.01,0.01)';
      OUTPUT_LOAD='(1.0,-1.0)';
      PINUSE='BI';
    'PROC_ID0':
      PIN_NUMBER='(BG72,0,0,0,0,0,0,0,0,0,0,0,0,0,0,0,0,0,0,0,0,0,0,0,0,0,0,0,0,~
0,0,0,0,0,0,0,0,0,0,0,0,0)';
      INPUT_LOAD='(-0.01,0.01)';
      PINUSE='IN';
    'PROC_ID1':
      PIN_NUMBER='(BH71,0,0,0,0,0,0,0,0,0,0,0,0,0,0,0,0,0,0,0,0,0,0,0,0,0,0,0,0,~
0,0,0,0,0,0,0,0,0,0,0,0,0)';
      INPUT_LOAD='(-0.01,0.01)';
      PINUSE='IN';
    'PROCDIS_N':
      PIN_NUMBER='(DA52,0,0,0,0,0,0,0,0,0,0,0,0,0,0,0,0,0,0,0,0,0,0,0,0,0,0,0,0,~
0,0,0,0,0,0,0,0,0,0,0,0,0)';
      INPUT_LOAD='(-0.01,0.01)';
      PINUSE='IN';
    'PREQ_N':
      PIN_NUMBER='(AV22,0,0,0,0,0,0,0,0,0,0,0,0,0,0,0,0,0,0,0,0,0,0,0,0,0,0,0,0,~
0,0,0,0,0,0,0,0,0,0,0,0,0)';
      INPUT_LOAD='(-0.01,0.01)';
      PINUSE='IN';
    'PRDY_N':
      PIN_NUMBER='(BP26,0,0,0,0,0,0,0,0,0,0,0,0,0,0,0,0,0,0,0,0,0,0,0,0,0,0,0,0,~
0,0,0,0,0,0,0,0,0,0,0,0,0)';
      OUTPUT_LOAD='(1.0,-1.0)';
      PINUSE='OUT';
    'PKG_ID0':
      PIN_NUMBER='(BL64,0,0,0,0,0,0,0,0,0,0,0,0,0,0,0,0,0,0,0,0,0,0,0,0,0,0,0,0,~
0,0,0,0,0,0,0,0,0,0,0,0,0)';
      INPUT_LOAD='(-0.01,0.01)';
      PINUSE='IN';
    'PKG_ID1':
      PIN_NUMBER='(AY63,0,0,0,0,0,0,0,0,0,0,0,0,0,0,0,0,0,0,0,0,0,0,0,0,0,0,0,0,~
0,0,0,0,0,0,0,0,0,0,0,0,0)';
      INPUT_LOAD='(-0.01,0.01)';
      PINUSE='IN';
    'PKG_ID2':
      PIN_NUMBER='(BN64,0,0,0,0,0,0,0,0,0,0,0,0,0,0,0,0,0,0,0,0,0,0,0,0,0,0,0,0,~
0,0,0,0,0,0,0,0,0,0,0,0,0)';
      INPUT_LOAD='(-0.01,0.01)';
      PINUSE='IN';
    'PECI':
      PIN_NUMBER='(BH24,0,0,0,0,0,0,0,0,0,0,0,0,0,0,0,0,0,0,0,0,0,0,0,0,0,0,0,0,~
0,0,0,0,0,0,0,0,0,0,0,0,0)';
      BIDIRECTIONAL='TRUE';
      INPUT_LOAD='(-0.01,0.01)';
      OUTPUT_LOAD='(1.0,-1.0)';
      PINUSE='BI';
    'RSVD72':
      PIN_NUMBER='(BR23,0,0,0,0,0,0,0,0,0,0,0,0,0,0,0,0,0,0,0,0,0,0,0,0,0,0,0,0,~
0,0,0,0,0,0,0,0,0,0,0,0,0)';
      BIDIRECTIONAL='TRUE';
      INPUT_LOAD='(-0.01,0.01)';
      OUTPUT_LOAD='(1.0,-1.0)';
      PINUSE='BI';
    'LEGACY_SKT':
      PIN_NUMBER='(CY59,0,0,0,0,0,0,0,0,0,0,0,0,0,0,0,0,0,0,0,0,0,0,0,0,0,0,0,0,~
0,0,0,0,0,0,0,0,0,0,0,0,0)';
      INPUT_LOAD='(-0.01,0.01)';
      PINUSE='IN';
    'FRMAGENT':
      PIN_NUMBER='(AU17,0,0,0,0,0,0,0,0,0,0,0,0,0,0,0,0,0,0,0,0,0,0,0,0,0,0,0,0,~
0,0,0,0,0,0,0,0,0,0,0,0,0)';
      INPUT_LOAD='(-0.01,0.01)';
      PINUSE='IN';
    'DMIMODE_OVERRIDE':
      PIN_NUMBER='(AW17,0,0,0,0,0,0,0,0,0,0,0,0,0,0,0,0,0,0,0,0,0,0,0,0,0,0,0,0,~
0,0,0,0,0,0,0,0,0,0,0,0,0)';
      INPUT_LOAD='(-0.01,0.01)';
      PINUSE='IN';
    'DDR67_RESET_N':
      PIN_NUMBER='(CY55,0,0,0,0,0,0,0,0,0,0,0,0,0,0,0,0,0,0,0,0,0,0,0,0,0,0,0,0,~
0,0,0,0,0,0,0,0,0,0,0,0,0)';
      OUTPUT_LOAD='(1.0,-1.0)';
      PINUSE='OUT';
    'DDR45_RESET_N':
      PIN_NUMBER='(CY42,0,0,0,0,0,0,0,0,0,0,0,0,0,0,0,0,0,0,0,0,0,0,0,0,0,0,0,0,~
0,0,0,0,0,0,0,0,0,0,0,0,0)';
      OUTPUT_LOAD='(1.0,-1.0)';
      PINUSE='OUT';
    'DDR4567_SPDSDA':
      PIN_NUMBER='(CT18,0,0,0,0,0,0,0,0,0,0,0,0,0,0,0,0,0,0,0,0,0,0,0,0,0,0,0,0,~
0,0,0,0,0,0,0,0,0,0,0,0,0)';
      BIDIRECTIONAL='TRUE';
      INPUT_LOAD='(-0.01,0.01)';
      OUTPUT_LOAD='(1.0,-1.0)';
      PINUSE='BI';
    'DDR4567_SPDSCL':
      PIN_NUMBER='(CU17,0,0,0,0,0,0,0,0,0,0,0,0,0,0,0,0,0,0,0,0,0,0,0,0,0,0,0,0,~
0,0,0,0,0,0,0,0,0,0,0,0,0)';
      OUTPUT_LOAD='(1.0,-1.0)';
      PINUSE='OUT';
    'DDR23_RESET_N':
      PIN_NUMBER='(AV51,0,0,0,0,0,0,0,0,0,0,0,0,0,0,0,0,0,0,0,0,0,0,0,0,0,0,0,0,~
0,0,0,0,0,0,0,0,0,0,0,0,0)';
      OUTPUT_LOAD='(1.0,-1.0)';
      PINUSE='OUT';
    'DDR01_RESET_N':
      PIN_NUMBER='(AU50,0,0,0,0,0,0,0,0,0,0,0,0,0,0,0,0,0,0,0,0,0,0,0,0,0,0,0,0,~
0,0,0,0,0,0,0,0,0,0,0,0,0)';
      OUTPUT_LOAD='(1.0,-1.0)';
      PINUSE='OUT';
    'DDR0123_SPDSDA':
      PIN_NUMBER='(BY22,0,0,0,0,0,0,0,0,0,0,0,0,0,0,0,0,0,0,0,0,0,0,0,0,0,0,0,0,~
0,0,0,0,0,0,0,0,0,0,0,0,0)';
      BIDIRECTIONAL='TRUE';
      INPUT_LOAD='(-0.01,0.01)';
      OUTPUT_LOAD='(1.0,-1.0)';
      PINUSE='BI';
    'DDR0123_SPDSCL':
      PIN_NUMBER='(BT22,0,0,0,0,0,0,0,0,0,0,0,0,0,0,0,0,0,0,0,0,0,0,0,0,0,0,0,0,~
0,0,0,0,0,0,0,0,0,0,0,0,0)';
      OUTPUT_LOAD='(1.0,-1.0)';
      PINUSE='OUT';
    'BMCINIT':
      PIN_NUMBER='(BN23,0,0,0,0,0,0,0,0,0,0,0,0,0,0,0,0,0,0,0,0,0,0,0,0,0,0,0,0,~
0,0,0,0,0,0,0,0,0,0,0,0,0)';
      INPUT_LOAD='(-0.01,0.01)';
      PINUSE='IN';
    'BIST_ENABLE':
      PIN_NUMBER='(AT18,0,0,0,0,0,0,0,0,0,0,0,0,0,0,0,0,0,0,0,0,0,0,0,0,0,0,0,0,~
0,0,0,0,0,0,0,0,0,0,0,0,0)';
      INPUT_LOAD='(-0.01,0.01)';
      PINUSE='IN';
    'BCLK3_DP':
      PIN_NUMBER='(DA27,0,0,0,0,0,0,0,0,0,0,0,0,0,0,0,0,0,0,0,0,0,0,0,0,0,0,0,0,~
0,0,0,0,0,0,0,0,0,0,0,0,0)';
      INPUT_LOAD='(-0.01,0.01)';
      PINUSE='IN';
    'BCLK3_DN':
      PIN_NUMBER='(CW27,0,0,0,0,0,0,0,0,0,0,0,0,0,0,0,0,0,0,0,0,0,0,0,0,0,0,0,0,~
0,0,0,0,0,0,0,0,0,0,0,0,0)';
      INPUT_LOAD='(-0.01,0.01)';
      PINUSE='IN';
    'BCLK2_DP':
      PIN_NUMBER='(AV28,0,0,0,0,0,0,0,0,0,0,0,0,0,0,0,0,0,0,0,0,0,0,0,0,0,0,0,0,~
0,0,0,0,0,0,0,0,0,0,0,0,0)';
      INPUT_LOAD='(-0.01,0.01)';
      PINUSE='IN';
    'BCLK2_DN':
      PIN_NUMBER='(AU29,0,0,0,0,0,0,0,0,0,0,0,0,0,0,0,0,0,0,0,0,0,0,0,0,0,0,0,0,~
0,0,0,0,0,0,0,0,0,0,0,0,0)';
      INPUT_LOAD='(-0.01,0.01)';
      PINUSE='IN';
    'BCLK0_DP':
      PIN_NUMBER='(AV30,0,0,0,0,0,0,0,0,0,0,0,0,0,0,0,0,0,0,0,0,0,0,0,0,0,0,0,0,~
0,0,0,0,0,0,0,0,0,0,0,0,0)';
      INPUT_LOAD='(-0.01,0.01)';
      PINUSE='IN';
    'BCLK1_DN':
      PIN_NUMBER='(CY28,0,0,0,0,0,0,0,0,0,0,0,0,0,0,0,0,0,0,0,0,0,0,0,0,0,0,0,0,~
0,0,0,0,0,0,0,0,0,0,0,0,0)';
      INPUT_LOAD='(-0.01,0.01)';
      PINUSE='IN';
    'BCLK1_DP':
      PIN_NUMBER='(CW29,0,0,0,0,0,0,0,0,0,0,0,0,0,0,0,0,0,0,0,0,0,0,0,0,0,0,0,0,~
0,0,0,0,0,0,0,0,0,0,0,0,0)';
      INPUT_LOAD='(-0.01,0.01)';
      PINUSE='IN';
    'BCLK0_DN':
      PIN_NUMBER='(AT30,0,0,0,0,0,0,0,0,0,0,0,0,0,0,0,0,0,0,0,0,0,0,0,0,0,0,0,0,~
0,0,0,0,0,0,0,0,0,0,0,0,0)';
      INPUT_LOAD='(-0.01,0.01)';
      PINUSE='IN';
    'RSVD120':
      PIN_NUMBER='(CL72,0,0,0,0,0,0,0,0,0,0,0,0,0,0,0,0,0,0,0,0,0,0,0,0,0,0,0,0,~
0,0,0,0,0,0,0,0,0,0,0,0,0)';
      BIDIRECTIONAL='TRUE';
      INPUT_LOAD='(-0.01,0.01)';
      OUTPUT_LOAD='(1.0,-1.0)';
      PINUSE='BI';
    'RSVD157':
      PIN_NUMBER='(D4,0,0,0,0,0,0,0,0,0,0,0,0,0,0,0,0,0,0,0,0,0,0,0,0,0,0,0,0,0,~
0,0,0,0,0,0,0,0,0,0,0,0)';
      BIDIRECTIONAL='TRUE';
      INPUT_LOAD='(-0.01,0.01)';
      OUTPUT_LOAD='(1.0,-1.0)';
      PINUSE='BI';
    'XTAL_CLK_DN':
      PIN_NUMBER='(CW31,0,0,0,0,0,0,0,0,0,0,0,0,0,0,0,0,0,0,0,0,0,0,0,0,0,0,0,0,~
0,0,0,0,0,0,0,0,0,0,0,0,0)';
      INPUT_LOAD='(-0.01,0.01)';
      PINUSE='IN';
    'CATERR_N':
      PIN_NUMBER='(0,BP24,0,0,0,0,0,0,0,0,0,0,0,0,0,0,0,0,0,0,0,0,0,0,0,0,0,0,0,~
0,0,0,0,0,0,0,0,0,0,0,0,0)';
      BIDIRECTIONAL='TRUE';
      INPUT_LOAD='(-0.01,0.01)';
      OUTPUT_LOAD='(1.0,-1.0)';
      PINUSE='BI';
    'CXPSMBUSSCL':
      PIN_NUMBER='(0,CA25,0,0,0,0,0,0,0,0,0,0,0,0,0,0,0,0,0,0,0,0,0,0,0,0,0,0,0,~
0,0,0,0,0,0,0,0,0,0,0,0,0)';
      OUTPUT_LOAD='(1.0,-1.0)';
      PINUSE='OUT';
    'CXPSMBUSSDA':
      PIN_NUMBER='(0,BY26,0,0,0,0,0,0,0,0,0,0,0,0,0,0,0,0,0,0,0,0,0,0,0,0,0,0,0,~
0,0,0,0,0,0,0,0,0,0,0,0,0)';
      BIDIRECTIONAL='TRUE';
      INPUT_LOAD='(-0.01,0.01)';
      OUTPUT_LOAD='(1.0,-1.0)';
      PINUSE='BI';
    'CXPSMBUS_ALERT_N':
      PIN_NUMBER='(0,BV26,0,0,0,0,0,0,0,0,0,0,0,0,0,0,0,0,0,0,0,0,0,0,0,0,0,0,0,~
0,0,0,0,0,0,0,0,0,0,0,0,0)';
      INPUT_LOAD='(-0.01,0.01)';
      PINUSE='IN';
    'DDR01_DRAM_PWR_OK':
      PIN_NUMBER='(0,A43,0,0,0,0,0,0,0,0,0,0,0,0,0,0,0,0,0,0,0,0,0,0,0,0,0,0,0,0~
,0,0,0,0,0,0,0,0,0,0,0,0)';
      INPUT_LOAD='(-0.01,0.01)';
      PINUSE='IN';
    'DDR23_DRAM_PWR_OK':
      PIN_NUMBER='(0,F47,0,0,0,0,0,0,0,0,0,0,0,0,0,0,0,0,0,0,0,0,0,0,0,0,0,0,0,0~
,0,0,0,0,0,0,0,0,0,0,0,0)';
      INPUT_LOAD='(-0.01,0.01)';
      PINUSE='IN';
    'DDR45_DRAM_PWR_OK':
      PIN_NUMBER='(0,CY44,0,0,0,0,0,0,0,0,0,0,0,0,0,0,0,0,0,0,0,0,0,0,0,0,0,0,0,~
0,0,0,0,0,0,0,0,0,0,0,0,0)';
      INPUT_LOAD='(-0.01,0.01)';
      PINUSE='IN';
    'DDR67_DRAM_PWR_OK':
      PIN_NUMBER='(0,CW45,0,0,0,0,0,0,0,0,0,0,0,0,0,0,0,0,0,0,0,0,0,0,0,0,0,0,0,~
0,0,0,0,0,0,0,0,0,0,0,0,0)';
      INPUT_LOAD='(-0.01,0.01)';
      PINUSE='IN';
    'RSVD96':
      PIN_NUMBER='(0,CH22,0,0,0,0,0,0,0,0,0,0,0,0,0,0,0,0,0,0,0,0,0,0,0,0,0,0,0,~
0,0,0,0,0,0,0,0,0,0,0,0,0)';
      BIDIRECTIONAL='TRUE';
      INPUT_LOAD='(-0.01,0.01)';
      OUTPUT_LOAD='(1.0,-1.0)';
      PINUSE='BI';
    'ERROR_N2':
      PIN_NUMBER='(0,BD22,0,0,0,0,0,0,0,0,0,0,0,0,0,0,0,0,0,0,0,0,0,0,0,0,0,0,0,~
0,0,0,0,0,0,0,0,0,0,0,0,0)';
      OUTPUT_LOAD='(1.0,-1.0)';
      PINUSE='OUT';
    'ERROR_N1':
      PIN_NUMBER='(0,AY22,0,0,0,0,0,0,0,0,0,0,0,0,0,0,0,0,0,0,0,0,0,0,0,0,0,0,0,~
0,0,0,0,0,0,0,0,0,0,0,0,0)';
      OUTPUT_LOAD='(1.0,-1.0)';
      PINUSE='OUT';
    'ERROR_N0':
      PIN_NUMBER='(0,BF22,0,0,0,0,0,0,0,0,0,0,0,0,0,0,0,0,0,0,0,0,0,0,0,0,0,0,0,~
0,0,0,0,0,0,0,0,0,0,0,0,0)';
      OUTPUT_LOAD='(1.0,-1.0)';
      PINUSE='OUT';
    'FBRK_N':
      PIN_NUMBER='(0,AV57,0,0,0,0,0,0,0,0,0,0,0,0,0,0,0,0,0,0,0,0,0,0,0,0,0,0,0,~
0,0,0,0,0,0,0,0,0,0,0,0,0)';
      INPUT_LOAD='(-0.01,0.01)';
      PINUSE='IN';
    'MEMHOT_IN_N':
      PIN_NUMBER='(0,AU21,0,0,0,0,0,0,0,0,0,0,0,0,0,0,0,0,0,0,0,0,0,0,0,0,0,0,0,~
0,0,0,0,0,0,0,0,0,0,0,0,0)';
      INPUT_LOAD='(-0.01,0.01)';
      PINUSE='IN';
    'MEMHOT_OUT_N':
      PIN_NUMBER='(0,CF26,0,0,0,0,0,0,0,0,0,0,0,0,0,0,0,0,0,0,0,0,0,0,0,0,0,0,0,~
0,0,0,0,0,0,0,0,0,0,0,0,0)';
      OUTPUT_LOAD='(1.0,-1.0)';
      PINUSE='OUT';
    'MEMTRIP_N':
      PIN_NUMBER='(0,AV24,0,0,0,0,0,0,0,0,0,0,0,0,0,0,0,0,0,0,0,0,0,0,0,0,0,0,0,~
0,0,0,0,0,0,0,0,0,0,0,0,0)';
      OUTPUT_LOAD='(1.0,-1.0)';
      PINUSE='OUT';
    'NMI':
      PIN_NUMBER='(0,AV18,0,0,0,0,0,0,0,0,0,0,0,0,0,0,0,0,0,0,0,0,0,0,0,0,0,0,0,~
0,0,0,0,0,0,0,0,0,0,0,0,0)';
      INPUT_LOAD='(-0.01,0.01)';
      PINUSE='IN';
    'PIROM_AD2':
      PIN_NUMBER='(0,CP71,0,0,0,0,0,0,0,0,0,0,0,0,0,0,0,0,0,0,0,0,0,0,0,0,0,0,0,~
0,0,0,0,0,0,0,0,0,0,0,0,0)';
      INPUT_LOAD='(-0.01,0.01)';
      PINUSE='IN';
    'PIROM_AD1':
      PIN_NUMBER='(0,CT71,0,0,0,0,0,0,0,0,0,0,0,0,0,0,0,0,0,0,0,0,0,0,0,0,0,0,0,~
0,0,0,0,0,0,0,0,0,0,0,0,0)';
      INPUT_LOAD='(-0.01,0.01)';
      PINUSE='IN';
    'PIROM_AD0':
      PIN_NUMBER='(0,CR70,0,0,0,0,0,0,0,0,0,0,0,0,0,0,0,0,0,0,0,0,0,0,0,0,0,0,0,~
0,0,0,0,0,0,0,0,0,0,0,0,0)';
      INPUT_LOAD='(-0.01,0.01)';
      PINUSE='IN';
    'PIROM_SCL':
      PIN_NUMBER='(0,CU70,0,0,0,0,0,0,0,0,0,0,0,0,0,0,0,0,0,0,0,0,0,0,0,0,0,0,0,~
0,0,0,0,0,0,0,0,0,0,0,0,0)';
      INPUT_LOAD='(-0.01,0.01)';
      PINUSE='IN';
    'PIROM_SDA':
      PIN_NUMBER='(0,CM71,0,0,0,0,0,0,0,0,0,0,0,0,0,0,0,0,0,0,0,0,0,0,0,0,0,0,0,~
0,0,0,0,0,0,0,0,0,0,0,0,0)';
      BIDIRECTIONAL='TRUE';
      INPUT_LOAD='(-0.01,0.01)';
      OUTPUT_LOAD='(1.0,-1.0)';
      PINUSE='BI';
    'PIROM_SM_WP':
      PIN_NUMBER='(0,CR72,0,0,0,0,0,0,0,0,0,0,0,0,0,0,0,0,0,0,0,0,0,0,0,0,0,0,0,~
0,0,0,0,0,0,0,0,0,0,0,0,0)';
      INPUT_LOAD='(-0.01,0.01)';
      PINUSE='IN';
    'PMDOWN6':
      PIN_NUMBER='(0,CC25,0,0,0,0,0,0,0,0,0,0,0,0,0,0,0,0,0,0,0,0,0,0,0,0,0,0,0,~
0,0,0,0,0,0,0,0,0,0,0,0,0)';
      BIDIRECTIONAL='TRUE';
      INPUT_LOAD='(-0.01,0.01)';
      OUTPUT_LOAD='(1.0,-1.0)';
      PINUSE='BI';
    'PMDOWN5':
      PIN_NUMBER='(0,CE23,0,0,0,0,0,0,0,0,0,0,0,0,0,0,0,0,0,0,0,0,0,0,0,0,0,0,0,~
0,0,0,0,0,0,0,0,0,0,0,0,0)';
      BIDIRECTIONAL='TRUE';
      INPUT_LOAD='(-0.01,0.01)';
      OUTPUT_LOAD='(1.0,-1.0)';
      PINUSE='BI';
    'PMDOWN4':
      PIN_NUMBER='(0,CV18,0,0,0,0,0,0,0,0,0,0,0,0,0,0,0,0,0,0,0,0,0,0,0,0,0,0,0,~
0,0,0,0,0,0,0,0,0,0,0,0,0)';
      BIDIRECTIONAL='TRUE';
      INPUT_LOAD='(-0.01,0.01)';
      OUTPUT_LOAD='(1.0,-1.0)';
      PINUSE='BI';
    'PMDOWN3':
      PIN_NUMBER='(0,CD24,0,0,0,0,0,0,0,0,0,0,0,0,0,0,0,0,0,0,0,0,0,0,0,0,0,0,0,~
0,0,0,0,0,0,0,0,0,0,0,0,0)';
      BIDIRECTIONAL='TRUE';
      INPUT_LOAD='(-0.01,0.01)';
      OUTPUT_LOAD='(1.0,-1.0)';
      PINUSE='BI';
    'PMDOWN2':
      PIN_NUMBER='(0,CM26,0,0,0,0,0,0,0,0,0,0,0,0,0,0,0,0,0,0,0,0,0,0,0,0,0,0,0,~
0,0,0,0,0,0,0,0,0,0,0,0,0)';
      BIDIRECTIONAL='TRUE';
      INPUT_LOAD='(-0.01,0.01)';
      OUTPUT_LOAD='(1.0,-1.0)';
      PINUSE='BI';
    'PMDOWN1':
      PIN_NUMBER='(0,CP26,0,0,0,0,0,0,0,0,0,0,0,0,0,0,0,0,0,0,0,0,0,0,0,0,0,0,0,~
0,0,0,0,0,0,0,0,0,0,0,0,0)';
      BIDIRECTIONAL='TRUE';
      INPUT_LOAD='(-0.01,0.01)';
      OUTPUT_LOAD='(1.0,-1.0)';
      PINUSE='BI';
    'PMDOWN0':
      PIN_NUMBER='(0,CW39,0,0,0,0,0,0,0,0,0,0,0,0,0,0,0,0,0,0,0,0,0,0,0,0,0,0,0,~
0,0,0,0,0,0,0,0,0,0,0,0,0)';
      INPUT_LOAD='(-0.01,0.01)';
      PINUSE='IN';
    'PMDOWN_PCH':
      PIN_NUMBER='(0,CY40,0,0,0,0,0,0,0,0,0,0,0,0,0,0,0,0,0,0,0,0,0,0,0,0,0,0,0,~
0,0,0,0,0,0,0,0,0,0,0,0,0)';
      BIDIRECTIONAL='TRUE';
      INPUT_LOAD='(-0.01,0.01)';
      OUTPUT_LOAD='(1.0,-1.0)';
      PINUSE='BI';
    'PMFAST_WAKE_N':
      PIN_NUMBER='(0,CP20,0,0,0,0,0,0,0,0,0,0,0,0,0,0,0,0,0,0,0,0,0,0,0,0,0,0,0,~
0,0,0,0,0,0,0,0,0,0,0,0,0)';
      BIDIRECTIONAL='TRUE';
      INPUT_LOAD='(-0.01,0.01)';
      OUTPUT_LOAD='(1.0,-1.0)';
      PINUSE='BI';
    'PMSYNC6':
      PIN_NUMBER='(0,CF24,0,0,0,0,0,0,0,0,0,0,0,0,0,0,0,0,0,0,0,0,0,0,0,0,0,0,0,~
0,0,0,0,0,0,0,0,0,0,0,0,0)';
      BIDIRECTIONAL='TRUE';
      INPUT_LOAD='(-0.01,0.01)';
      OUTPUT_LOAD='(1.0,-1.0)';
      PINUSE='BI';
    'PMSYNC5':
      PIN_NUMBER='(0,CH24,0,0,0,0,0,0,0,0,0,0,0,0,0,0,0,0,0,0,0,0,0,0,0,0,0,0,0,~
0,0,0,0,0,0,0,0,0,0,0,0,0)';
      BIDIRECTIONAL='TRUE';
      INPUT_LOAD='(-0.01,0.01)';
      OUTPUT_LOAD='(1.0,-1.0)';
      PINUSE='BI';
    'PMSYNC4':
      PIN_NUMBER='(0,CR19,0,0,0,0,0,0,0,0,0,0,0,0,0,0,0,0,0,0,0,0,0,0,0,0,0,0,0,~
0,0,0,0,0,0,0,0,0,0,0,0,0)';
      BIDIRECTIONAL='TRUE';
      INPUT_LOAD='(-0.01,0.01)';
      OUTPUT_LOAD='(1.0,-1.0)';
      PINUSE='BI';
    'PMSYNC3':
      PIN_NUMBER='(0,CE25,0,0,0,0,0,0,0,0,0,0,0,0,0,0,0,0,0,0,0,0,0,0,0,0,0,0,0,~
0,0,0,0,0,0,0,0,0,0,0,0,0)';
      BIDIRECTIONAL='TRUE';
      INPUT_LOAD='(-0.01,0.01)';
      OUTPUT_LOAD='(1.0,-1.0)';
      PINUSE='BI';
    'PMSYNC2':
      PIN_NUMBER='(0,CH26,0,0,0,0,0,0,0,0,0,0,0,0,0,0,0,0,0,0,0,0,0,0,0,0,0,0,0,~
0,0,0,0,0,0,0,0,0,0,0,0,0)';
      BIDIRECTIONAL='TRUE';
      INPUT_LOAD='(-0.01,0.01)';
      OUTPUT_LOAD='(1.0,-1.0)';
      PINUSE='BI';
    'PMSYNC1':
      PIN_NUMBER='(0,CL25,0,0,0,0,0,0,0,0,0,0,0,0,0,0,0,0,0,0,0,0,0,0,0,0,0,0,0,~
0,0,0,0,0,0,0,0,0,0,0,0,0)';
      BIDIRECTIONAL='TRUE';
      INPUT_LOAD='(-0.01,0.01)';
      OUTPUT_LOAD='(1.0,-1.0)';
      PINUSE='BI';
    'PMSYNC0':
      PIN_NUMBER='(0,CN25,0,0,0,0,0,0,0,0,0,0,0,0,0,0,0,0,0,0,0,0,0,0,0,0,0,0,0,~
0,0,0,0,0,0,0,0,0,0,0,0,0)';
      BIDIRECTIONAL='TRUE';
      INPUT_LOAD='(-0.01,0.01)';
      OUTPUT_LOAD='(1.0,-1.0)';
      PINUSE='BI';
    'PMSYNC_PCH':
      PIN_NUMBER='(0,DA39,0,0,0,0,0,0,0,0,0,0,0,0,0,0,0,0,0,0,0,0,0,0,0,0,0,0,0,~
0,0,0,0,0,0,0,0,0,0,0,0,0)';
      BIDIRECTIONAL='TRUE';
      INPUT_LOAD='(-0.01,0.01)';
      OUTPUT_LOAD='(1.0,-1.0)';
      PINUSE='BI';
    'PROCHOT_N':
      PIN_NUMBER='(0,AU19,0,0,0,0,0,0,0,0,0,0,0,0,0,0,0,0,0,0,0,0,0,0,0,0,0,0,0,~
0,0,0,0,0,0,0,0,0,0,0,0,0)';
      INPUT_LOAD='(-0.01,0.01)';
      PINUSE='IN';
    'PWRGOOD':
      PIN_NUMBER='(0,AV20,0,0,0,0,0,0,0,0,0,0,0,0,0,0,0,0,0,0,0,0,0,0,0,0,0,0,0,~
0,0,0,0,0,0,0,0,0,0,0,0,0)';
      INPUT_LOAD='(-0.01,0.01)';
      PINUSE='IN';
    'RESET_N':
      PIN_NUMBER='(0,BH61,0,0,0,0,0,0,0,0,0,0,0,0,0,0,0,0,0,0,0,0,0,0,0,0,0,0,0,~
0,0,0,0,0,0,0,0,0,0,0,0,0)';
      INPUT_LOAD='(-0.01,0.01)';
      PINUSE='IN';
    'RSVD113':
      PIN_NUMBER='(0,CL21,0,0,0,0,0,0,0,0,0,0,0,0,0,0,0,0,0,0,0,0,0,0,0,0,0,0,0,~
0,0,0,0,0,0,0,0,0,0,0,0,0)';
      BIDIRECTIONAL='TRUE';
      INPUT_LOAD='(-0.01,0.01)';
      OUTPUT_LOAD='(1.0,-1.0)';
      PINUSE='BI';
    'RSVD116':
      PIN_NUMBER='(0,CL64,0,0,0,0,0,0,0,0,0,0,0,0,0,0,0,0,0,0,0,0,0,0,0,0,0,0,0,~
0,0,0,0,0,0,0,0,0,0,0,0,0)';
      BIDIRECTIONAL='TRUE';
      INPUT_LOAD='(-0.01,0.01)';
      OUTPUT_LOAD='(1.0,-1.0)';
      PINUSE='BI';
    'RSVD121':
      PIN_NUMBER='(0,CM63,0,0,0,0,0,0,0,0,0,0,0,0,0,0,0,0,0,0,0,0,0,0,0,0,0,0,0,~
0,0,0,0,0,0,0,0,0,0,0,0,0)';
      BIDIRECTIONAL='TRUE';
      INPUT_LOAD='(-0.01,0.01)';
      OUTPUT_LOAD='(1.0,-1.0)';
      PINUSE='BI';
    'RSVD126':
      PIN_NUMBER='(0,CN62,0,0,0,0,0,0,0,0,0,0,0,0,0,0,0,0,0,0,0,0,0,0,0,0,0,0,0,~
0,0,0,0,0,0,0,0,0,0,0,0,0)';
      BIDIRECTIONAL='TRUE';
      INPUT_LOAD='(-0.01,0.01)';
      OUTPUT_LOAD='(1.0,-1.0)';
      PINUSE='BI';
    'RSVD132':
      PIN_NUMBER='(0,CR23,0,0,0,0,0,0,0,0,0,0,0,0,0,0,0,0,0,0,0,0,0,0,0,0,0,0,0,~
0,0,0,0,0,0,0,0,0,0,0,0,0)';
      BIDIRECTIONAL='TRUE';
      INPUT_LOAD='(-0.01,0.01)';
      OUTPUT_LOAD='(1.0,-1.0)';
      PINUSE='BI';
    'RSVD141':
      PIN_NUMBER='(0,CV24,0,0,0,0,0,0,0,0,0,0,0,0,0,0,0,0,0,0,0,0,0,0,0,0,0,0,0,~
0,0,0,0,0,0,0,0,0,0,0,0,0)';
      BIDIRECTIONAL='TRUE';
      INPUT_LOAD='(-0.01,0.01)';
      OUTPUT_LOAD='(1.0,-1.0)';
      PINUSE='BI';
    'RSVD145':
      PIN_NUMBER='(0,CW23,0,0,0,0,0,0,0,0,0,0,0,0,0,0,0,0,0,0,0,0,0,0,0,0,0,0,0,~
0,0,0,0,0,0,0,0,0,0,0,0,0)';
      BIDIRECTIONAL='TRUE';
      INPUT_LOAD='(-0.01,0.01)';
      OUTPUT_LOAD='(1.0,-1.0)';
      PINUSE='BI';
    'RSVD146':
      PIN_NUMBER='(0,CW25,0,0,0,0,0,0,0,0,0,0,0,0,0,0,0,0,0,0,0,0,0,0,0,0,0,0,0,~
0,0,0,0,0,0,0,0,0,0,0,0,0)';
      BIDIRECTIONAL='TRUE';
      INPUT_LOAD='(-0.01,0.01)';
      OUTPUT_LOAD='(1.0,-1.0)';
      PINUSE='BI';
    'RSVD150':
      PIN_NUMBER='(0,CW68,0,0,0,0,0,0,0,0,0,0,0,0,0,0,0,0,0,0,0,0,0,0,0,0,0,0,0,~
0,0,0,0,0,0,0,0,0,0,0,0,0)';
      BIDIRECTIONAL='TRUE';
      INPUT_LOAD='(-0.01,0.01)';
      OUTPUT_LOAD='(1.0,-1.0)';
      PINUSE='BI';
    'RSVD15':
      PIN_NUMBER='(0,AV26,0,0,0,0,0,0,0,0,0,0,0,0,0,0,0,0,0,0,0,0,0,0,0,0,0,0,0,~
0,0,0,0,0,0,0,0,0,0,0,0,0)';
      BIDIRECTIONAL='TRUE';
      INPUT_LOAD='(-0.01,0.01)';
      OUTPUT_LOAD='(1.0,-1.0)';
      PINUSE='BI';
    'RSVD27':
      PIN_NUMBER='(0,AY26,0,0,0,0,0,0,0,0,0,0,0,0,0,0,0,0,0,0,0,0,0,0,0,0,0,0,0,~
0,0,0,0,0,0,0,0,0,0,0,0,0)';
      BIDIRECTIONAL='TRUE';
      INPUT_LOAD='(-0.01,0.01)';
      OUTPUT_LOAD='(1.0,-1.0)';
      PINUSE='BI';
    'RSVD29':
      PIN_NUMBER='(0,AY65,0,0,0,0,0,0,0,0,0,0,0,0,0,0,0,0,0,0,0,0,0,0,0,0,0,0,0,~
0,0,0,0,0,0,0,0,0,0,0,0,0)';
      BIDIRECTIONAL='TRUE';
      INPUT_LOAD='(-0.01,0.01)';
      OUTPUT_LOAD='(1.0,-1.0)';
      PINUSE='BI';
    'RSVD4':
      PIN_NUMBER='(0,AT24,0,0,0,0,0,0,0,0,0,0,0,0,0,0,0,0,0,0,0,0,0,0,0,0,0,0,0,~
0,0,0,0,0,0,0,0,0,0,0,0,0)';
      BIDIRECTIONAL='TRUE';
      INPUT_LOAD='(-0.01,0.01)';
      OUTPUT_LOAD='(1.0,-1.0)';
      PINUSE='BI';
    'RSVD59':
      PIN_NUMBER='(0,BJ70,0,0,0,0,0,0,0,0,0,0,0,0,0,0,0,0,0,0,0,0,0,0,0,0,0,0,0,~
0,0,0,0,0,0,0,0,0,0,0,0,0)';
      BIDIRECTIONAL='TRUE';
      INPUT_LOAD='(-0.01,0.01)';
      OUTPUT_LOAD='(1.0,-1.0)';
      PINUSE='BI';
    'RSVD6':
      PIN_NUMBER='(0,AU25,0,0,0,0,0,0,0,0,0,0,0,0,0,0,0,0,0,0,0,0,0,0,0,0,0,0,0,~
0,0,0,0,0,0,0,0,0,0,0,0,0)';
      BIDIRECTIONAL='TRUE';
      INPUT_LOAD='(-0.01,0.01)';
      OUTPUT_LOAD='(1.0,-1.0)';
      PINUSE='BI';
    'RSVD69':
      PIN_NUMBER='(0,BP67,0,0,0,0,0,0,0,0,0,0,0,0,0,0,0,0,0,0,0,0,0,0,0,0,0,0,0,~
0,0,0,0,0,0,0,0,0,0,0,0,0)';
      BIDIRECTIONAL='TRUE';
      INPUT_LOAD='(-0.01,0.01)';
      OUTPUT_LOAD='(1.0,-1.0)';
      PINUSE='BI';
    'RSVD70':
      PIN_NUMBER='(0,BP69,0,0,0,0,0,0,0,0,0,0,0,0,0,0,0,0,0,0,0,0,0,0,0,0,0,0,0,~
0,0,0,0,0,0,0,0,0,0,0,0,0)';
      BIDIRECTIONAL='TRUE';
      INPUT_LOAD='(-0.01,0.01)';
      OUTPUT_LOAD='(1.0,-1.0)';
      PINUSE='BI';
    'RSVD104':
      PIN_NUMBER='(0,CJ62,0,0,0,0,0,0,0,0,0,0,0,0,0,0,0,0,0,0,0,0,0,0,0,0,0,0,0,~
0,0,0,0,0,0,0,0,0,0,0,0,0)';
      BIDIRECTIONAL='TRUE';
      INPUT_LOAD='(-0.01,0.01)';
      OUTPUT_LOAD='(1.0,-1.0)';
      PINUSE='BI';
    'SKTOCC_N':
      PIN_NUMBER='(0,CG66,0,0,0,0,0,0,0,0,0,0,0,0,0,0,0,0,0,0,0,0,0,0,0,0,0,0,0,~
0,0,0,0,0,0,0,0,0,0,0,0,0)';
      OUTPUT_LOAD='(1.0,-1.0)';
      PINUSE='OUT';
    'SVIDALERT0_N':
      PIN_NUMBER='(0,BK26,0,0,0,0,0,0,0,0,0,0,0,0,0,0,0,0,0,0,0,0,0,0,0,0,0,0,0,~
0,0,0,0,0,0,0,0,0,0,0,0,0)';
      INPUT_LOAD='(-0.01,0.01)';
      PINUSE='IN';
    'SVIDALERT1_N':
      PIN_NUMBER='(0,BJ25,0,0,0,0,0,0,0,0,0,0,0,0,0,0,0,0,0,0,0,0,0,0,0,0,0,0,0,~
0,0,0,0,0,0,0,0,0,0,0,0,0)';
      INPUT_LOAD='(-0.01,0.01)';
      PINUSE='IN';
    'SVIDCLK0':
      PIN_NUMBER='(0,BH26,0,0,0,0,0,0,0,0,0,0,0,0,0,0,0,0,0,0,0,0,0,0,0,0,0,0,0,~
0,0,0,0,0,0,0,0,0,0,0,0,0)';
      OUTPUT_LOAD='(1.0,-1.0)';
      PINUSE='OUT';
    'SVIDCLK1':
      PIN_NUMBER='(0,BF26,0,0,0,0,0,0,0,0,0,0,0,0,0,0,0,0,0,0,0,0,0,0,0,0,0,0,0,~
0,0,0,0,0,0,0,0,0,0,0,0,0)';
      OUTPUT_LOAD='(1.0,-1.0)';
      PINUSE='OUT';
    'SVIDDATA0':
      PIN_NUMBER='(0,BD26,0,0,0,0,0,0,0,0,0,0,0,0,0,0,0,0,0,0,0,0,0,0,0,0,0,0,0,~
0,0,0,0,0,0,0,0,0,0,0,0,0)';
      BIDIRECTIONAL='TRUE';
      INPUT_LOAD='(-0.01,0.01)';
      OUTPUT_LOAD='(1.0,-1.0)';
      PINUSE='BI';
    'SVIDDATA1':
      PIN_NUMBER='(0,BL25,0,0,0,0,0,0,0,0,0,0,0,0,0,0,0,0,0,0,0,0,0,0,0,0,0,0,0,~
0,0,0,0,0,0,0,0,0,0,0,0,0)';
      BIDIRECTIONAL='TRUE';
      INPUT_LOAD='(-0.01,0.01)';
      OUTPUT_LOAD='(1.0,-1.0)';
      PINUSE='BI';
    'TAP_ODT_EN':
      PIN_NUMBER='(0,AY20,0,0,0,0,0,0,0,0,0,0,0,0,0,0,0,0,0,0,0,0,0,0,0,0,0,0,0,~
0,0,0,0,0,0,0,0,0,0,0,0,0)';
      INPUT_LOAD='(-0.01,0.01)';
      PINUSE='IN';
    'RSVD19':
      PIN_NUMBER='(0,AV59,0,0,0,0,0,0,0,0,0,0,0,0,0,0,0,0,0,0,0,0,0,0,0,0,0,0,0,~
0,0,0,0,0,0,0,0,0,0,0,0,0)';
      BIDIRECTIONAL='TRUE';
      INPUT_LOAD='(-0.01,0.01)';
      OUTPUT_LOAD='(1.0,-1.0)';
      PINUSE='BI';
    'THERMTRIP_N':
      PIN_NUMBER='(0,BL62,0,0,0,0,0,0,0,0,0,0,0,0,0,0,0,0,0,0,0,0,0,0,0,0,0,0,0,~
0,0,0,0,0,0,0,0,0,0,0,0,0)';
      OUTPUT_LOAD='(1.0,-1.0)';
      PINUSE='OUT';
    'PLT_AUX_PWRGOOD':
      PIN_NUMBER='(0,0,CV20,0,0,0,0,0,0,0,0,0,0,0,0,0,0,0,0,0,0,0,0,0,0,0,0,0,0,~
0,0,0,0,0,0,0,0,0,0,0,0,0)';
      INPUT_LOAD='(-0.01,0.01)';
      PINUSE='IN';
    'RSVD109':
      PIN_NUMBER='(0,0,CK22,0,0,0,0,0,0,0,0,0,0,0,0,0,0,0,0,0,0,0,0,0,0,0,0,0,0,~
0,0,0,0,0,0,0,0,0,0,0,0,0)';
      BIDIRECTIONAL='TRUE';
      INPUT_LOAD='(-0.01,0.01)';
      OUTPUT_LOAD='(1.0,-1.0)';
      PINUSE='BI';
    'RSVD110':
      PIN_NUMBER='(0,0,CK24,0,0,0,0,0,0,0,0,0,0,0,0,0,0,0,0,0,0,0,0,0,0,0,0,0,0,~
0,0,0,0,0,0,0,0,0,0,0,0,0)';
      BIDIRECTIONAL='TRUE';
      INPUT_LOAD='(-0.01,0.01)';
      OUTPUT_LOAD='(1.0,-1.0)';
      PINUSE='BI';
    'RSVD114':
      PIN_NUMBER='(0,0,CL23,0,0,0,0,0,0,0,0,0,0,0,0,0,0,0,0,0,0,0,0,0,0,0,0,0,0,~
0,0,0,0,0,0,0,0,0,0,0,0,0)';
      BIDIRECTIONAL='TRUE';
      INPUT_LOAD='(-0.01,0.01)';
      OUTPUT_LOAD='(1.0,-1.0)';
      PINUSE='BI';
    'RSVD11':
      PIN_NUMBER='(0,0,AU62,0,0,0,0,0,0,0,0,0,0,0,0,0,0,0,0,0,0,0,0,0,0,0,0,0,0,~
0,0,0,0,0,0,0,0,0,0,0,0,0)';
      BIDIRECTIONAL='TRUE';
      INPUT_LOAD='(-0.01,0.01)';
      OUTPUT_LOAD='(1.0,-1.0)';
      PINUSE='BI';
    'RSVD117':
      PIN_NUMBER='(0,0,CL66,0,0,0,0,0,0,0,0,0,0,0,0,0,0,0,0,0,0,0,0,0,0,0,0,0,0,~
0,0,0,0,0,0,0,0,0,0,0,0,0)';
      BIDIRECTIONAL='TRUE';
      INPUT_LOAD='(-0.01,0.01)';
      OUTPUT_LOAD='(1.0,-1.0)';
      PINUSE='BI';
    'RSVD123':
      PIN_NUMBER='(0,0,CN21,0,0,0,0,0,0,0,0,0,0,0,0,0,0,0,0,0,0,0,0,0,0,0,0,0,0,~
0,0,0,0,0,0,0,0,0,0,0,0,0)';
      BIDIRECTIONAL='TRUE';
      INPUT_LOAD='(-0.01,0.01)';
      OUTPUT_LOAD='(1.0,-1.0)';
      PINUSE='BI';
    'RSVD124':
      PIN_NUMBER='(0,0,CN23,0,0,0,0,0,0,0,0,0,0,0,0,0,0,0,0,0,0,0,0,0,0,0,0,0,0,~
0,0,0,0,0,0,0,0,0,0,0,0,0)';
      BIDIRECTIONAL='TRUE';
      INPUT_LOAD='(-0.01,0.01)';
      OUTPUT_LOAD='(1.0,-1.0)';
      PINUSE='BI';
    'RSVD12':
      PIN_NUMBER='(0,0,AU64,0,0,0,0,0,0,0,0,0,0,0,0,0,0,0,0,0,0,0,0,0,0,0,0,0,0,~
0,0,0,0,0,0,0,0,0,0,0,0,0)';
      BIDIRECTIONAL='TRUE';
      INPUT_LOAD='(-0.01,0.01)';
      OUTPUT_LOAD='(1.0,-1.0)';
      PINUSE='BI';
    'RSVD127':
      PIN_NUMBER='(0,0,CP22,0,0,0,0,0,0,0,0,0,0,0,0,0,0,0,0,0,0,0,0,0,0,0,0,0,0,~
0,0,0,0,0,0,0,0,0,0,0,0,0)';
      BIDIRECTIONAL='TRUE';
      INPUT_LOAD='(-0.01,0.01)';
      OUTPUT_LOAD='(1.0,-1.0)';
      PINUSE='BI';
    'RSVD128':
      PIN_NUMBER='(0,0,CP24,0,0,0,0,0,0,0,0,0,0,0,0,0,0,0,0,0,0,0,0,0,0,0,0,0,0,~
0,0,0,0,0,0,0,0,0,0,0,0,0)';
      BIDIRECTIONAL='TRUE';
      INPUT_LOAD='(-0.01,0.01)';
      OUTPUT_LOAD='(1.0,-1.0)';
      PINUSE='BI';
    'RSVD131':
      PIN_NUMBER='(0,0,CR21,0,0,0,0,0,0,0,0,0,0,0,0,0,0,0,0,0,0,0,0,0,0,0,0,0,0,~
0,0,0,0,0,0,0,0,0,0,0,0,0)';
      BIDIRECTIONAL='TRUE';
      INPUT_LOAD='(-0.01,0.01)';
      OUTPUT_LOAD='(1.0,-1.0)';
      PINUSE='BI';
    'RSVD136':
      PIN_NUMBER='(0,0,CT22,0,0,0,0,0,0,0,0,0,0,0,0,0,0,0,0,0,0,0,0,0,0,0,0,0,0,~
0,0,0,0,0,0,0,0,0,0,0,0,0)';
      BIDIRECTIONAL='TRUE';
      INPUT_LOAD='(-0.01,0.01)';
      OUTPUT_LOAD='(1.0,-1.0)';
      PINUSE='BI';
    'RSVD137':
      PIN_NUMBER='(0,0,CT24,0,0,0,0,0,0,0,0,0,0,0,0,0,0,0,0,0,0,0,0,0,0,0,0,0,0,~
0,0,0,0,0,0,0,0,0,0,0,0,0)';
      BIDIRECTIONAL='TRUE';
      INPUT_LOAD='(-0.01,0.01)';
      OUTPUT_LOAD='(1.0,-1.0)';
      PINUSE='BI';
    'RSVD140':
      PIN_NUMBER='(0,0,CV22,0,0,0,0,0,0,0,0,0,0,0,0,0,0,0,0,0,0,0,0,0,0,0,0,0,0,~
0,0,0,0,0,0,0,0,0,0,0,0,0)';
      BIDIRECTIONAL='TRUE';
      INPUT_LOAD='(-0.01,0.01)';
      OUTPUT_LOAD='(1.0,-1.0)';
      PINUSE='BI';
    'RSVD142':
      PIN_NUMBER='(0,0,CV69,0,0,0,0,0,0,0,0,0,0,0,0,0,0,0,0,0,0,0,0,0,0,0,0,0,0,~
0,0,0,0,0,0,0,0,0,0,0,0,0)';
      BIDIRECTIONAL='TRUE';
      INPUT_LOAD='(-0.01,0.01)';
      OUTPUT_LOAD='(1.0,-1.0)';
      PINUSE='BI';
    'RSVD143':
      PIN_NUMBER='(0,0,CV71,0,0,0,0,0,0,0,0,0,0,0,0,0,0,0,0,0,0,0,0,0,0,0,0,0,0,~
0,0,0,0,0,0,0,0,0,0,0,0,0)';
      BIDIRECTIONAL='TRUE';
      INPUT_LOAD='(-0.01,0.01)';
      OUTPUT_LOAD='(1.0,-1.0)';
      PINUSE='BI';
    'RSVD144':
      PIN_NUMBER='(0,0,CW21,0,0,0,0,0,0,0,0,0,0,0,0,0,0,0,0,0,0,0,0,0,0,0,0,0,0,~
0,0,0,0,0,0,0,0,0,0,0,0,0)';
      BIDIRECTIONAL='TRUE';
      INPUT_LOAD='(-0.01,0.01)';
      OUTPUT_LOAD='(1.0,-1.0)';
      PINUSE='BI';
    'CD_INIT_ERROR':
      PIN_NUMBER='(0,0,CY20,0,0,0,0,0,0,0,0,0,0,0,0,0,0,0,0,0,0,0,0,0,0,0,0,0,0,~
0,0,0,0,0,0,0,0,0,0,0,0,0)';
      OUTPUT_LOAD='(1.0,-1.0)';
      PINUSE='OUT';
    'TEST_5':
      PIN_NUMBER='(0,0,CY22,0,0,0,0,0,0,0,0,0,0,0,0,0,0,0,0,0,0,0,0,0,0,0,0,0,0,~
0,0,0,0,0,0,0,0,0,0,0,0,0)';
      BIDIRECTIONAL='TRUE';
      INPUT_LOAD='(-0.01,0.01)';
      OUTPUT_LOAD='(1.0,-1.0)';
      PINUSE='BI';
    'RSVD155':
      PIN_NUMBER='(0,0,CY69,0,0,0,0,0,0,0,0,0,0,0,0,0,0,0,0,0,0,0,0,0,0,0,0,0,0,~
0,0,0,0,0,0,0,0,0,0,0,0,0)';
      BIDIRECTIONAL='TRUE';
      INPUT_LOAD='(-0.01,0.01)';
      OUTPUT_LOAD='(1.0,-1.0)';
      PINUSE='BI';
    'RSVD156':
      PIN_NUMBER='(0,0,CY71,0,0,0,0,0,0,0,0,0,0,0,0,0,0,0,0,0,0,0,0,0,0,0,0,0,0,~
0,0,0,0,0,0,0,0,0,0,0,0,0)';
      BIDIRECTIONAL='TRUE';
      INPUT_LOAD='(-0.01,0.01)';
      OUTPUT_LOAD='(1.0,-1.0)';
      PINUSE='BI';
    'RSVD20':
      PIN_NUMBER='(0,0,AV63,0,0,0,0,0,0,0,0,0,0,0,0,0,0,0,0,0,0,0,0,0,0,0,0,0,0,~
0,0,0,0,0,0,0,0,0,0,0,0,0)';
      BIDIRECTIONAL='TRUE';
      INPUT_LOAD='(-0.01,0.01)';
      OUTPUT_LOAD='(1.0,-1.0)';
      PINUSE='BI';
    'RSVD23':
      PIN_NUMBER='(0,0,AW19,0,0,0,0,0,0,0,0,0,0,0,0,0,0,0,0,0,0,0,0,0,0,0,0,0,0,~
0,0,0,0,0,0,0,0,0,0,0,0,0)';
      BIDIRECTIONAL='TRUE';
      INPUT_LOAD='(-0.01,0.01)';
      OUTPUT_LOAD='(1.0,-1.0)';
      PINUSE='BI';
    'RSVD24':
      PIN_NUMBER='(0,0,AW64,0,0,0,0,0,0,0,0,0,0,0,0,0,0,0,0,0,0,0,0,0,0,0,0,0,0,~
0,0,0,0,0,0,0,0,0,0,0,0,0)';
      BIDIRECTIONAL='TRUE';
      INPUT_LOAD='(-0.01,0.01)';
      OUTPUT_LOAD='(1.0,-1.0)';
      PINUSE='BI';
    'RSVD28':
      PIN_NUMBER='(0,0,AY61,0,0,0,0,0,0,0,0,0,0,0,0,0,0,0,0,0,0,0,0,0,0,0,0,0,0,~
0,0,0,0,0,0,0,0,0,0,0,0,0)';
      BIDIRECTIONAL='TRUE';
      INPUT_LOAD='(-0.01,0.01)';
      OUTPUT_LOAD='(1.0,-1.0)';
      PINUSE='BI';
    'RSVD30':
      PIN_NUMBER='(0,0,AY67,0,0,0,0,0,0,0,0,0,0,0,0,0,0,0,0,0,0,0,0,0,0,0,0,0,0,~
0,0,0,0,0,0,0,0,0,0,0,0,0)';
      BIDIRECTIONAL='TRUE';
      INPUT_LOAD='(-0.01,0.01)';
      OUTPUT_LOAD='(1.0,-1.0)';
      PINUSE='BI';
    'RSVD32':
      PIN_NUMBER='(0,0,BA62,0,0,0,0,0,0,0,0,0,0,0,0,0,0,0,0,0,0,0,0,0,0,0,0,0,0,~
0,0,0,0,0,0,0,0,0,0,0,0,0)';
      BIDIRECTIONAL='TRUE';
      INPUT_LOAD='(-0.01,0.01)';
      OUTPUT_LOAD='(1.0,-1.0)';
      PINUSE='BI';
    'RSVD33':
      PIN_NUMBER='(0,0,BA66,0,0,0,0,0,0,0,0,0,0,0,0,0,0,0,0,0,0,0,0,0,0,0,0,0,0,~
0,0,0,0,0,0,0,0,0,0,0,0,0)';
      BIDIRECTIONAL='TRUE';
      INPUT_LOAD='(-0.01,0.01)';
      OUTPUT_LOAD='(1.0,-1.0)';
      PINUSE='BI';
    'RSVD34':
      PIN_NUMBER='(0,0,BA68,0,0,0,0,0,0,0,0,0,0,0,0,0,0,0,0,0,0,0,0,0,0,0,0,0,0,~
0,0,0,0,0,0,0,0,0,0,0,0,0)';
      BIDIRECTIONAL='TRUE';
      INPUT_LOAD='(-0.01,0.01)';
      OUTPUT_LOAD='(1.0,-1.0)';
      PINUSE='BI';
    'RSVD35':
      PIN_NUMBER='(0,0,BB61,0,0,0,0,0,0,0,0,0,0,0,0,0,0,0,0,0,0,0,0,0,0,0,0,0,0,~
0,0,0,0,0,0,0,0,0,0,0,0,0)';
      BIDIRECTIONAL='TRUE';
      INPUT_LOAD='(-0.01,0.01)';
      OUTPUT_LOAD='(1.0,-1.0)';
      PINUSE='BI';
    'RSVD36':
      PIN_NUMBER='(0,0,BB67,0,0,0,0,0,0,0,0,0,0,0,0,0,0,0,0,0,0,0,0,0,0,0,0,0,0,~
0,0,0,0,0,0,0,0,0,0,0,0,0)';
      BIDIRECTIONAL='TRUE';
      INPUT_LOAD='(-0.01,0.01)';
      OUTPUT_LOAD='(1.0,-1.0)';
      PINUSE='BI';
    'RSVD38':
      PIN_NUMBER='(0,0,BC25,0,0,0,0,0,0,0,0,0,0,0,0,0,0,0,0,0,0,0,0,0,0,0,0,0,0,~
0,0,0,0,0,0,0,0,0,0,0,0,0)';
      BIDIRECTIONAL='TRUE';
      INPUT_LOAD='(-0.01,0.01)';
      OUTPUT_LOAD='(1.0,-1.0)';
      PINUSE='BI';
    'RSVD39':
      PIN_NUMBER='(0,0,BC64,0,0,0,0,0,0,0,0,0,0,0,0,0,0,0,0,0,0,0,0,0,0,0,0,0,0,~
0,0,0,0,0,0,0,0,0,0,0,0,0)';
      BIDIRECTIONAL='TRUE';
      INPUT_LOAD='(-0.01,0.01)';
      OUTPUT_LOAD='(1.0,-1.0)';
      PINUSE='BI';
    'RSVD40':
      PIN_NUMBER='(0,0,BD61,0,0,0,0,0,0,0,0,0,0,0,0,0,0,0,0,0,0,0,0,0,0,0,0,0,0,~
0,0,0,0,0,0,0,0,0,0,0,0,0)';
      BIDIRECTIONAL='TRUE';
      INPUT_LOAD='(-0.01,0.01)';
      OUTPUT_LOAD='(1.0,-1.0)';
      PINUSE='BI';
    'RSVD41':
      PIN_NUMBER='(0,0,BD63,0,0,0,0,0,0,0,0,0,0,0,0,0,0,0,0,0,0,0,0,0,0,0,0,0,0,~
0,0,0,0,0,0,0,0,0,0,0,0,0)';
      BIDIRECTIONAL='TRUE';
      INPUT_LOAD='(-0.01,0.01)';
      OUTPUT_LOAD='(1.0,-1.0)';
      PINUSE='BI';
    'RSVD42':
      PIN_NUMBER='(0,0,BD65,0,0,0,0,0,0,0,0,0,0,0,0,0,0,0,0,0,0,0,0,0,0,0,0,0,0,~
0,0,0,0,0,0,0,0,0,0,0,0,0)';
      BIDIRECTIONAL='TRUE';
      INPUT_LOAD='(-0.01,0.01)';
      OUTPUT_LOAD='(1.0,-1.0)';
      PINUSE='BI';
    'RSVD47':
      PIN_NUMBER='(0,0,BE25,0,0,0,0,0,0,0,0,0,0,0,0,0,0,0,0,0,0,0,0,0,0,0,0,0,0,~
0,0,0,0,0,0,0,0,0,0,0,0,0)';
      BIDIRECTIONAL='TRUE';
      INPUT_LOAD='(-0.01,0.01)';
      OUTPUT_LOAD='(1.0,-1.0)';
      PINUSE='BI';
    'RSVD48':
      PIN_NUMBER='(0,0,BE62,0,0,0,0,0,0,0,0,0,0,0,0,0,0,0,0,0,0,0,0,0,0,0,0,0,0,~
0,0,0,0,0,0,0,0,0,0,0,0,0)';
      BIDIRECTIONAL='TRUE';
      INPUT_LOAD='(-0.01,0.01)';
      OUTPUT_LOAD='(1.0,-1.0)';
      PINUSE='BI';
    'RSVD50':
      PIN_NUMBER='(0,0,BF65,0,0,0,0,0,0,0,0,0,0,0,0,0,0,0,0,0,0,0,0,0,0,0,0,0,0,~
0,0,0,0,0,0,0,0,0,0,0,0,0)';
      BIDIRECTIONAL='TRUE';
      INPUT_LOAD='(-0.01,0.01)';
      OUTPUT_LOAD='(1.0,-1.0)';
      PINUSE='BI';
    'RSVD52':
      PIN_NUMBER='(0,0,BG62,0,0,0,0,0,0,0,0,0,0,0,0,0,0,0,0,0,0,0,0,0,0,0,0,0,0,~
0,0,0,0,0,0,0,0,0,0,0,0,0)';
      BIDIRECTIONAL='TRUE';
      INPUT_LOAD='(-0.01,0.01)';
      OUTPUT_LOAD='(1.0,-1.0)';
      PINUSE='BI';
    'RSVD53':
      PIN_NUMBER='(0,0,BG64,0,0,0,0,0,0,0,0,0,0,0,0,0,0,0,0,0,0,0,0,0,0,0,0,0,0,~
0,0,0,0,0,0,0,0,0,0,0,0,0)';
      BIDIRECTIONAL='TRUE';
      INPUT_LOAD='(-0.01,0.01)';
      OUTPUT_LOAD='(1.0,-1.0)';
      PINUSE='BI';
    'RSVD55':
      PIN_NUMBER='(0,0,BH63,0,0,0,0,0,0,0,0,0,0,0,0,0,0,0,0,0,0,0,0,0,0,0,0,0,0,~
0,0,0,0,0,0,0,0,0,0,0,0,0)';
      BIDIRECTIONAL='TRUE';
      INPUT_LOAD='(-0.01,0.01)';
      OUTPUT_LOAD='(1.0,-1.0)';
      PINUSE='BI';
    'RSVD56':
      PIN_NUMBER='(0,0,BH65,0,0,0,0,0,0,0,0,0,0,0,0,0,0,0,0,0,0,0,0,0,0,0,0,0,0,~
0,0,0,0,0,0,0,0,0,0,0,0,0)';
      BIDIRECTIONAL='TRUE';
      INPUT_LOAD='(-0.01,0.01)';
      OUTPUT_LOAD='(1.0,-1.0)';
      PINUSE='BI';
    'RSVD58':
      PIN_NUMBER='(0,0,BJ64,0,0,0,0,0,0,0,0,0,0,0,0,0,0,0,0,0,0,0,0,0,0,0,0,0,0,~
0,0,0,0,0,0,0,0,0,0,0,0,0)';
      BIDIRECTIONAL='TRUE';
      INPUT_LOAD='(-0.01,0.01)';
      OUTPUT_LOAD='(1.0,-1.0)';
      PINUSE='BI';
    'RSVD61':
      PIN_NUMBER='(0,0,BK63,0,0,0,0,0,0,0,0,0,0,0,0,0,0,0,0,0,0,0,0,0,0,0,0,0,0,~
0,0,0,0,0,0,0,0,0,0,0,0,0)';
      BIDIRECTIONAL='TRUE';
      INPUT_LOAD='(-0.01,0.01)';
      OUTPUT_LOAD='(1.0,-1.0)';
      PINUSE='BI';
    'RSVD64':
      PIN_NUMBER='(0,0,BM63,0,0,0,0,0,0,0,0,0,0,0,0,0,0,0,0,0,0,0,0,0,0,0,0,0,0,~
0,0,0,0,0,0,0,0,0,0,0,0,0)';
      BIDIRECTIONAL='TRUE';
      INPUT_LOAD='(-0.01,0.01)';
      OUTPUT_LOAD='(1.0,-1.0)';
      PINUSE='BI';
    'RSVD86':
      PIN_NUMBER='(0,0,CD65,0,0,0,0,0,0,0,0,0,0,0,0,0,0,0,0,0,0,0,0,0,0,0,0,0,0,~
0,0,0,0,0,0,0,0,0,0,0,0,0)';
      BIDIRECTIONAL='TRUE';
      INPUT_LOAD='(-0.01,0.01)';
      OUTPUT_LOAD='(1.0,-1.0)';
      PINUSE='BI';
    'TEST_6':
      PIN_NUMBER='(0,0,CF61,0,0,0,0,0,0,0,0,0,0,0,0,0,0,0,0,0,0,0,0,0,0,0,0,0,0,~
0,0,0,0,0,0,0,0,0,0,0,0,0)';
      BIDIRECTIONAL='TRUE';
      INPUT_LOAD='(-0.01,0.01)';
      OUTPUT_LOAD='(1.0,-1.0)';
      PINUSE='BI';
    'RSVD93':
      PIN_NUMBER='(0,0,CF63,0,0,0,0,0,0,0,0,0,0,0,0,0,0,0,0,0,0,0,0,0,0,0,0,0,0,~
0,0,0,0,0,0,0,0,0,0,0,0,0)';
      BIDIRECTIONAL='TRUE';
      INPUT_LOAD='(-0.01,0.01)';
      OUTPUT_LOAD='(1.0,-1.0)';
      PINUSE='BI';
    'RSVD94':
      PIN_NUMBER='(0,0,CF65,0,0,0,0,0,0,0,0,0,0,0,0,0,0,0,0,0,0,0,0,0,0,0,0,0,0,~
0,0,0,0,0,0,0,0,0,0,0,0,0)';
      BIDIRECTIONAL='TRUE';
      INPUT_LOAD='(-0.01,0.01)';
      OUTPUT_LOAD='(1.0,-1.0)';
      PINUSE='BI';
    'RSVD98':
      PIN_NUMBER='(0,0,CH63,0,0,0,0,0,0,0,0,0,0,0,0,0,0,0,0,0,0,0,0,0,0,0,0,0,0,~
0,0,0,0,0,0,0,0,0,0,0,0,0)';
      BIDIRECTIONAL='TRUE';
      INPUT_LOAD='(-0.01,0.01)';
      OUTPUT_LOAD='(1.0,-1.0)';
      PINUSE='BI';
    'RSVD100':
      PIN_NUMBER='(0,0,CH71,0,0,0,0,0,0,0,0,0,0,0,0,0,0,0,0,0,0,0,0,0,0,0,0,0,0,~
0,0,0,0,0,0,0,0,0,0,0,0,0)';
      BIDIRECTIONAL='TRUE';
      INPUT_LOAD='(-0.01,0.01)';
      OUTPUT_LOAD='(1.0,-1.0)';
      PINUSE='BI';
    'RSVD101':
      PIN_NUMBER='(0,0,CJ21,0,0,0,0,0,0,0,0,0,0,0,0,0,0,0,0,0,0,0,0,0,0,0,0,0,0,~
0,0,0,0,0,0,0,0,0,0,0,0,0)';
      BIDIRECTIONAL='TRUE';
      INPUT_LOAD='(-0.01,0.01)';
      OUTPUT_LOAD='(1.0,-1.0)';
      PINUSE='BI';
    'RSVD102':
      PIN_NUMBER='(0,0,CJ23,0,0,0,0,0,0,0,0,0,0,0,0,0,0,0,0,0,0,0,0,0,0,0,0,0,0,~
0,0,0,0,0,0,0,0,0,0,0,0,0)';
      BIDIRECTIONAL='TRUE';
      INPUT_LOAD='(-0.01,0.01)';
      OUTPUT_LOAD='(1.0,-1.0)';
      PINUSE='BI';
    'RSVD103':
      PIN_NUMBER='(0,0,CJ25,0,0,0,0,0,0,0,0,0,0,0,0,0,0,0,0,0,0,0,0,0,0,0,0,0,0,~
0,0,0,0,0,0,0,0,0,0,0,0,0)';
      BIDIRECTIONAL='TRUE';
      INPUT_LOAD='(-0.01,0.01)';
      OUTPUT_LOAD='(1.0,-1.0)';
      PINUSE='BI';
    'RSVD105':
      PIN_NUMBER='(0,0,CJ66,0,0,0,0,0,0,0,0,0,0,0,0,0,0,0,0,0,0,0,0,0,0,0,0,0,0,~
0,0,0,0,0,0,0,0,0,0,0,0,0)';
      BIDIRECTIONAL='TRUE';
      INPUT_LOAD='(-0.01,0.01)';
      OUTPUT_LOAD='(1.0,-1.0)';
      PINUSE='BI';
    'RSVD25':
      PIN_NUMBER='(0,0,AW70,0,0,0,0,0,0,0,0,0,0,0,0,0,0,0,0,0,0,0,0,0,0,0,0,0,0,~
0,0,0,0,0,0,0,0,0,0,0,0,0)';
      BIDIRECTIONAL='TRUE';
      INPUT_LOAD='(-0.01,0.01)';
      OUTPUT_LOAD='(1.0,-1.0)';
      PINUSE='BI';
    'TEST_8':
      PIN_NUMBER='(0,0,AY69,0,0,0,0,0,0,0,0,0,0,0,0,0,0,0,0,0,0,0,0,0,0,0,0,0,0,~
0,0,0,0,0,0,0,0,0,0,0,0,0)';
      BIDIRECTIONAL='TRUE';
      INPUT_LOAD='(-0.01,0.01)';
      OUTPUT_LOAD='(1.0,-1.0)';
      PINUSE='BI';
    'TEST_7':
      PIN_NUMBER='(0,0,AV69,0,0,0,0,0,0,0,0,0,0,0,0,0,0,0,0,0,0,0,0,0,0,0,0,0,0,~
0,0,0,0,0,0,0,0,0,0,0,0,0)';
      BIDIRECTIONAL='TRUE';
      INPUT_LOAD='(-0.01,0.01)';
      OUTPUT_LOAD='(1.0,-1.0)';
      PINUSE='BI';
    'PARTITION_ID1':
      PIN_NUMBER='(0,0,AV71,0,0,0,0,0,0,0,0,0,0,0,0,0,0,0,0,0,0,0,0,0,0,0,0,0,0,~
0,0,0,0,0,0,0,0,0,0,0,0,0)';
      INPUT_LOAD='(-0.01,0.01)';
      PINUSE='IN';
    'PARTITION_ID0':
      PIN_NUMBER='(0,0,BA70,0,0,0,0,0,0,0,0,0,0,0,0,0,0,0,0,0,0,0,0,0,0,0,0,0,0,~
0,0,0,0,0,0,0,0,0,0,0,0,0)';
      INPUT_LOAD='(-0.01,0.01)';
      PINUSE='IN';
    'SMB_CLK':
      PIN_NUMBER='(0,0,CE64,0,0,0,0,0,0,0,0,0,0,0,0,0,0,0,0,0,0,0,0,0,0,0,0,0,0,~
0,0,0,0,0,0,0,0,0,0,0,0,0)';
      OUTPUT_LOAD='(1.0,-1.0)';
      PINUSE='OUT';
    'SMB_DATA':
      PIN_NUMBER='(0,0,CD63,0,0,0,0,0,0,0,0,0,0,0,0,0,0,0,0,0,0,0,0,0,0,0,0,0,0,~
0,0,0,0,0,0,0,0,0,0,0,0,0)';
      BIDIRECTIONAL='TRUE';
      INPUT_LOAD='(-0.01,0.01)';
      OUTPUT_LOAD='(1.0,-1.0)';
      PINUSE='BI';
    'TEST_1':
      PIN_NUMBER='(0,0,CJ64,0,0,0,0,0,0,0,0,0,0,0,0,0,0,0,0,0,0,0,0,0,0,0,0,0,0,~
0,0,0,0,0,0,0,0,0,0,0,0,0)';
      BIDIRECTIONAL='TRUE';
      INPUT_LOAD='(-0.01,0.01)';
      OUTPUT_LOAD='(1.0,-1.0)';
      PINUSE='BI';
    'TEST_2':
      PIN_NUMBER='(0,0,CK65,0,0,0,0,0,0,0,0,0,0,0,0,0,0,0,0,0,0,0,0,0,0,0,0,0,0,~
0,0,0,0,0,0,0,0,0,0,0,0,0)';
      BIDIRECTIONAL='TRUE';
      INPUT_LOAD='(-0.01,0.01)';
      OUTPUT_LOAD='(1.0,-1.0)';
      PINUSE='BI';
    'TEST_3':
      PIN_NUMBER='(0,0,CH65,0,0,0,0,0,0,0,0,0,0,0,0,0,0,0,0,0,0,0,0,0,0,0,0,0,0,~
0,0,0,0,0,0,0,0,0,0,0,0,0)';
      BIDIRECTIONAL='TRUE';
      INPUT_LOAD='(-0.01,0.01)';
      OUTPUT_LOAD='(1.0,-1.0)';
      PINUSE='BI';
    'RSVD37':
      PIN_NUMBER='(0,0,0,BC23,0,0,0,0,0,0,0,0,0,0,0,0,0,0,0,0,0,0,0,0,0,0,0,0,0,~
0,0,0,0,0,0,0,0,0,0,0,0,0)';
      BIDIRECTIONAL='TRUE';
      INPUT_LOAD='(-0.01,0.01)';
      OUTPUT_LOAD='(1.0,-1.0)';
      PINUSE='BI';
    'RSVD46':
      PIN_NUMBER='(0,0,0,BE23,0,0,0,0,0,0,0,0,0,0,0,0,0,0,0,0,0,0,0,0,0,0,0,0,0,~
0,0,0,0,0,0,0,0,0,0,0,0,0)';
      BIDIRECTIONAL='TRUE';
      INPUT_LOAD='(-0.01,0.01)';
      OUTPUT_LOAD='(1.0,-1.0)';
      PINUSE='BI';
    'RSVD49':
      PIN_NUMBER='(0,0,0,BF24,0,0,0,0,0,0,0,0,0,0,0,0,0,0,0,0,0,0,0,0,0,0,0,0,0,~
0,0,0,0,0,0,0,0,0,0,0,0,0)';
      BIDIRECTIONAL='TRUE';
      INPUT_LOAD='(-0.01,0.01)';
      OUTPUT_LOAD='(1.0,-1.0)';
      PINUSE='BI';
    'MBP0_N':
      PIN_NUMBER='(0,0,0,BL23,0,0,0,0,0,0,0,0,0,0,0,0,0,0,0,0,0,0,0,0,0,0,0,0,0,~
0,0,0,0,0,0,0,0,0,0,0,0,0)';
      BIDIRECTIONAL='TRUE';
      INPUT_LOAD='(-0.01,0.01)';
      OUTPUT_LOAD='(1.0,-1.0)';
      PINUSE='BI';
    'MBP1_N':
      PIN_NUMBER='(0,0,0,BN25,0,0,0,0,0,0,0,0,0,0,0,0,0,0,0,0,0,0,0,0,0,0,0,0,0,~
0,0,0,0,0,0,0,0,0,0,0,0,0)';
      BIDIRECTIONAL='TRUE';
      INPUT_LOAD='(-0.01,0.01)';
      OUTPUT_LOAD='(1.0,-1.0)';
      PINUSE='BI';
    'MBP2_N':
      PIN_NUMBER='(0,0,0,BJ23,0,0,0,0,0,0,0,0,0,0,0,0,0,0,0,0,0,0,0,0,0,0,0,0,0,~
0,0,0,0,0,0,0,0,0,0,0,0,0)';
      BIDIRECTIONAL='TRUE';
      INPUT_LOAD='(-0.01,0.01)';
      OUTPUT_LOAD='(1.0,-1.0)';
      PINUSE='BI';
    'MBP3_N':
      PIN_NUMBER='(0,0,0,BK24,0,0,0,0,0,0,0,0,0,0,0,0,0,0,0,0,0,0,0,0,0,0,0,0,0,~
0,0,0,0,0,0,0,0,0,0,0,0,0)';
      BIDIRECTIONAL='TRUE';
      INPUT_LOAD='(-0.01,0.01)';
      OUTPUT_LOAD='(1.0,-1.0)';
      PINUSE='BI';
    'PMAX_TRIGGER_IO':
      PIN_NUMBER='(0,0,0,BD24,0,0,0,0,0,0,0,0,0,0,0,0,0,0,0,0,0,0,0,0,0,0,0,0,0,~
0,0,0,0,0,0,0,0,0,0,0,0,0)';
      BIDIRECTIONAL='TRUE';
      INPUT_LOAD='(-0.01,0.01)';
      OUTPUT_LOAD='(1.0,-1.0)';
      PINUSE='BI';
    'RMCA_N':
      PIN_NUMBER='(0,0,0,BH22,0,0,0,0,0,0,0,0,0,0,0,0,0,0,0,0,0,0,0,0,0,0,0,0,0,~
0,0,0,0,0,0,0,0,0,0,0,0,0)';
      BIDIRECTIONAL='TRUE';
      INPUT_LOAD='(-0.01,0.01)';
      OUTPUT_LOAD='(1.0,-1.0)';
      PINUSE='BI';
    'RSVD10':
      PIN_NUMBER='(0,0,0,AU58,0,0,0,0,0,0,0,0,0,0,0,0,0,0,0,0,0,0,0,0,0,0,0,0,0,~
0,0,0,0,0,0,0,0,0,0,0,0,0)';
      BIDIRECTIONAL='TRUE';
      INPUT_LOAD='(-0.01,0.01)';
      OUTPUT_LOAD='(1.0,-1.0)';
      PINUSE='BI';
    'RSVD90':
      PIN_NUMBER='(0,0,0,CE62,0,0,0,0,0,0,0,0,0,0,0,0,0,0,0,0,0,0,0,0,0,0,0,0,0,~
0,0,0,0,0,0,0,0,0,0,0,0,0)';
      BIDIRECTIONAL='TRUE';
      INPUT_LOAD='(-0.01,0.01)';
      OUTPUT_LOAD='(1.0,-1.0)';
      PINUSE='BI';
    'RSVD139':
      PIN_NUMBER='(0,0,0,CU62,0,0,0,0,0,0,0,0,0,0,0,0,0,0,0,0,0,0,0,0,0,0,0,0,0,~
0,0,0,0,0,0,0,0,0,0,0,0,0)';
      BIDIRECTIONAL='TRUE';
      INPUT_LOAD='(-0.01,0.01)';
      OUTPUT_LOAD='(1.0,-1.0)';
      PINUSE='BI';
    'RSVD125':
      PIN_NUMBER='(0,0,0,CN60,0,0,0,0,0,0,0,0,0,0,0,0,0,0,0,0,0,0,0,0,0,0,0,0,0,~
0,0,0,0,0,0,0,0,0,0,0,0,0)';
      BIDIRECTIONAL='TRUE';
      INPUT_LOAD='(-0.01,0.01)';
      OUTPUT_LOAD='(1.0,-1.0)';
      PINUSE='BI';
    'RSVD129':
      PIN_NUMBER='(0,0,0,CP61,0,0,0,0,0,0,0,0,0,0,0,0,0,0,0,0,0,0,0,0,0,0,0,0,0,~
0,0,0,0,0,0,0,0,0,0,0,0,0)';
      BIDIRECTIONAL='TRUE';
      INPUT_LOAD='(-0.01,0.01)';
      OUTPUT_LOAD='(1.0,-1.0)';
      PINUSE='BI';
    'RSVD134':
      PIN_NUMBER='(0,0,0,CR60,0,0,0,0,0,0,0,0,0,0,0,0,0,0,0,0,0,0,0,0,0,0,0,0,0,~
0,0,0,0,0,0,0,0,0,0,0,0,0)';
      BIDIRECTIONAL='TRUE';
      INPUT_LOAD='(-0.01,0.01)';
      OUTPUT_LOAD='(1.0,-1.0)';
      PINUSE='BI';
    'RSVD151':
      PIN_NUMBER='(0,0,0,CY24,0,0,0,0,0,0,0,0,0,0,0,0,0,0,0,0,0,0,0,0,0,0,0,0,0,~
0,0,0,0,0,0,0,0,0,0,0,0,0)';
      BIDIRECTIONAL='TRUE';
      INPUT_LOAD='(-0.01,0.01)';
      OUTPUT_LOAD='(1.0,-1.0)';
      PINUSE='BI';
    'RSVD152':
      PIN_NUMBER='(0,0,0,CY38,0,0,0,0,0,0,0,0,0,0,0,0,0,0,0,0,0,0,0,0,0,0,0,0,0,~
0,0,0,0,0,0,0,0,0,0,0,0,0)';
      BIDIRECTIONAL='TRUE';
      INPUT_LOAD='(-0.01,0.01)';
      OUTPUT_LOAD='(1.0,-1.0)';
      PINUSE='BI';
    'RSVD153':
      PIN_NUMBER='(0,0,0,CY49,0,0,0,0,0,0,0,0,0,0,0,0,0,0,0,0,0,0,0,0,0,0,0,0,0,~
0,0,0,0,0,0,0,0,0,0,0,0,0)';
      BIDIRECTIONAL='TRUE';
      INPUT_LOAD='(-0.01,0.01)';
      OUTPUT_LOAD='(1.0,-1.0)';
      PINUSE='BI';
    'RSVD158':
      PIN_NUMBER='(0,0,0,DA45,0,0,0,0,0,0,0,0,0,0,0,0,0,0,0,0,0,0,0,0,0,0,0,0,0,~
0,0,0,0,0,0,0,0,0,0,0,0,0)';
      BIDIRECTIONAL='TRUE';
      INPUT_LOAD='(-0.01,0.01)';
      OUTPUT_LOAD='(1.0,-1.0)';
      PINUSE='BI';
    'RSVD162':
      PIN_NUMBER='(0,0,0,H12,0,0,0,0,0,0,0,0,0,0,0,0,0,0,0,0,0,0,0,0,0,0,0,0,0,0~
,0,0,0,0,0,0,0,0,0,0,0,0)';
      BIDIRECTIONAL='TRUE';
      INPUT_LOAD='(-0.01,0.01)';
      OUTPUT_LOAD='(1.0,-1.0)';
      PINUSE='BI';
    'RSVD16':
      PIN_NUMBER='(0,0,0,AV32,0,0,0,0,0,0,0,0,0,0,0,0,0,0,0,0,0,0,0,0,0,0,0,0,0,~
0,0,0,0,0,0,0,0,0,0,0,0,0)';
      BIDIRECTIONAL='TRUE';
      INPUT_LOAD='(-0.01,0.01)';
      OUTPUT_LOAD='(1.0,-1.0)';
      PINUSE='BI';
    'RSVD17':
      PIN_NUMBER='(0,0,0,AV38,0,0,0,0,0,0,0,0,0,0,0,0,0,0,0,0,0,0,0,0,0,0,0,0,0,~
0,0,0,0,0,0,0,0,0,0,0,0,0)';
      BIDIRECTIONAL='TRUE';
      INPUT_LOAD='(-0.01,0.01)';
      OUTPUT_LOAD='(1.0,-1.0)';
      PINUSE='BI';
    'RSVD18':
      PIN_NUMBER='(0,0,0,AV40,0,0,0,0,0,0,0,0,0,0,0,0,0,0,0,0,0,0,0,0,0,0,0,0,0,~
0,0,0,0,0,0,0,0,0,0,0,0,0)';
      BIDIRECTIONAL='TRUE';
      INPUT_LOAD='(-0.01,0.01)';
      OUTPUT_LOAD='(1.0,-1.0)';
      PINUSE='BI';
    'RSVD7':
      PIN_NUMBER='(0,0,0,AU33,0,0,0,0,0,0,0,0,0,0,0,0,0,0,0,0,0,0,0,0,0,0,0,0,0,~
0,0,0,0,0,0,0,0,0,0,0,0,0)';
      BIDIRECTIONAL='TRUE';
      INPUT_LOAD='(-0.01,0.01)';
      OUTPUT_LOAD='(1.0,-1.0)';
      PINUSE='BI';
    'RSVD9':
      PIN_NUMBER='(0,0,0,AU56,0,0,0,0,0,0,0,0,0,0,0,0,0,0,0,0,0,0,0,0,0,0,0,0,0,~
0,0,0,0,0,0,0,0,0,0,0,0,0)';
      BIDIRECTIONAL='TRUE';
      INPUT_LOAD='(-0.01,0.01)';
      OUTPUT_LOAD='(1.0,-1.0)';
      PINUSE='BI';
    'RSVD81':
      PIN_NUMBER='(0,0,0,CC64,0,0,0,0,0,0,0,0,0,0,0,0,0,0,0,0,0,0,0,0,0,0,0,0,0,~
0,0,0,0,0,0,0,0,0,0,0,0,0)';
      BIDIRECTIONAL='TRUE';
      INPUT_LOAD='(-0.01,0.01)';
      OUTPUT_LOAD='(1.0,-1.0)';
      PINUSE='BI';
    'VCCD_HV_SENSE':
      PIN_NUMBER='(0,0,0,BU11,0,0,0,0,0,0,0,0,0,0,0,0,0,0,0,0,0,0,0,0,0,0,0,0,0,~
0,0,0,0,0,0,0,0,0,0,0,0,0)';
      PINUSE='POWER';
      NO_LOAD_CHECK='Both';
      NO_IO_CHECK='Both';
      NO_ASSERT_CHECK='TRUE';
      NO_DIR_CHECK='TRUE';
      ALLOW_CONNECT='TRUE';
    'VCCFA_EHV_FIVRA_SENSE':
      PIN_NUMBER='(0,0,0,AY85,0,0,0,0,0,0,0,0,0,0,0,0,0,0,0,0,0,0,0,0,0,0,0,0,0,~
0,0,0,0,0,0,0,0,0,0,0,0,0)';
      PINUSE='POWER';
      NO_LOAD_CHECK='Both';
      NO_IO_CHECK='Both';
      NO_ASSERT_CHECK='TRUE';
      NO_DIR_CHECK='TRUE';
      ALLOW_CONNECT='TRUE';
    'VCCFA_EHV_SENSE':
      PIN_NUMBER='(0,0,0,AU11,0,0,0,0,0,0,0,0,0,0,0,0,0,0,0,0,0,0,0,0,0,0,0,0,0,~
0,0,0,0,0,0,0,0,0,0,0,0,0)';
      PINUSE='POWER';
      NO_LOAD_CHECK='Both';
      NO_IO_CHECK='Both';
      NO_ASSERT_CHECK='TRUE';
      NO_DIR_CHECK='TRUE';
      ALLOW_CONNECT='TRUE';
    'VCCINFAON_SENSE':
      PIN_NUMBER='(0,0,0,CA11,0,0,0,0,0,0,0,0,0,0,0,0,0,0,0,0,0,0,0,0,0,0,0,0,0,~
0,0,0,0,0,0,0,0,0,0,0,0,0)';
      PINUSE='POWER';
      NO_LOAD_CHECK='Both';
      NO_IO_CHECK='Both';
      NO_ASSERT_CHECK='TRUE';
      NO_DIR_CHECK='TRUE';
      ALLOW_CONNECT='TRUE';
    'VCCIN_SENSE':
      PIN_NUMBER='(0,0,0,BD87,0,0,0,0,0,0,0,0,0,0,0,0,0,0,0,0,0,0,0,0,0,0,0,0,0,~
0,0,0,0,0,0,0,0,0,0,0,0,0)';
      PINUSE='POWER';
      NO_LOAD_CHECK='Both';
      NO_IO_CHECK='Both';
      NO_ASSERT_CHECK='TRUE';
      NO_DIR_CHECK='TRUE';
      ALLOW_CONNECT='TRUE';
    'VSS_VCCD_HV_SENSE':
      PIN_NUMBER='(0,0,0,BN11,0,0,0,0,0,0,0,0,0,0,0,0,0,0,0,0,0,0,0,0,0,0,0,0,0,~
0,0,0,0,0,0,0,0,0,0,0,0,0)';
      PINUSE='POWER';
      NO_LOAD_CHECK='Both';
      NO_IO_CHECK='Both';
      NO_ASSERT_CHECK='TRUE';
      NO_DIR_CHECK='TRUE';
      ALLOW_CONNECT='TRUE';
    'VSS_VCCFA_EHV_FIVRA_SENSE':
      PIN_NUMBER='(0,0,0,AT85,0,0,0,0,0,0,0,0,0,0,0,0,0,0,0,0,0,0,0,0,0,0,0,0,0,~
0,0,0,0,0,0,0,0,0,0,0,0,0)';
      PINUSE='POWER';
      NO_LOAD_CHECK='Both';
      NO_IO_CHECK='Both';
      NO_ASSERT_CHECK='TRUE';
      NO_DIR_CHECK='TRUE';
      ALLOW_CONNECT='TRUE';
    'VSS_VCCFA_EHV_SENSE':
      PIN_NUMBER='(0,0,0,BA11,0,0,0,0,0,0,0,0,0,0,0,0,0,0,0,0,0,0,0,0,0,0,0,0,0,~
0,0,0,0,0,0,0,0,0,0,0,0,0)';
      PINUSE='POWER';
      NO_LOAD_CHECK='Both';
      NO_IO_CHECK='Both';
      NO_ASSERT_CHECK='TRUE';
      NO_DIR_CHECK='TRUE';
      ALLOW_CONNECT='TRUE';
    'VSS_VCCINFAON_SENSE':
      PIN_NUMBER='(0,0,0,CE11,0,0,0,0,0,0,0,0,0,0,0,0,0,0,0,0,0,0,0,0,0,0,0,0,0,~
0,0,0,0,0,0,0,0,0,0,0,0,0)';
      PINUSE='POWER';
      NO_LOAD_CHECK='Both';
      NO_IO_CHECK='Both';
      NO_ASSERT_CHECK='TRUE';
      NO_DIR_CHECK='TRUE';
      ALLOW_CONNECT='TRUE';
    'VSS_VCCIN_SENSE':
      PIN_NUMBER='(0,0,0,BC90,0,0,0,0,0,0,0,0,0,0,0,0,0,0,0,0,0,0,0,0,0,0,0,0,0,~
0,0,0,0,0,0,0,0,0,0,0,0,0)';
      PINUSE='POWER';
      NO_LOAD_CHECK='Both';
      NO_IO_CHECK='Both';
      NO_ASSERT_CHECK='TRUE';
      NO_DIR_CHECK='TRUE';
      ALLOW_CONNECT='TRUE';
    'RSVD0':
      PIN_NUMBER='(0,0,0,0,AC78,0,0,0,0,0,0,0,0,0,0,0,0,0,0,0,0,0,0,0,0,0,0,0,0,~
0,0,0,0,0,0,0,0,0,0,0,0,0)';
      BIDIRECTIONAL='TRUE';
      INPUT_LOAD='(-0.01,0.01)';
      OUTPUT_LOAD='(1.0,-1.0)';
      PINUSE='BI';
    'RSVD1':
      PIN_NUMBER='(0,0,0,0,AD77,0,0,0,0,0,0,0,0,0,0,0,0,0,0,0,0,0,0,0,0,0,0,0,0,~
0,0,0,0,0,0,0,0,0,0,0,0,0)';
      BIDIRECTIONAL='TRUE';
      INPUT_LOAD='(-0.01,0.01)';
      OUTPUT_LOAD='(1.0,-1.0)';
      PINUSE='BI';
    'RSVD106':
      PIN_NUMBER='(0,0,0,0,CJ68,0,0,0,0,0,0,0,0,0,0,0,0,0,0,0,0,0,0,0,0,0,0,0,0,~
0,0,0,0,0,0,0,0,0,0,0,0,0)';
      BIDIRECTIONAL='TRUE';
      INPUT_LOAD='(-0.01,0.01)';
      OUTPUT_LOAD='(1.0,-1.0)';
      PINUSE='BI';
    'RSVD107':
      PIN_NUMBER='(0,0,0,0,CJ70,0,0,0,0,0,0,0,0,0,0,0,0,0,0,0,0,0,0,0,0,0,0,0,0,~
0,0,0,0,0,0,0,0,0,0,0,0,0)';
      BIDIRECTIONAL='TRUE';
      INPUT_LOAD='(-0.01,0.01)';
      OUTPUT_LOAD='(1.0,-1.0)';
      PINUSE='BI';
    'RSVD112':
      PIN_NUMBER='(0,0,0,0,CK67,0,0,0,0,0,0,0,0,0,0,0,0,0,0,0,0,0,0,0,0,0,0,0,0,~
0,0,0,0,0,0,0,0,0,0,0,0,0)';
      BIDIRECTIONAL='TRUE';
      INPUT_LOAD='(-0.01,0.01)';
      OUTPUT_LOAD='(1.0,-1.0)';
      PINUSE='BI';
    'RSVD133':
      PIN_NUMBER='(0,0,0,0,CR25,0,0,0,0,0,0,0,0,0,0,0,0,0,0,0,0,0,0,0,0,0,0,0,0,~
0,0,0,0,0,0,0,0,0,0,0,0,0)';
      BIDIRECTIONAL='TRUE';
      INPUT_LOAD='(-0.01,0.01)';
      OUTPUT_LOAD='(1.0,-1.0)';
      PINUSE='BI';
    'RSVD138':
      PIN_NUMBER='(0,0,0,0,CT26,0,0,0,0,0,0,0,0,0,0,0,0,0,0,0,0,0,0,0,0,0,0,0,0,~
0,0,0,0,0,0,0,0,0,0,0,0,0)';
      BIDIRECTIONAL='TRUE';
      INPUT_LOAD='(-0.01,0.01)';
      OUTPUT_LOAD='(1.0,-1.0)';
      PINUSE='BI';
    'RSVD147':
      PIN_NUMBER='(0,0,0,0,CW41,0,0,0,0,0,0,0,0,0,0,0,0,0,0,0,0,0,0,0,0,0,0,0,0,~
0,0,0,0,0,0,0,0,0,0,0,0,0)';
      BIDIRECTIONAL='TRUE';
      INPUT_LOAD='(-0.01,0.01)';
      OUTPUT_LOAD='(1.0,-1.0)';
      PINUSE='BI';
    'RSVD149':
      PIN_NUMBER='(0,0,0,0,CW58,0,0,0,0,0,0,0,0,0,0,0,0,0,0,0,0,0,0,0,0,0,0,0,0,~
0,0,0,0,0,0,0,0,0,0,0,0,0)';
      BIDIRECTIONAL='TRUE';
      INPUT_LOAD='(-0.01,0.01)';
      OUTPUT_LOAD='(1.0,-1.0)';
      PINUSE='BI';
    'RSVD154':
      PIN_NUMBER='(0,0,0,0,CY57,0,0,0,0,0,0,0,0,0,0,0,0,0,0,0,0,0,0,0,0,0,0,0,0,~
0,0,0,0,0,0,0,0,0,0,0,0,0)';
      BIDIRECTIONAL='TRUE';
      INPUT_LOAD='(-0.01,0.01)';
      OUTPUT_LOAD='(1.0,-1.0)';
      PINUSE='BI';
    'RSVD160':
      PIN_NUMBER='(0,0,0,0,EG17,0,0,0,0,0,0,0,0,0,0,0,0,0,0,0,0,0,0,0,0,0,0,0,0,~
0,0,0,0,0,0,0,0,0,0,0,0,0)';
      BIDIRECTIONAL='TRUE';
      INPUT_LOAD='(-0.01,0.01)';
      OUTPUT_LOAD='(1.0,-1.0)';
      PINUSE='BI';
    'RSVD164':
      PIN_NUMBER='(0,0,0,0,U17,0,0,0,0,0,0,0,0,0,0,0,0,0,0,0,0,0,0,0,0,0,0,0,0,0~
,0,0,0,0,0,0,0,0,0,0,0,0)';
      BIDIRECTIONAL='TRUE';
      INPUT_LOAD='(-0.01,0.01)';
      OUTPUT_LOAD='(1.0,-1.0)';
      PINUSE='BI';
    'RSVD165':
      PIN_NUMBER='(0,0,0,0,W17,0,0,0,0,0,0,0,0,0,0,0,0,0,0,0,0,0,0,0,0,0,0,0,0,0~
,0,0,0,0,0,0,0,0,0,0,0,0)';
      BIDIRECTIONAL='TRUE';
      INPUT_LOAD='(-0.01,0.01)';
      OUTPUT_LOAD='(1.0,-1.0)';
      PINUSE='BI';
    'RSVD21':
      PIN_NUMBER='(0,0,0,0,AV65,0,0,0,0,0,0,0,0,0,0,0,0,0,0,0,0,0,0,0,0,0,0,0,0,~
0,0,0,0,0,0,0,0,0,0,0,0,0)';
      BIDIRECTIONAL='TRUE';
      INPUT_LOAD='(-0.01,0.01)';
      OUTPUT_LOAD='(1.0,-1.0)';
      PINUSE='BI';
    'RSVD26':
      PIN_NUMBER='(0,0,0,0,AY24,0,0,0,0,0,0,0,0,0,0,0,0,0,0,0,0,0,0,0,0,0,0,0,0,~
0,0,0,0,0,0,0,0,0,0,0,0,0)';
      BIDIRECTIONAL='TRUE';
      INPUT_LOAD='(-0.01,0.01)';
      OUTPUT_LOAD='(1.0,-1.0)';
      PINUSE='BI';
    'RSVD31':
      PIN_NUMBER='(0,0,0,0,BA25,0,0,0,0,0,0,0,0,0,0,0,0,0,0,0,0,0,0,0,0,0,0,0,0,~
0,0,0,0,0,0,0,0,0,0,0,0,0)';
      BIDIRECTIONAL='TRUE';
      INPUT_LOAD='(-0.01,0.01)';
      OUTPUT_LOAD='(1.0,-1.0)';
      PINUSE='BI';
    'RSVD43':
      PIN_NUMBER='(0,0,0,0,BD71,0,0,0,0,0,0,0,0,0,0,0,0,0,0,0,0,0,0,0,0,0,0,0,0,~
0,0,0,0,0,0,0,0,0,0,0,0,0)';
      BIDIRECTIONAL='TRUE';
      INPUT_LOAD='(-0.01,0.01)';
      OUTPUT_LOAD='(1.0,-1.0)';
      PINUSE='BI';
    'RSVD45':
      PIN_NUMBER='(0,0,0,0,BE21,0,0,0,0,0,0,0,0,0,0,0,0,0,0,0,0,0,0,0,0,0,0,0,0,~
0,0,0,0,0,0,0,0,0,0,0,0,0)';
      BIDIRECTIONAL='TRUE';
      INPUT_LOAD='(-0.01,0.01)';
      OUTPUT_LOAD='(1.0,-1.0)';
      PINUSE='BI';
    'RSVD51':
      PIN_NUMBER='(0,0,0,0,BF71,0,0,0,0,0,0,0,0,0,0,0,0,0,0,0,0,0,0,0,0,0,0,0,0,~
0,0,0,0,0,0,0,0,0,0,0,0,0)';
      BIDIRECTIONAL='TRUE';
      INPUT_LOAD='(-0.01,0.01)';
      OUTPUT_LOAD='(1.0,-1.0)';
      PINUSE='BI';
    'RSVD54':
      PIN_NUMBER='(0,0,0,0,BG78,0,0,0,0,0,0,0,0,0,0,0,0,0,0,0,0,0,0,0,0,0,0,0,0,~
0,0,0,0,0,0,0,0,0,0,0,0,0)';
      BIDIRECTIONAL='TRUE';
      INPUT_LOAD='(-0.01,0.01)';
      OUTPUT_LOAD='(1.0,-1.0)';
      PINUSE='BI';
    'RSVD57':
      PIN_NUMBER='(0,0,0,0,BJ21,0,0,0,0,0,0,0,0,0,0,0,0,0,0,0,0,0,0,0,0,0,0,0,0,~
0,0,0,0,0,0,0,0,0,0,0,0,0)';
      BIDIRECTIONAL='TRUE';
      INPUT_LOAD='(-0.01,0.01)';
      OUTPUT_LOAD='(1.0,-1.0)';
      PINUSE='BI';
    'RSVD60':
      PIN_NUMBER='(0,0,0,0,BK22,0,0,0,0,0,0,0,0,0,0,0,0,0,0,0,0,0,0,0,0,0,0,0,0,~
0,0,0,0,0,0,0,0,0,0,0,0,0)';
      BIDIRECTIONAL='TRUE';
      INPUT_LOAD='(-0.01,0.01)';
      OUTPUT_LOAD='(1.0,-1.0)';
      PINUSE='BI';
    'RSVD63':
      PIN_NUMBER='(0,0,0,0,BL60,0,0,0,0,0,0,0,0,0,0,0,0,0,0,0,0,0,0,0,0,0,0,0,0,~
0,0,0,0,0,0,0,0,0,0,0,0,0)';
      BIDIRECTIONAL='TRUE';
      INPUT_LOAD='(-0.01,0.01)';
      OUTPUT_LOAD='(1.0,-1.0)';
      PINUSE='BI';
    'RSVD65':
      PIN_NUMBER='(0,0,0,0,BM65,0,0,0,0,0,0,0,0,0,0,0,0,0,0,0,0,0,0,0,0,0,0,0,0,~
0,0,0,0,0,0,0,0,0,0,0,0,0)';
      BIDIRECTIONAL='TRUE';
      INPUT_LOAD='(-0.01,0.01)';
      OUTPUT_LOAD='(1.0,-1.0)';
      PINUSE='BI';
    'RSVD67':
      PIN_NUMBER='(0,0,0,0,BP22,0,0,0,0,0,0,0,0,0,0,0,0,0,0,0,0,0,0,0,0,0,0,0,0,~
0,0,0,0,0,0,0,0,0,0,0,0,0)';
      BIDIRECTIONAL='TRUE';
      INPUT_LOAD='(-0.01,0.01)';
      OUTPUT_LOAD='(1.0,-1.0)';
      PINUSE='BI';
    'RSVD68':
      PIN_NUMBER='(0,0,0,0,BP65,0,0,0,0,0,0,0,0,0,0,0,0,0,0,0,0,0,0,0,0,0,0,0,0,~
0,0,0,0,0,0,0,0,0,0,0,0,0)';
      BIDIRECTIONAL='TRUE';
      INPUT_LOAD='(-0.01,0.01)';
      OUTPUT_LOAD='(1.0,-1.0)';
      PINUSE='BI';
    'RSVD71':
      PIN_NUMBER='(0,0,0,0,BR21,0,0,0,0,0,0,0,0,0,0,0,0,0,0,0,0,0,0,0,0,0,0,0,0,~
0,0,0,0,0,0,0,0,0,0,0,0,0)';
      BIDIRECTIONAL='TRUE';
      INPUT_LOAD='(-0.01,0.01)';
      OUTPUT_LOAD='(1.0,-1.0)';
      PINUSE='BI';
    'RSVD82':
      PIN_NUMBER='(0,0,0,0,CC66,0,0,0,0,0,0,0,0,0,0,0,0,0,0,0,0,0,0,0,0,0,0,0,0,~
0,0,0,0,0,0,0,0,0,0,0,0,0)';
      BIDIRECTIONAL='TRUE';
      INPUT_LOAD='(-0.01,0.01)';
      OUTPUT_LOAD='(1.0,-1.0)';
      PINUSE='BI';
    'RSVD83':
      PIN_NUMBER='(0,0,0,0,CD22,0,0,0,0,0,0,0,0,0,0,0,0,0,0,0,0,0,0,0,0,0,0,0,0,~
0,0,0,0,0,0,0,0,0,0,0,0,0)';
      BIDIRECTIONAL='TRUE';
      INPUT_LOAD='(-0.01,0.01)';
      OUTPUT_LOAD='(1.0,-1.0)';
      PINUSE='BI';
    'RSVD84':
      PIN_NUMBER='(0,0,0,0,CD26,0,0,0,0,0,0,0,0,0,0,0,0,0,0,0,0,0,0,0,0,0,0,0,0,~
0,0,0,0,0,0,0,0,0,0,0,0,0)';
      BIDIRECTIONAL='TRUE';
      INPUT_LOAD='(-0.01,0.01)';
      OUTPUT_LOAD='(1.0,-1.0)';
      PINUSE='BI';
    'RSVD85':
      PIN_NUMBER='(0,0,0,0,CD30,0,0,0,0,0,0,0,0,0,0,0,0,0,0,0,0,0,0,0,0,0,0,0,0,~
0,0,0,0,0,0,0,0,0,0,0,0,0)';
      BIDIRECTIONAL='TRUE';
      INPUT_LOAD='(-0.01,0.01)';
      OUTPUT_LOAD='(1.0,-1.0)';
      PINUSE='BI';
    'RSVD92':
      PIN_NUMBER='(0,0,0,0,CF22,0,0,0,0,0,0,0,0,0,0,0,0,0,0,0,0,0,0,0,0,0,0,0,0,~
0,0,0,0,0,0,0,0,0,0,0,0,0)';
      BIDIRECTIONAL='TRUE';
      INPUT_LOAD='(-0.01,0.01)';
      OUTPUT_LOAD='(1.0,-1.0)';
      PINUSE='BI';
    'RSVD99':
      PIN_NUMBER='(0,0,0,0,CH69,0,0,0,0,0,0,0,0,0,0,0,0,0,0,0,0,0,0,0,0,0,0,0,0,~
0,0,0,0,0,0,0,0,0,0,0,0,0)';
      BIDIRECTIONAL='TRUE';
      INPUT_LOAD='(-0.01,0.01)';
      OUTPUT_LOAD='(1.0,-1.0)';
      PINUSE='BI';
    'RSVD119':
      PIN_NUMBER='(0,0,0,0,0,CL70,0,0,0,0,0,0,0,0,0,0,0,0,0,0,0,0,0,0,0,0,0,0,0,~
0,0,0,0,0,0,0,0,0,0,0,0,0)';
      BIDIRECTIONAL='TRUE';
      INPUT_LOAD='(-0.01,0.01)';
      OUTPUT_LOAD='(1.0,-1.0)';
      PINUSE='BI';
    'RSVD115':
      PIN_NUMBER='(0,0,0,0,0,CL60,0,0,0,0,0,0,0,0,0,0,0,0,0,0,0,0,0,0,0,0,0,0,0,~
0,0,0,0,0,0,0,0,0,0,0,0,0)';
      BIDIRECTIONAL='TRUE';
      INPUT_LOAD='(-0.01,0.01)';
      OUTPUT_LOAD='(1.0,-1.0)';
      PINUSE='BI';
    'RSVD148':
      PIN_NUMBER='(0,0,0,0,0,CW43,0,0,0,0,0,0,0,0,0,0,0,0,0,0,0,0,0,0,0,0,0,0,0,~
0,0,0,0,0,0,0,0,0,0,0,0,0)';
      BIDIRECTIONAL='TRUE';
      INPUT_LOAD='(-0.01,0.01)';
      OUTPUT_LOAD='(1.0,-1.0)';
      PINUSE='BI';
    'RSVD159':
      PIN_NUMBER='(0,0,0,0,0,DA70,0,0,0,0,0,0,0,0,0,0,0,0,0,0,0,0,0,0,0,0,0,0,0,~
0,0,0,0,0,0,0,0,0,0,0,0,0)';
      BIDIRECTIONAL='TRUE';
      INPUT_LOAD='(-0.01,0.01)';
      OUTPUT_LOAD='(1.0,-1.0)';
      PINUSE='BI';
    'RSVD44':
      PIN_NUMBER='(0,0,0,0,0,BD77,0,0,0,0,0,0,0,0,0,0,0,0,0,0,0,0,0,0,0,0,0,0,0,~
0,0,0,0,0,0,0,0,0,0,0,0,0)';
      BIDIRECTIONAL='TRUE';
      INPUT_LOAD='(-0.01,0.01)';
      OUTPUT_LOAD='(1.0,-1.0)';
      PINUSE='BI';
    'RSVD97':
      PIN_NUMBER='(0,0,0,0,0,CH61,0,0,0,0,0,0,0,0,0,0,0,0,0,0,0,0,0,0,0,0,0,0,0,~
0,0,0,0,0,0,0,0,0,0,0,0,0)';
      BIDIRECTIONAL='TRUE';
      INPUT_LOAD='(-0.01,0.01)';
      OUTPUT_LOAD='(1.0,-1.0)';
      PINUSE='BI';
    'RSVD8':
      PIN_NUMBER='(0,0,0,0,0,AU52,0,0,0,0,0,0,0,0,0,0,0,0,0,0,0,0,0,0,0,0,0,0,0,~
0,0,0,0,0,0,0,0,0,0,0,0,0)';
      BIDIRECTIONAL='TRUE';
      INPUT_LOAD='(-0.01,0.01)';
      OUTPUT_LOAD='(1.0,-1.0)';
      PINUSE='BI';
    'RSVD87':
      PIN_NUMBER='(0,0,0,0,0,CD69,0,0,0,0,0,0,0,0,0,0,0,0,0,0,0,0,0,0,0,0,0,0,0,~
0,0,0,0,0,0,0,0,0,0,0,0,0)';
      BIDIRECTIONAL='TRUE';
      INPUT_LOAD='(-0.01,0.01)';
      OUTPUT_LOAD='(1.0,-1.0)';
      PINUSE='BI';
    'RSVD111':
      PIN_NUMBER='(0,0,0,0,0,CK61,0,0,0,0,0,0,0,0,0,0,0,0,0,0,0,0,0,0,0,0,0,0,0,~
0,0,0,0,0,0,0,0,0,0,0,0,0)';
      BIDIRECTIONAL='TRUE';
      INPUT_LOAD='(-0.01,0.01)';
      OUTPUT_LOAD='(1.0,-1.0)';
      PINUSE='BI';
    'RSVD95':
      PIN_NUMBER='(0,0,0,0,0,CG60,0,0,0,0,0,0,0,0,0,0,0,0,0,0,0,0,0,0,0,0,0,0,0,~
0,0,0,0,0,0,0,0,0,0,0,0,0)';
      BIDIRECTIONAL='TRUE';
      INPUT_LOAD='(-0.01,0.01)';
      OUTPUT_LOAD='(1.0,-1.0)';
      PINUSE='BI';
    'RSVD163':
      PIN_NUMBER='(0,0,0,0,0,J13,0,0,0,0,0,0,0,0,0,0,0,0,0,0,0,0,0,0,0,0,0,0,0,0~
,0,0,0,0,0,0,0,0,0,0,0,0)';
      BIDIRECTIONAL='TRUE';
      INPUT_LOAD='(-0.01,0.01)';
      OUTPUT_LOAD='(1.0,-1.0)';
      PINUSE='BI';
    'PTI_DIE0015':
      PIN_NUMBER='(0,0,0,0,0,0,BP30,0,0,0,0,0,0,0,0,0,0,0,0,0,0,0,0,0,0,0,0,0,0,~
0,0,0,0,0,0,0,0,0,0,0,0,0)';
      OUTPUT_LOAD='(1.0,-1.0)';
      PINUSE='OUT';
    'PTI_DIE0014':
      PIN_NUMBER='(0,0,0,0,0,0,BN29,0,0,0,0,0,0,0,0,0,0,0,0,0,0,0,0,0,0,0,0,0,0,~
0,0,0,0,0,0,0,0,0,0,0,0,0)';
      OUTPUT_LOAD='(1.0,-1.0)';
      PINUSE='OUT';
    'PTI_DIE0013':
      PIN_NUMBER='(0,0,0,0,0,0,BP28,0,0,0,0,0,0,0,0,0,0,0,0,0,0,0,0,0,0,0,0,0,0,~
0,0,0,0,0,0,0,0,0,0,0,0,0)';
      OUTPUT_LOAD='(1.0,-1.0)';
      PINUSE='OUT';
    'PTI_DIE0012':
      PIN_NUMBER='(0,0,0,0,0,0,BN27,0,0,0,0,0,0,0,0,0,0,0,0,0,0,0,0,0,0,0,0,0,0,~
0,0,0,0,0,0,0,0,0,0,0,0,0)';
      OUTPUT_LOAD='(1.0,-1.0)';
      PINUSE='OUT';
    'PTI_DIE0011':
      PIN_NUMBER='(0,0,0,0,0,0,BT30,0,0,0,0,0,0,0,0,0,0,0,0,0,0,0,0,0,0,0,0,0,0,~
0,0,0,0,0,0,0,0,0,0,0,0,0)';
      OUTPUT_LOAD='(1.0,-1.0)';
      PINUSE='OUT';
    'PTI_DIE0010':
      PIN_NUMBER='(0,0,0,0,0,0,BU29,0,0,0,0,0,0,0,0,0,0,0,0,0,0,0,0,0,0,0,0,0,0,~
0,0,0,0,0,0,0,0,0,0,0,0,0)';
      OUTPUT_LOAD='(1.0,-1.0)';
      PINUSE='OUT';
    'PTI_DIE009':
      PIN_NUMBER='(0,0,0,0,0,0,BT28,0,0,0,0,0,0,0,0,0,0,0,0,0,0,0,0,0,0,0,0,0,0,~
0,0,0,0,0,0,0,0,0,0,0,0,0)';
      OUTPUT_LOAD='(1.0,-1.0)';
      PINUSE='OUT';
    'PTI_DIE008':
      PIN_NUMBER='(0,0,0,0,0,0,BU27,0,0,0,0,0,0,0,0,0,0,0,0,0,0,0,0,0,0,0,0,0,0,~
0,0,0,0,0,0,0,0,0,0,0,0,0)';
      OUTPUT_LOAD='(1.0,-1.0)';
      PINUSE='OUT';
    'PTI_DIE007':
      PIN_NUMBER='(0,0,0,0,0,0,BV28,0,0,0,0,0,0,0,0,0,0,0,0,0,0,0,0,0,0,0,0,0,0,~
0,0,0,0,0,0,0,0,0,0,0,0,0)';
      OUTPUT_LOAD='(1.0,-1.0)';
      PINUSE='OUT';
    'PTI_DIE006':
      PIN_NUMBER='(0,0,0,0,0,0,CA27,0,0,0,0,0,0,0,0,0,0,0,0,0,0,0,0,0,0,0,0,0,0,~
0,0,0,0,0,0,0,0,0,0,0,0,0)';
      OUTPUT_LOAD='(1.0,-1.0)';
      PINUSE='OUT';
    'PTI_DIE005':
      PIN_NUMBER='(0,0,0,0,0,0,BV30,0,0,0,0,0,0,0,0,0,0,0,0,0,0,0,0,0,0,0,0,0,0,~
0,0,0,0,0,0,0,0,0,0,0,0,0)';
      OUTPUT_LOAD='(1.0,-1.0)';
      PINUSE='OUT';
    'PTI_DIE004':
      PIN_NUMBER='(0,0,0,0,0,0,CA29,0,0,0,0,0,0,0,0,0,0,0,0,0,0,0,0,0,0,0,0,0,0,~
0,0,0,0,0,0,0,0,0,0,0,0,0)';
      OUTPUT_LOAD='(1.0,-1.0)';
      PINUSE='OUT';
    'PTI_DIE003':
      PIN_NUMBER='(0,0,0,0,0,0,BY30,0,0,0,0,0,0,0,0,0,0,0,0,0,0,0,0,0,0,0,0,0,0,~
0,0,0,0,0,0,0,0,0,0,0,0,0)';
      OUTPUT_LOAD='(1.0,-1.0)';
      PINUSE='OUT';
    'PTI_DIE002':
      PIN_NUMBER='(0,0,0,0,0,0,CC27,0,0,0,0,0,0,0,0,0,0,0,0,0,0,0,0,0,0,0,0,0,0,~
0,0,0,0,0,0,0,0,0,0,0,0,0)';
      OUTPUT_LOAD='(1.0,-1.0)';
      PINUSE='OUT';
    'PTI_DIE001':
      PIN_NUMBER='(0,0,0,0,0,0,CD28,0,0,0,0,0,0,0,0,0,0,0,0,0,0,0,0,0,0,0,0,0,0,~
0,0,0,0,0,0,0,0,0,0,0,0,0)';
      OUTPUT_LOAD='(1.0,-1.0)';
      PINUSE='OUT';
    'PTI_DIE000':
      PIN_NUMBER='(0,0,0,0,0,0,CC29,0,0,0,0,0,0,0,0,0,0,0,0,0,0,0,0,0,0,0,0,0,0,~
0,0,0,0,0,0,0,0,0,0,0,0,0)';
      OUTPUT_LOAD='(1.0,-1.0)';
      PINUSE='OUT';
    'PTI_DIE00_STB_0':
      PIN_NUMBER='(0,0,0,0,0,0,CB30,0,0,0,0,0,0,0,0,0,0,0,0,0,0,0,0,0,0,0,0,0,0,~
0,0,0,0,0,0,0,0,0,0,0,0,0)';
      OUTPUT_LOAD='(1.0,-1.0)';
      PINUSE='OUT';
    'PTI_DIE00_STB_1':
      PIN_NUMBER='(0,0,0,0,0,0,BY28,0,0,0,0,0,0,0,0,0,0,0,0,0,0,0,0,0,0,0,0,0,0,~
0,0,0,0,0,0,0,0,0,0,0,0,0)';
      OUTPUT_LOAD='(1.0,-1.0)';
      PINUSE='OUT';
    'PTI_DIE0115':
      PIN_NUMBER='(0,0,0,0,0,0,BN66,0,0,0,0,0,0,0,0,0,0,0,0,0,0,0,0,0,0,0,0,0,0,~
0,0,0,0,0,0,0,0,0,0,0,0,0)';
      OUTPUT_LOAD='(1.0,-1.0)';
      PINUSE='OUT';
    'PTI_DIE0114':
      PIN_NUMBER='(0,0,0,0,0,0,BM67,0,0,0,0,0,0,0,0,0,0,0,0,0,0,0,0,0,0,0,0,0,0,~
0,0,0,0,0,0,0,0,0,0,0,0,0)';
      OUTPUT_LOAD='(1.0,-1.0)';
      PINUSE='OUT';
    'PTI_DIE0113':
      PIN_NUMBER='(0,0,0,0,0,0,BL66,0,0,0,0,0,0,0,0,0,0,0,0,0,0,0,0,0,0,0,0,0,0,~
0,0,0,0,0,0,0,0,0,0,0,0,0)';
      OUTPUT_LOAD='(1.0,-1.0)';
      PINUSE='OUT';
    'PTI_DIE0112':
      PIN_NUMBER='(0,0,0,0,0,0,BJ66,0,0,0,0,0,0,0,0,0,0,0,0,0,0,0,0,0,0,0,0,0,0,~
0,0,0,0,0,0,0,0,0,0,0,0,0)';
      OUTPUT_LOAD='(1.0,-1.0)';
      PINUSE='OUT';
    'PTI_DIE0111':
      PIN_NUMBER='(0,0,0,0,0,0,BG66,0,0,0,0,0,0,0,0,0,0,0,0,0,0,0,0,0,0,0,0,0,0,~
0,0,0,0,0,0,0,0,0,0,0,0,0)';
      OUTPUT_LOAD='(1.0,-1.0)';
      PINUSE='OUT';
    'PTI_DIE0110':
      PIN_NUMBER='(0,0,0,0,0,0,BN68,0,0,0,0,0,0,0,0,0,0,0,0,0,0,0,0,0,0,0,0,0,0,~
0,0,0,0,0,0,0,0,0,0,0,0,0)';
      OUTPUT_LOAD='(1.0,-1.0)';
      PINUSE='OUT';
    'PTI_DIE019':
      PIN_NUMBER='(0,0,0,0,0,0,BM69,0,0,0,0,0,0,0,0,0,0,0,0,0,0,0,0,0,0,0,0,0,0,~
0,0,0,0,0,0,0,0,0,0,0,0,0)';
      OUTPUT_LOAD='(1.0,-1.0)';
      PINUSE='OUT';
    'PTI_DIE018':
      PIN_NUMBER='(0,0,0,0,0,0,BK69,0,0,0,0,0,0,0,0,0,0,0,0,0,0,0,0,0,0,0,0,0,0,~
0,0,0,0,0,0,0,0,0,0,0,0,0)';
      OUTPUT_LOAD='(1.0,-1.0)';
      PINUSE='OUT';
    'PTI_DIE017':
      PIN_NUMBER='(0,0,0,0,0,0,BD67,0,0,0,0,0,0,0,0,0,0,0,0,0,0,0,0,0,0,0,0,0,0,~
0,0,0,0,0,0,0,0,0,0,0,0,0)';
      OUTPUT_LOAD='(1.0,-1.0)';
      PINUSE='OUT';
    'PTI_DIE016':
      PIN_NUMBER='(0,0,0,0,0,0,BG68,0,0,0,0,0,0,0,0,0,0,0,0,0,0,0,0,0,0,0,0,0,0,~
0,0,0,0,0,0,0,0,0,0,0,0,0)';
      OUTPUT_LOAD='(1.0,-1.0)';
      PINUSE='OUT';
    'PTI_DIE015':
      PIN_NUMBER='(0,0,0,0,0,0,BC68,0,0,0,0,0,0,0,0,0,0,0,0,0,0,0,0,0,0,0,0,0,0,~
0,0,0,0,0,0,0,0,0,0,0,0,0)';
      OUTPUT_LOAD='(1.0,-1.0)';
      PINUSE='OUT';
    'PTI_DIE014':
      PIN_NUMBER='(0,0,0,0,0,0,BH69,0,0,0,0,0,0,0,0,0,0,0,0,0,0,0,0,0,0,0,0,0,0,~
0,0,0,0,0,0,0,0,0,0,0,0,0)';
      OUTPUT_LOAD='(1.0,-1.0)';
      PINUSE='OUT';
    'PTI_DIE013':
      PIN_NUMBER='(0,0,0,0,0,0,BF69,0,0,0,0,0,0,0,0,0,0,0,0,0,0,0,0,0,0,0,0,0,0,~
0,0,0,0,0,0,0,0,0,0,0,0,0)';
      OUTPUT_LOAD='(1.0,-1.0)';
      PINUSE='OUT';
    'PTI_DIE012':
      PIN_NUMBER='(0,0,0,0,0,0,BD69,0,0,0,0,0,0,0,0,0,0,0,0,0,0,0,0,0,0,0,0,0,0,~
0,0,0,0,0,0,0,0,0,0,0,0,0)';
      OUTPUT_LOAD='(1.0,-1.0)';
      PINUSE='OUT';
    'PTI_DIE011':
      PIN_NUMBER='(0,0,0,0,0,0,BE70,0,0,0,0,0,0,0,0,0,0,0,0,0,0,0,0,0,0,0,0,0,0,~
0,0,0,0,0,0,0,0,0,0,0,0,0)';
      OUTPUT_LOAD='(1.0,-1.0)';
      PINUSE='OUT';
    'PTI_DIE010':
      PIN_NUMBER='(0,0,0,0,0,0,BC70,0,0,0,0,0,0,0,0,0,0,0,0,0,0,0,0,0,0,0,0,0,0,~
0,0,0,0,0,0,0,0,0,0,0,0,0)';
      OUTPUT_LOAD='(1.0,-1.0)';
      PINUSE='OUT';
    'PTI_DIE01_STB_0':
      PIN_NUMBER='(0,0,0,0,0,0,BF67,0,0,0,0,0,0,0,0,0,0,0,0,0,0,0,0,0,0,0,0,0,0,~
0,0,0,0,0,0,0,0,0,0,0,0,0)';
      OUTPUT_LOAD='(1.0,-1.0)';
      PINUSE='OUT';
    'PTI_DIE01_STB_1':
      PIN_NUMBER='(0,0,0,0,0,0,BK67,0,0,0,0,0,0,0,0,0,0,0,0,0,0,0,0,0,0,0,0,0,0,~
0,0,0,0,0,0,0,0,0,0,0,0,0)';
      OUTPUT_LOAD='(1.0,-1.0)';
      PINUSE='OUT';
    'RSVD118':
      PIN_NUMBER='(0,0,0,0,0,0,CL68,0,0,0,0,0,0,0,0,0,0,0,0,0,0,0,0,0,0,0,0,0,0,~
0,0,0,0,0,0,0,0,0,0,0,0,0)';
      BIDIRECTIONAL='TRUE';
      INPUT_LOAD='(-0.01,0.01)';
      OUTPUT_LOAD='(1.0,-1.0)';
      PINUSE='BI';
    'RSVD122':
      PIN_NUMBER='(0,0,0,0,0,0,CM69,0,0,0,0,0,0,0,0,0,0,0,0,0,0,0,0,0,0,0,0,0,0,~
0,0,0,0,0,0,0,0,0,0,0,0,0)';
      BIDIRECTIONAL='TRUE';
      INPUT_LOAD='(-0.01,0.01)';
      OUTPUT_LOAD='(1.0,-1.0)';
      PINUSE='BI';
    'RSVD130':
      PIN_NUMBER='(0,0,0,0,0,0,CP69,0,0,0,0,0,0,0,0,0,0,0,0,0,0,0,0,0,0,0,0,0,0,~
0,0,0,0,0,0,0,0,0,0,0,0,0)';
      BIDIRECTIONAL='TRUE';
      INPUT_LOAD='(-0.01,0.01)';
      OUTPUT_LOAD='(1.0,-1.0)';
      PINUSE='BI';
    'RSVD135':
      PIN_NUMBER='(0,0,0,0,0,0,CR68,0,0,0,0,0,0,0,0,0,0,0,0,0,0,0,0,0,0,0,0,0,0,~
0,0,0,0,0,0,0,0,0,0,0,0,0)';
      BIDIRECTIONAL='TRUE';
      INPUT_LOAD='(-0.01,0.01)';
      OUTPUT_LOAD='(1.0,-1.0)';
      PINUSE='BI';
    'RSVD13':
      PIN_NUMBER='(0,0,0,0,0,0,AU66,0,0,0,0,0,0,0,0,0,0,0,0,0,0,0,0,0,0,0,0,0,0,~
0,0,0,0,0,0,0,0,0,0,0,0,0)';
      BIDIRECTIONAL='TRUE';
      INPUT_LOAD='(-0.01,0.01)';
      OUTPUT_LOAD='(1.0,-1.0)';
      PINUSE='BI';
    'RSVD14':
      PIN_NUMBER='(0,0,0,0,0,0,AU68,0,0,0,0,0,0,0,0,0,0,0,0,0,0,0,0,0,0,0,0,0,0,~
0,0,0,0,0,0,0,0,0,0,0,0,0)';
      BIDIRECTIONAL='TRUE';
      INPUT_LOAD='(-0.01,0.01)';
      OUTPUT_LOAD='(1.0,-1.0)';
      PINUSE='BI';
    'RSVD2':
      PIN_NUMBER='(0,0,0,0,0,0,AN17,0,0,0,0,0,0,0,0,0,0,0,0,0,0,0,0,0,0,0,0,0,0,~
0,0,0,0,0,0,0,0,0,0,0,0,0)';
      BIDIRECTIONAL='TRUE';
      INPUT_LOAD='(-0.01,0.01)';
      OUTPUT_LOAD='(1.0,-1.0)';
      PINUSE='BI';
    'RSVD22':
      PIN_NUMBER='(0,0,0,0,0,0,AV67,0,0,0,0,0,0,0,0,0,0,0,0,0,0,0,0,0,0,0,0,0,0,~
0,0,0,0,0,0,0,0,0,0,0,0,0)';
      BIDIRECTIONAL='TRUE';
      INPUT_LOAD='(-0.01,0.01)';
      OUTPUT_LOAD='(1.0,-1.0)';
      PINUSE='BI';
    'RSVD3':
      PIN_NUMBER='(0,0,0,0,0,0,AR17,0,0,0,0,0,0,0,0,0,0,0,0,0,0,0,0,0,0,0,0,0,0,~
0,0,0,0,0,0,0,0,0,0,0,0,0)';
      BIDIRECTIONAL='TRUE';
      INPUT_LOAD='(-0.01,0.01)';
      OUTPUT_LOAD='(1.0,-1.0)';
      PINUSE='BI';
    'RSVD5':
      PIN_NUMBER='(0,0,0,0,0,0,AT67,0,0,0,0,0,0,0,0,0,0,0,0,0,0,0,0,0,0,0,0,0,0,~
0,0,0,0,0,0,0,0,0,0,0,0,0)';
      BIDIRECTIONAL='TRUE';
      INPUT_LOAD='(-0.01,0.01)';
      OUTPUT_LOAD='(1.0,-1.0)';
      PINUSE='BI';
    'RSVD62':
      PIN_NUMBER='(0,0,0,0,0,0,BL21,0,0,0,0,0,0,0,0,0,0,0,0,0,0,0,0,0,0,0,0,0,0,~
0,0,0,0,0,0,0,0,0,0,0,0,0)';
      BIDIRECTIONAL='TRUE';
      INPUT_LOAD='(-0.01,0.01)';
      OUTPUT_LOAD='(1.0,-1.0)';
      PINUSE='BI';
    'RSVD66':
      PIN_NUMBER='(0,0,0,0,0,0,BN21,0,0,0,0,0,0,0,0,0,0,0,0,0,0,0,0,0,0,0,0,0,0,~
0,0,0,0,0,0,0,0,0,0,0,0,0)';
      BIDIRECTIONAL='TRUE';
      INPUT_LOAD='(-0.01,0.01)';
      OUTPUT_LOAD='(1.0,-1.0)';
      PINUSE='BI';
    'RSVD73':
      PIN_NUMBER='(0,0,0,0,0,0,BV22,0,0,0,0,0,0,0,0,0,0,0,0,0,0,0,0,0,0,0,0,0,0,~
0,0,0,0,0,0,0,0,0,0,0,0,0)';
      BIDIRECTIONAL='TRUE';
      INPUT_LOAD='(-0.01,0.01)';
      OUTPUT_LOAD='(1.0,-1.0)';
      PINUSE='BI';
    'RSVD74':
      PIN_NUMBER='(0,0,0,0,0,0,BW21,0,0,0,0,0,0,0,0,0,0,0,0,0,0,0,0,0,0,0,0,0,0,~
0,0,0,0,0,0,0,0,0,0,0,0,0)';
      BIDIRECTIONAL='TRUE';
      INPUT_LOAD='(-0.01,0.01)';
      OUTPUT_LOAD='(1.0,-1.0)';
      PINUSE='BI';
    'RSVD75':
      PIN_NUMBER='(0,0,0,0,0,0,BW23,0,0,0,0,0,0,0,0,0,0,0,0,0,0,0,0,0,0,0,0,0,0,~
0,0,0,0,0,0,0,0,0,0,0,0,0)';
      BIDIRECTIONAL='TRUE';
      INPUT_LOAD='(-0.01,0.01)';
      OUTPUT_LOAD='(1.0,-1.0)';
      PINUSE='BI';
    'RSVD77':
      PIN_NUMBER='(0,0,0,0,0,0,CA21,0,0,0,0,0,0,0,0,0,0,0,0,0,0,0,0,0,0,0,0,0,0,~
0,0,0,0,0,0,0,0,0,0,0,0,0)';
      BIDIRECTIONAL='TRUE';
      INPUT_LOAD='(-0.01,0.01)';
      OUTPUT_LOAD='(1.0,-1.0)';
      PINUSE='BI';
    'RSVD78':
      PIN_NUMBER='(0,0,0,0,0,0,CA23,0,0,0,0,0,0,0,0,0,0,0,0,0,0,0,0,0,0,0,0,0,0,~
0,0,0,0,0,0,0,0,0,0,0,0,0)';
      BIDIRECTIONAL='TRUE';
      INPUT_LOAD='(-0.01,0.01)';
      OUTPUT_LOAD='(1.0,-1.0)';
      PINUSE='BI';
    'RSVD79':
      PIN_NUMBER='(0,0,0,0,0,0,CC21,0,0,0,0,0,0,0,0,0,0,0,0,0,0,0,0,0,0,0,0,0,0,~
0,0,0,0,0,0,0,0,0,0,0,0,0)';
      BIDIRECTIONAL='TRUE';
      INPUT_LOAD='(-0.01,0.01)';
      OUTPUT_LOAD='(1.0,-1.0)';
      PINUSE='BI';
    'RSVD80':
      PIN_NUMBER='(0,0,0,0,0,0,CC23,0,0,0,0,0,0,0,0,0,0,0,0,0,0,0,0,0,0,0,0,0,0,~
0,0,0,0,0,0,0,0,0,0,0,0,0)';
      BIDIRECTIONAL='TRUE';
      INPUT_LOAD='(-0.01,0.01)';
      OUTPUT_LOAD='(1.0,-1.0)';
      PINUSE='BI';
    'RSVD89':
      PIN_NUMBER='(0,0,0,0,0,0,CE21,0,0,0,0,0,0,0,0,0,0,0,0,0,0,0,0,0,0,0,0,0,0,~
0,0,0,0,0,0,0,0,0,0,0,0,0)';
      BIDIRECTIONAL='TRUE';
      INPUT_LOAD='(-0.01,0.01)';
      OUTPUT_LOAD='(1.0,-1.0)';
      PINUSE='BI';
    'UPI0_AC_COUPLING':
      PIN_NUMBER='(0,0,0,0,0,0,BA23,0,0,0,0,0,0,0,0,0,0,0,0,0,0,0,0,0,0,0,0,0,0,~
0,0,0,0,0,0,0,0,0,0,0,0,0)';
      INPUT_LOAD='(-0.01,0.01)';
      PINUSE='IN';
    'UPI1_AC_COUPLING':
      PIN_NUMBER='(0,0,0,0,0,0,CW19,0,0,0,0,0,0,0,0,0,0,0,0,0,0,0,0,0,0,0,0,0,0,~
0,0,0,0,0,0,0,0,0,0,0,0,0)';
      INPUT_LOAD='(-0.01,0.01)';
      PINUSE='IN';
    'UPI2_AC_COUPLING':
      PIN_NUMBER='(0,0,0,0,0,0,BB65,0,0,0,0,0,0,0,0,0,0,0,0,0,0,0,0,0,0,0,0,0,0,~
0,0,0,0,0,0,0,0,0,0,0,0,0)';
      INPUT_LOAD='(-0.01,0.01)';
      PINUSE='IN';
    'UPI3_AC_COUPLING':
      PIN_NUMBER='(0,0,0,0,0,0,CK71,0,0,0,0,0,0,0,0,0,0,0,0,0,0,0,0,0,0,0,0,0,0,~
0,0,0,0,0,0,0,0,0,0,0,0,0)';
      INPUT_LOAD='(-0.01,0.01)';
      PINUSE='IN';
    'DDR0_ALERT_N':
      PIN_NUMBER='(0,0,0,0,0,0,0,AT49,0,0,0,0,0,0,0,0,0,0,0,0,0,0,0,0,0,0,0,0,0,~
0,0,0,0,0,0,0,0,0,0,0,0,0)';
      INPUT_LOAD='(-0.01,0.01)';
      PINUSE='IN';
    'DDR0_A_RSP1':
      PIN_NUMBER='(0,0,0,0,0,0,0,AU43,0,0,0,0,0,0,0,0,0,0,0,0,0,0,0,0,0,0,0,0,0,~
0,0,0,0,0,0,0,0,0,0,0,0,0)';
      INPUT_LOAD='(-0.01,0.01)';
      PINUSE='IN';
    'DDR0_A_RSP0':
      PIN_NUMBER='(0,0,0,0,0,0,0,AT42,0,0,0,0,0,0,0,0,0,0,0,0,0,0,0,0,0,0,0,0,0,~
0,0,0,0,0,0,0,0,0,0,0,0,0)';
      INPUT_LOAD='(-0.01,0.01)';
      PINUSE='IN';
    'DDR0_B_RSP1':
      PIN_NUMBER='(0,0,0,0,0,0,0,AV42,0,0,0,0,0,0,0,0,0,0,0,0,0,0,0,0,0,0,0,0,0,~
0,0,0,0,0,0,0,0,0,0,0,0,0)';
      INPUT_LOAD='(-0.01,0.01)';
      PINUSE='IN';
    'DDR0_B_RSP0':
      PIN_NUMBER='(0,0,0,0,0,0,0,AV44,0,0,0,0,0,0,0,0,0,0,0,0,0,0,0,0,0,0,0,0,0,~
0,0,0,0,0,0,0,0,0,0,0,0,0)';
      INPUT_LOAD='(-0.01,0.01)';
      PINUSE='IN';
    'DDR0_CLK_DN1':
      PIN_NUMBER='(0,0,0,0,0,0,0,G45,0,0,0,0,0,0,0,0,0,0,0,0,0,0,0,0,0,0,0,0,0,0~
,0,0,0,0,0,0,0,0,0,0,0,0)';
      OUTPUT_LOAD='(1.0,-1.0)';
      PINUSE='OUT';
    'DDR0_CLK_DN0':
      PIN_NUMBER='(0,0,0,0,0,0,0,B44,0,0,0,0,0,0,0,0,0,0,0,0,0,0,0,0,0,0,0,0,0,0~
,0,0,0,0,0,0,0,0,0,0,0,0)';
      OUTPUT_LOAD='(1.0,-1.0)';
      PINUSE='OUT';
    'DDR0_CLK_DP1':
      PIN_NUMBER='(0,0,0,0,0,0,0,E45,0,0,0,0,0,0,0,0,0,0,0,0,0,0,0,0,0,0,0,0,0,0~
,0,0,0,0,0,0,0,0,0,0,0,0)';
      OUTPUT_LOAD='(1.0,-1.0)';
      PINUSE='OUT';
    'DDR0_CLK_DP0':
      PIN_NUMBER='(0,0,0,0,0,0,0,C43,0,0,0,0,0,0,0,0,0,0,0,0,0,0,0,0,0,0,0,0,0,0~
,0,0,0,0,0,0,0,0,0,0,0,0)';
      OUTPUT_LOAD='(1.0,-1.0)';
      PINUSE='OUT';
    'DDR0_SA_CA6':
      PIN_NUMBER='(0,0,0,0,0,0,0,C48,0,0,0,0,0,0,0,0,0,0,0,0,0,0,0,0,0,0,0,0,0,0~
,0,0,0,0,0,0,0,0,0,0,0,0)';
      OUTPUT_LOAD='(1.0,-1.0)';
      PINUSE='OUT';
    'DDR0_SA_CA5':
      PIN_NUMBER='(0,0,0,0,0,0,0,E50,0,0,0,0,0,0,0,0,0,0,0,0,0,0,0,0,0,0,0,0,0,0~
,0,0,0,0,0,0,0,0,0,0,0,0)';
      OUTPUT_LOAD='(1.0,-1.0)';
      PINUSE='OUT';
    'DDR0_SA_CA4':
      PIN_NUMBER='(0,0,0,0,0,0,0,C50,0,0,0,0,0,0,0,0,0,0,0,0,0,0,0,0,0,0,0,0,0,0~
,0,0,0,0,0,0,0,0,0,0,0,0)';
      OUTPUT_LOAD='(1.0,-1.0)';
      PINUSE='OUT';
    'DDR0_SA_CA3':
      PIN_NUMBER='(0,0,0,0,0,0,0,F51,0,0,0,0,0,0,0,0,0,0,0,0,0,0,0,0,0,0,0,0,0,0~
,0,0,0,0,0,0,0,0,0,0,0,0)';
      OUTPUT_LOAD='(1.0,-1.0)';
      PINUSE='OUT';
    'DDR0_SA_CA2':
      PIN_NUMBER='(0,0,0,0,0,0,0,B51,0,0,0,0,0,0,0,0,0,0,0,0,0,0,0,0,0,0,0,0,0,0~
,0,0,0,0,0,0,0,0,0,0,0,0)';
      OUTPUT_LOAD='(1.0,-1.0)';
      PINUSE='OUT';
    'DDR0_SA_CA1':
      PIN_NUMBER='(0,0,0,0,0,0,0,G52,0,0,0,0,0,0,0,0,0,0,0,0,0,0,0,0,0,0,0,0,0,0~
,0,0,0,0,0,0,0,0,0,0,0,0)';
      OUTPUT_LOAD='(1.0,-1.0)';
      PINUSE='OUT';
    'DDR0_SA_CA0':
      PIN_NUMBER='(0,0,0,0,0,0,0,A52,0,0,0,0,0,0,0,0,0,0,0,0,0,0,0,0,0,0,0,0,0,0~
,0,0,0,0,0,0,0,0,0,0,0,0)';
      OUTPUT_LOAD='(1.0,-1.0)';
      PINUSE='OUT';
    'DDR0_SA_CS_N3':
      PIN_NUMBER='(0,0,0,0,0,0,0,F53,0,0,0,0,0,0,0,0,0,0,0,0,0,0,0,0,0,0,0,0,0,0~
,0,0,0,0,0,0,0,0,0,0,0,0)';
      OUTPUT_LOAD='(1.0,-1.0)';
      PINUSE='OUT';
    'DDR0_SA_CS_N2':
      PIN_NUMBER='(0,0,0,0,0,0,0,E54,0,0,0,0,0,0,0,0,0,0,0,0,0,0,0,0,0,0,0,0,0,0~
,0,0,0,0,0,0,0,0,0,0,0,0)';
      OUTPUT_LOAD='(1.0,-1.0)';
      PINUSE='OUT';
    'DDR0_SA_CS_N1':
      PIN_NUMBER='(0,0,0,0,0,0,0,B53,0,0,0,0,0,0,0,0,0,0,0,0,0,0,0,0,0,0,0,0,0,0~
,0,0,0,0,0,0,0,0,0,0,0,0)';
      OUTPUT_LOAD='(1.0,-1.0)';
      PINUSE='OUT';
    'DDR0_SA_CS_N0':
      PIN_NUMBER='(0,0,0,0,0,0,0,C54,0,0,0,0,0,0,0,0,0,0,0,0,0,0,0,0,0,0,0,0,0,0~
,0,0,0,0,0,0,0,0,0,0,0,0)';
      OUTPUT_LOAD='(1.0,-1.0)';
      PINUSE='OUT';
    'DDR0_SA_DQ31':
      PIN_NUMBER='(0,0,0,0,0,0,0,E62,0,0,0,0,0,0,0,0,0,0,0,0,0,0,0,0,0,0,0,0,0,0~
,0,0,0,0,0,0,0,0,0,0,0,0)';
      BIDIRECTIONAL='TRUE';
      INPUT_LOAD='(-0.01,0.01)';
      OUTPUT_LOAD='(1.0,-1.0)';
      PINUSE='BI';
    'DDR0_SA_DQ30':
      PIN_NUMBER='(0,0,0,0,0,0,0,F63,0,0,0,0,0,0,0,0,0,0,0,0,0,0,0,0,0,0,0,0,0,0~
,0,0,0,0,0,0,0,0,0,0,0,0)';
      BIDIRECTIONAL='TRUE';
      INPUT_LOAD='(-0.01,0.01)';
      OUTPUT_LOAD='(1.0,-1.0)';
      PINUSE='BI';
    'DDR0_SA_DQ29':
      PIN_NUMBER='(0,0,0,0,0,0,0,C62,0,0,0,0,0,0,0,0,0,0,0,0,0,0,0,0,0,0,0,0,0,0~
,0,0,0,0,0,0,0,0,0,0,0,0)';
      BIDIRECTIONAL='TRUE';
      INPUT_LOAD='(-0.01,0.01)';
      OUTPUT_LOAD='(1.0,-1.0)';
      PINUSE='BI';
    'DDR0_SA_DQ28':
      PIN_NUMBER='(0,0,0,0,0,0,0,B63,0,0,0,0,0,0,0,0,0,0,0,0,0,0,0,0,0,0,0,0,0,0~
,0,0,0,0,0,0,0,0,0,0,0,0)';
      BIDIRECTIONAL='TRUE';
      INPUT_LOAD='(-0.01,0.01)';
      OUTPUT_LOAD='(1.0,-1.0)';
      PINUSE='BI';
    'DDR0_SA_DQ27':
      PIN_NUMBER='(0,0,0,0,0,0,0,F65,0,0,0,0,0,0,0,0,0,0,0,0,0,0,0,0,0,0,0,0,0,0~
,0,0,0,0,0,0,0,0,0,0,0,0)';
      BIDIRECTIONAL='TRUE';
      INPUT_LOAD='(-0.01,0.01)';
      OUTPUT_LOAD='(1.0,-1.0)';
      PINUSE='BI';
    'DDR0_SA_DQ26':
      PIN_NUMBER='(0,0,0,0,0,0,0,E66,0,0,0,0,0,0,0,0,0,0,0,0,0,0,0,0,0,0,0,0,0,0~
,0,0,0,0,0,0,0,0,0,0,0,0)';
      BIDIRECTIONAL='TRUE';
      INPUT_LOAD='(-0.01,0.01)';
      OUTPUT_LOAD='(1.0,-1.0)';
      PINUSE='BI';
    'DDR0_SA_DQ25':
      PIN_NUMBER='(0,0,0,0,0,0,0,B65,0,0,0,0,0,0,0,0,0,0,0,0,0,0,0,0,0,0,0,0,0,0~
,0,0,0,0,0,0,0,0,0,0,0,0)';
      BIDIRECTIONAL='TRUE';
      INPUT_LOAD='(-0.01,0.01)';
      OUTPUT_LOAD='(1.0,-1.0)';
      PINUSE='BI';
    'DDR0_SA_DQ24':
      PIN_NUMBER='(0,0,0,0,0,0,0,C66,0,0,0,0,0,0,0,0,0,0,0,0,0,0,0,0,0,0,0,0,0,0~
,0,0,0,0,0,0,0,0,0,0,0,0)';
      BIDIRECTIONAL='TRUE';
      INPUT_LOAD='(-0.01,0.01)';
      OUTPUT_LOAD='(1.0,-1.0)';
      PINUSE='BI';
    'DDR0_SA_DQ23':
      PIN_NUMBER='(0,0,0,0,0,0,0,E68,0,0,0,0,0,0,0,0,0,0,0,0,0,0,0,0,0,0,0,0,0,0~
,0,0,0,0,0,0,0,0,0,0,0,0)';
      BIDIRECTIONAL='TRUE';
      INPUT_LOAD='(-0.01,0.01)';
      OUTPUT_LOAD='(1.0,-1.0)';
      PINUSE='BI';
    'DDR0_SA_DQ22':
      PIN_NUMBER='(0,0,0,0,0,0,0,F69,0,0,0,0,0,0,0,0,0,0,0,0,0,0,0,0,0,0,0,0,0,0~
,0,0,0,0,0,0,0,0,0,0,0,0)';
      BIDIRECTIONAL='TRUE';
      INPUT_LOAD='(-0.01,0.01)';
      OUTPUT_LOAD='(1.0,-1.0)';
      PINUSE='BI';
    'DDR0_SA_DQ21':
      PIN_NUMBER='(0,0,0,0,0,0,0,C68,0,0,0,0,0,0,0,0,0,0,0,0,0,0,0,0,0,0,0,0,0,0~
,0,0,0,0,0,0,0,0,0,0,0,0)';
      BIDIRECTIONAL='TRUE';
      INPUT_LOAD='(-0.01,0.01)';
      OUTPUT_LOAD='(1.0,-1.0)';
      PINUSE='BI';
    'DDR0_SA_DQ20':
      PIN_NUMBER='(0,0,0,0,0,0,0,B69,0,0,0,0,0,0,0,0,0,0,0,0,0,0,0,0,0,0,0,0,0,0~
,0,0,0,0,0,0,0,0,0,0,0,0)';
      BIDIRECTIONAL='TRUE';
      INPUT_LOAD='(-0.01,0.01)';
      OUTPUT_LOAD='(1.0,-1.0)';
      PINUSE='BI';
    'DDR0_SA_DQ19':
      PIN_NUMBER='(0,0,0,0,0,0,0,F71,0,0,0,0,0,0,0,0,0,0,0,0,0,0,0,0,0,0,0,0,0,0~
,0,0,0,0,0,0,0,0,0,0,0,0)';
      BIDIRECTIONAL='TRUE';
      INPUT_LOAD='(-0.01,0.01)';
      OUTPUT_LOAD='(1.0,-1.0)';
      PINUSE='BI';
    'DDR0_SA_DQ18':
      PIN_NUMBER='(0,0,0,0,0,0,0,D73,0,0,0,0,0,0,0,0,0,0,0,0,0,0,0,0,0,0,0,0,0,0~
,0,0,0,0,0,0,0,0,0,0,0,0)';
      BIDIRECTIONAL='TRUE';
      INPUT_LOAD='(-0.01,0.01)';
      OUTPUT_LOAD='(1.0,-1.0)';
      PINUSE='BI';
    'DDR0_SA_DQ17':
      PIN_NUMBER='(0,0,0,0,0,0,0,E72,0,0,0,0,0,0,0,0,0,0,0,0,0,0,0,0,0,0,0,0,0,0~
,0,0,0,0,0,0,0,0,0,0,0,0)';
      BIDIRECTIONAL='TRUE';
      INPUT_LOAD='(-0.01,0.01)';
      OUTPUT_LOAD='(1.0,-1.0)';
      PINUSE='BI';
    'DDR0_SA_DQ16':
      PIN_NUMBER='(0,0,0,0,0,0,0,B73,0,0,0,0,0,0,0,0,0,0,0,0,0,0,0,0,0,0,0,0,0,0~
,0,0,0,0,0,0,0,0,0,0,0,0)';
      BIDIRECTIONAL='TRUE';
      INPUT_LOAD='(-0.01,0.01)';
      OUTPUT_LOAD='(1.0,-1.0)';
      PINUSE='BI';
    'DDR0_SA_DQ15':
      PIN_NUMBER='(0,0,0,0,0,0,0,M65,0,0,0,0,0,0,0,0,0,0,0,0,0,0,0,0,0,0,0,0,0,0~
,0,0,0,0,0,0,0,0,0,0,0,0)';
      BIDIRECTIONAL='TRUE';
      INPUT_LOAD='(-0.01,0.01)';
      OUTPUT_LOAD='(1.0,-1.0)';
      PINUSE='BI';
    'DDR0_SA_DQ14':
      PIN_NUMBER='(0,0,0,0,0,0,0,N66,0,0,0,0,0,0,0,0,0,0,0,0,0,0,0,0,0,0,0,0,0,0~
,0,0,0,0,0,0,0,0,0,0,0,0)';
      BIDIRECTIONAL='TRUE';
      INPUT_LOAD='(-0.01,0.01)';
      OUTPUT_LOAD='(1.0,-1.0)';
      PINUSE='BI';
    'DDR0_SA_DQ13':
      PIN_NUMBER='(0,0,0,0,0,0,0,K65,0,0,0,0,0,0,0,0,0,0,0,0,0,0,0,0,0,0,0,0,0,0~
,0,0,0,0,0,0,0,0,0,0,0,0)';
      BIDIRECTIONAL='TRUE';
      INPUT_LOAD='(-0.01,0.01)';
      OUTPUT_LOAD='(1.0,-1.0)';
      PINUSE='BI';
    'DDR0_SA_DQ12':
      PIN_NUMBER='(0,0,0,0,0,0,0,J66,0,0,0,0,0,0,0,0,0,0,0,0,0,0,0,0,0,0,0,0,0,0~
,0,0,0,0,0,0,0,0,0,0,0,0)';
      BIDIRECTIONAL='TRUE';
      INPUT_LOAD='(-0.01,0.01)';
      OUTPUT_LOAD='(1.0,-1.0)';
      PINUSE='BI';
    'DDR0_SA_DQ11':
      PIN_NUMBER='(0,0,0,0,0,0,0,N68,0,0,0,0,0,0,0,0,0,0,0,0,0,0,0,0,0,0,0,0,0,0~
,0,0,0,0,0,0,0,0,0,0,0,0)';
      BIDIRECTIONAL='TRUE';
      INPUT_LOAD='(-0.01,0.01)';
      OUTPUT_LOAD='(1.0,-1.0)';
      PINUSE='BI';
    'DDR0_SA_DQ10':
      PIN_NUMBER='(0,0,0,0,0,0,0,M69,0,0,0,0,0,0,0,0,0,0,0,0,0,0,0,0,0,0,0,0,0,0~
,0,0,0,0,0,0,0,0,0,0,0,0)';
      BIDIRECTIONAL='TRUE';
      INPUT_LOAD='(-0.01,0.01)';
      OUTPUT_LOAD='(1.0,-1.0)';
      PINUSE='BI';
    'DDR0_SA_DQ9':
      PIN_NUMBER='(0,0,0,0,0,0,0,J68,0,0,0,0,0,0,0,0,0,0,0,0,0,0,0,0,0,0,0,0,0,0~
,0,0,0,0,0,0,0,0,0,0,0,0)';
      BIDIRECTIONAL='TRUE';
      INPUT_LOAD='(-0.01,0.01)';
      OUTPUT_LOAD='(1.0,-1.0)';
      PINUSE='BI';
    'DDR0_SA_DQ8':
      PIN_NUMBER='(0,0,0,0,0,0,0,K69,0,0,0,0,0,0,0,0,0,0,0,0,0,0,0,0,0,0,0,0,0,0~
,0,0,0,0,0,0,0,0,0,0,0,0)';
      BIDIRECTIONAL='TRUE';
      INPUT_LOAD='(-0.01,0.01)';
      OUTPUT_LOAD='(1.0,-1.0)';
      PINUSE='BI';
    'DDR0_SA_DQ7':
      PIN_NUMBER='(0,0,0,0,0,0,0,F75,0,0,0,0,0,0,0,0,0,0,0,0,0,0,0,0,0,0,0,0,0,0~
,0,0,0,0,0,0,0,0,0,0,0,0)';
      BIDIRECTIONAL='TRUE';
      INPUT_LOAD='(-0.01,0.01)';
      OUTPUT_LOAD='(1.0,-1.0)';
      PINUSE='BI';
    'DDR0_SA_DQ6':
      PIN_NUMBER='(0,0,0,0,0,0,0,G76,0,0,0,0,0,0,0,0,0,0,0,0,0,0,0,0,0,0,0,0,0,0~
,0,0,0,0,0,0,0,0,0,0,0,0)';
      BIDIRECTIONAL='TRUE';
      INPUT_LOAD='(-0.01,0.01)';
      OUTPUT_LOAD='(1.0,-1.0)';
      PINUSE='BI';
    'DDR0_SA_DQ5':
      PIN_NUMBER='(0,0,0,0,0,0,0,D75,0,0,0,0,0,0,0,0,0,0,0,0,0,0,0,0,0,0,0,0,0,0~
,0,0,0,0,0,0,0,0,0,0,0,0)';
      BIDIRECTIONAL='TRUE';
      INPUT_LOAD='(-0.01,0.01)';
      OUTPUT_LOAD='(1.0,-1.0)';
      PINUSE='BI';
    'DDR0_SA_DQ4':
      PIN_NUMBER='(0,0,0,0,0,0,0,C76,0,0,0,0,0,0,0,0,0,0,0,0,0,0,0,0,0,0,0,0,0,0~
,0,0,0,0,0,0,0,0,0,0,0,0)';
      BIDIRECTIONAL='TRUE';
      INPUT_LOAD='(-0.01,0.01)';
      OUTPUT_LOAD='(1.0,-1.0)';
      PINUSE='BI';
    'DDR0_SA_DQ3':
      PIN_NUMBER='(0,0,0,0,0,0,0,G78,0,0,0,0,0,0,0,0,0,0,0,0,0,0,0,0,0,0,0,0,0,0~
,0,0,0,0,0,0,0,0,0,0,0,0)';
      BIDIRECTIONAL='TRUE';
      INPUT_LOAD='(-0.01,0.01)';
      OUTPUT_LOAD='(1.0,-1.0)';
      PINUSE='BI';
    'DDR0_SA_DQ2':
      PIN_NUMBER='(0,0,0,0,0,0,0,M77,0,0,0,0,0,0,0,0,0,0,0,0,0,0,0,0,0,0,0,0,0,0~
,0,0,0,0,0,0,0,0,0,0,0,0)';
      BIDIRECTIONAL='TRUE';
      INPUT_LOAD='(-0.01,0.01)';
      OUTPUT_LOAD='(1.0,-1.0)';
      PINUSE='BI';
    'DDR0_SA_DQ1':
      PIN_NUMBER='(0,0,0,0,0,0,0,B79,0,0,0,0,0,0,0,0,0,0,0,0,0,0,0,0,0,0,0,0,0,0~
,0,0,0,0,0,0,0,0,0,0,0,0)';
      BIDIRECTIONAL='TRUE';
      INPUT_LOAD='(-0.01,0.01)';
      OUTPUT_LOAD='(1.0,-1.0)';
      PINUSE='BI';
    'DDR0_SA_DQ0':
      PIN_NUMBER='(0,0,0,0,0,0,0,B81,0,0,0,0,0,0,0,0,0,0,0,0,0,0,0,0,0,0,0,0,0,0~
,0,0,0,0,0,0,0,0,0,0,0,0)';
      BIDIRECTIONAL='TRUE';
      INPUT_LOAD='(-0.01,0.01)';
      OUTPUT_LOAD='(1.0,-1.0)';
      PINUSE='BI';
    'DDR0_SA_DQS_DN9':
      PIN_NUMBER='(0,0,0,0,0,0,0,G58,0,0,0,0,0,0,0,0,0,0,0,0,0,0,0,0,0,0,0,0,0,0~
,0,0,0,0,0,0,0,0,0,0,0,0)';
      BIDIRECTIONAL='TRUE';
      INPUT_LOAD='(-0.01,0.01)';
      OUTPUT_LOAD='(1.0,-1.0)';
      PINUSE='BI';
    'DDR0_SA_DQS_DN8':
      PIN_NUMBER='(0,0,0,0,0,0,0,G64,0,0,0,0,0,0,0,0,0,0,0,0,0,0,0,0,0,0,0,0,0,0~
,0,0,0,0,0,0,0,0,0,0,0,0)';
      BIDIRECTIONAL='TRUE';
      INPUT_LOAD='(-0.01,0.01)';
      OUTPUT_LOAD='(1.0,-1.0)';
      PINUSE='BI';
    'DDR0_SA_DQS_DN7':
      PIN_NUMBER='(0,0,0,0,0,0,0,G70,0,0,0,0,0,0,0,0,0,0,0,0,0,0,0,0,0,0,0,0,0,0~
,0,0,0,0,0,0,0,0,0,0,0,0)';
      BIDIRECTIONAL='TRUE';
      INPUT_LOAD='(-0.01,0.01)';
      OUTPUT_LOAD='(1.0,-1.0)';
      PINUSE='BI';
    'DDR0_SA_DQS_DN6':
      PIN_NUMBER='(0,0,0,0,0,0,0,P67,0,0,0,0,0,0,0,0,0,0,0,0,0,0,0,0,0,0,0,0,0,0~
,0,0,0,0,0,0,0,0,0,0,0,0)';
      BIDIRECTIONAL='TRUE';
      INPUT_LOAD='(-0.01,0.01)';
      OUTPUT_LOAD='(1.0,-1.0)';
      PINUSE='BI';
    'DDR0_SA_DQS_DN5':
      PIN_NUMBER='(0,0,0,0,0,0,0,H77,0,0,0,0,0,0,0,0,0,0,0,0,0,0,0,0,0,0,0,0,0,0~
,0,0,0,0,0,0,0,0,0,0,0,0)';
      BIDIRECTIONAL='TRUE';
      INPUT_LOAD='(-0.01,0.01)';
      OUTPUT_LOAD='(1.0,-1.0)';
      PINUSE='BI';
    'DDR0_SA_DQS_DN4':
      PIN_NUMBER='(0,0,0,0,0,0,0,A58,0,0,0,0,0,0,0,0,0,0,0,0,0,0,0,0,0,0,0,0,0,0~
,0,0,0,0,0,0,0,0,0,0,0,0)';
      BIDIRECTIONAL='TRUE';
      INPUT_LOAD='(-0.01,0.01)';
      OUTPUT_LOAD='(1.0,-1.0)';
      PINUSE='BI';
    'DDR0_SA_DQS_DN3':
      PIN_NUMBER='(0,0,0,0,0,0,0,A64,0,0,0,0,0,0,0,0,0,0,0,0,0,0,0,0,0,0,0,0,0,0~
,0,0,0,0,0,0,0,0,0,0,0,0)';
      BIDIRECTIONAL='TRUE';
      INPUT_LOAD='(-0.01,0.01)';
      OUTPUT_LOAD='(1.0,-1.0)';
      PINUSE='BI';
    'DDR0_SA_DQS_DN2':
      PIN_NUMBER='(0,0,0,0,0,0,0,B71,0,0,0,0,0,0,0,0,0,0,0,0,0,0,0,0,0,0,0,0,0,0~
,0,0,0,0,0,0,0,0,0,0,0,0)';
      BIDIRECTIONAL='TRUE';
      INPUT_LOAD='(-0.01,0.01)';
      OUTPUT_LOAD='(1.0,-1.0)';
      PINUSE='BI';
    'DDR0_SA_DQS_DN1':
      PIN_NUMBER='(0,0,0,0,0,0,0,H67,0,0,0,0,0,0,0,0,0,0,0,0,0,0,0,0,0,0,0,0,0,0~
,0,0,0,0,0,0,0,0,0,0,0,0)';
      BIDIRECTIONAL='TRUE';
      INPUT_LOAD='(-0.01,0.01)';
      OUTPUT_LOAD='(1.0,-1.0)';
      PINUSE='BI';
    'DDR0_SA_DQS_DN0':
      PIN_NUMBER='(0,0,0,0,0,0,0,B77,0,0,0,0,0,0,0,0,0,0,0,0,0,0,0,0,0,0,0,0,0,0~
,0,0,0,0,0,0,0,0,0,0,0,0)';
      BIDIRECTIONAL='TRUE';
      INPUT_LOAD='(-0.01,0.01)';
      OUTPUT_LOAD='(1.0,-1.0)';
      PINUSE='BI';
    'DDR0_SA_DQS_DP9':
      PIN_NUMBER='(0,0,0,0,0,0,0,E58,0,0,0,0,0,0,0,0,0,0,0,0,0,0,0,0,0,0,0,0,0,0~
,0,0,0,0,0,0,0,0,0,0,0,0)';
      BIDIRECTIONAL='TRUE';
      INPUT_LOAD='(-0.01,0.01)';
      OUTPUT_LOAD='(1.0,-1.0)';
      PINUSE='BI';
    'DDR0_SA_DQS_DP8':
      PIN_NUMBER='(0,0,0,0,0,0,0,E64,0,0,0,0,0,0,0,0,0,0,0,0,0,0,0,0,0,0,0,0,0,0~
,0,0,0,0,0,0,0,0,0,0,0,0)';
      BIDIRECTIONAL='TRUE';
      INPUT_LOAD='(-0.01,0.01)';
      OUTPUT_LOAD='(1.0,-1.0)';
      PINUSE='BI';
    'DDR0_SA_DQS_DP7':
      PIN_NUMBER='(0,0,0,0,0,0,0,E70,0,0,0,0,0,0,0,0,0,0,0,0,0,0,0,0,0,0,0,0,0,0~
,0,0,0,0,0,0,0,0,0,0,0,0)';
      BIDIRECTIONAL='TRUE';
      INPUT_LOAD='(-0.01,0.01)';
      OUTPUT_LOAD='(1.0,-1.0)';
      PINUSE='BI';
    'DDR0_SA_DQS_DP6':
      PIN_NUMBER='(0,0,0,0,0,0,0,M67,0,0,0,0,0,0,0,0,0,0,0,0,0,0,0,0,0,0,0,0,0,0~
,0,0,0,0,0,0,0,0,0,0,0,0)';
      BIDIRECTIONAL='TRUE';
      INPUT_LOAD='(-0.01,0.01)';
      OUTPUT_LOAD='(1.0,-1.0)';
      PINUSE='BI';
    'DDR0_SA_DQS_DP5':
      PIN_NUMBER='(0,0,0,0,0,0,0,F77,0,0,0,0,0,0,0,0,0,0,0,0,0,0,0,0,0,0,0,0,0,0~
,0,0,0,0,0,0,0,0,0,0,0,0)';
      BIDIRECTIONAL='TRUE';
      INPUT_LOAD='(-0.01,0.01)';
      OUTPUT_LOAD='(1.0,-1.0)';
      PINUSE='BI';
    'DDR0_SA_DQS_DP4':
      PIN_NUMBER='(0,0,0,0,0,0,0,C58,0,0,0,0,0,0,0,0,0,0,0,0,0,0,0,0,0,0,0,0,0,0~
,0,0,0,0,0,0,0,0,0,0,0,0)';
      BIDIRECTIONAL='TRUE';
      INPUT_LOAD='(-0.01,0.01)';
      OUTPUT_LOAD='(1.0,-1.0)';
      PINUSE='BI';
    'DDR0_SA_DQS_DP3':
      PIN_NUMBER='(0,0,0,0,0,0,0,C64,0,0,0,0,0,0,0,0,0,0,0,0,0,0,0,0,0,0,0,0,0,0~
,0,0,0,0,0,0,0,0,0,0,0,0)';
      BIDIRECTIONAL='TRUE';
      INPUT_LOAD='(-0.01,0.01)';
      OUTPUT_LOAD='(1.0,-1.0)';
      PINUSE='BI';
    'DDR0_SA_DQS_DP2':
      PIN_NUMBER='(0,0,0,0,0,0,0,C70,0,0,0,0,0,0,0,0,0,0,0,0,0,0,0,0,0,0,0,0,0,0~
,0,0,0,0,0,0,0,0,0,0,0,0)';
      BIDIRECTIONAL='TRUE';
      INPUT_LOAD='(-0.01,0.01)';
      OUTPUT_LOAD='(1.0,-1.0)';
      PINUSE='BI';
    'DDR0_SA_DQS_DP1':
      PIN_NUMBER='(0,0,0,0,0,0,0,K67,0,0,0,0,0,0,0,0,0,0,0,0,0,0,0,0,0,0,0,0,0,0~
,0,0,0,0,0,0,0,0,0,0,0,0)';
      BIDIRECTIONAL='TRUE';
      INPUT_LOAD='(-0.01,0.01)';
      OUTPUT_LOAD='(1.0,-1.0)';
      PINUSE='BI';
    'DDR0_SA_DQS_DP0':
      PIN_NUMBER='(0,0,0,0,0,0,0,D77,0,0,0,0,0,0,0,0,0,0,0,0,0,0,0,0,0,0,0,0,0,0~
,0,0,0,0,0,0,0,0,0,0,0,0)';
      BIDIRECTIONAL='TRUE';
      INPUT_LOAD='(-0.01,0.01)';
      OUTPUT_LOAD='(1.0,-1.0)';
      PINUSE='BI';
    'DDR0_SA_ECC7':
      PIN_NUMBER='(0,0,0,0,0,0,0,E56,0,0,0,0,0,0,0,0,0,0,0,0,0,0,0,0,0,0,0,0,0,0~
,0,0,0,0,0,0,0,0,0,0,0,0)';
      BIDIRECTIONAL='TRUE';
      INPUT_LOAD='(-0.01,0.01)';
      OUTPUT_LOAD='(1.0,-1.0)';
      PINUSE='BI';
    'DDR0_SA_ECC6':
      PIN_NUMBER='(0,0,0,0,0,0,0,F57,0,0,0,0,0,0,0,0,0,0,0,0,0,0,0,0,0,0,0,0,0,0~
,0,0,0,0,0,0,0,0,0,0,0,0)';
      BIDIRECTIONAL='TRUE';
      INPUT_LOAD='(-0.01,0.01)';
      OUTPUT_LOAD='(1.0,-1.0)';
      PINUSE='BI';
    'DDR0_SA_ECC5':
      PIN_NUMBER='(0,0,0,0,0,0,0,C56,0,0,0,0,0,0,0,0,0,0,0,0,0,0,0,0,0,0,0,0,0,0~
,0,0,0,0,0,0,0,0,0,0,0,0)';
      BIDIRECTIONAL='TRUE';
      INPUT_LOAD='(-0.01,0.01)';
      OUTPUT_LOAD='(1.0,-1.0)';
      PINUSE='BI';
    'DDR0_SA_ECC4':
      PIN_NUMBER='(0,0,0,0,0,0,0,B57,0,0,0,0,0,0,0,0,0,0,0,0,0,0,0,0,0,0,0,0,0,0~
,0,0,0,0,0,0,0,0,0,0,0,0)';
      BIDIRECTIONAL='TRUE';
      INPUT_LOAD='(-0.01,0.01)';
      OUTPUT_LOAD='(1.0,-1.0)';
      PINUSE='BI';
    'DDR0_SA_ECC3':
      PIN_NUMBER='(0,0,0,0,0,0,0,F59,0,0,0,0,0,0,0,0,0,0,0,0,0,0,0,0,0,0,0,0,0,0~
,0,0,0,0,0,0,0,0,0,0,0,0)';
      BIDIRECTIONAL='TRUE';
      INPUT_LOAD='(-0.01,0.01)';
      OUTPUT_LOAD='(1.0,-1.0)';
      PINUSE='BI';
    'DDR0_SA_ECC2':
      PIN_NUMBER='(0,0,0,0,0,0,0,E60,0,0,0,0,0,0,0,0,0,0,0,0,0,0,0,0,0,0,0,0,0,0~
,0,0,0,0,0,0,0,0,0,0,0,0)';
      BIDIRECTIONAL='TRUE';
      INPUT_LOAD='(-0.01,0.01)';
      OUTPUT_LOAD='(1.0,-1.0)';
      PINUSE='BI';
    'DDR0_SA_ECC1':
      PIN_NUMBER='(0,0,0,0,0,0,0,B59,0,0,0,0,0,0,0,0,0,0,0,0,0,0,0,0,0,0,0,0,0,0~
,0,0,0,0,0,0,0,0,0,0,0,0)';
      BIDIRECTIONAL='TRUE';
      INPUT_LOAD='(-0.01,0.01)';
      OUTPUT_LOAD='(1.0,-1.0)';
      PINUSE='BI';
    'DDR0_SA_ECC0':
      PIN_NUMBER='(0,0,0,0,0,0,0,C60,0,0,0,0,0,0,0,0,0,0,0,0,0,0,0,0,0,0,0,0,0,0~
,0,0,0,0,0,0,0,0,0,0,0,0)';
      BIDIRECTIONAL='TRUE';
      INPUT_LOAD='(-0.01,0.01)';
      OUTPUT_LOAD='(1.0,-1.0)';
      PINUSE='BI';
    'DDR0_SA_PAR':
      PIN_NUMBER='(0,0,0,0,0,0,0,E48,0,0,0,0,0,0,0,0,0,0,0,0,0,0,0,0,0,0,0,0,0,0~
,0,0,0,0,0,0,0,0,0,0,0,0)';
      OUTPUT_LOAD='(1.0,-1.0)';
      PINUSE='OUT';
    'DDR0_SB_CA6':
      PIN_NUMBER='(0,0,0,0,0,0,0,A39,0,0,0,0,0,0,0,0,0,0,0,0,0,0,0,0,0,0,0,0,0,0~
,0,0,0,0,0,0,0,0,0,0,0,0)';
      OUTPUT_LOAD='(1.0,-1.0)';
      PINUSE='OUT';
    'DDR0_SB_CA5':
      PIN_NUMBER='(0,0,0,0,0,0,0,F40,0,0,0,0,0,0,0,0,0,0,0,0,0,0,0,0,0,0,0,0,0,0~
,0,0,0,0,0,0,0,0,0,0,0,0)';
      OUTPUT_LOAD='(1.0,-1.0)';
      PINUSE='OUT';
    'DDR0_SB_CA4':
      PIN_NUMBER='(0,0,0,0,0,0,0,B40,0,0,0,0,0,0,0,0,0,0,0,0,0,0,0,0,0,0,0,0,0,0~
,0,0,0,0,0,0,0,0,0,0,0,0)';
      OUTPUT_LOAD='(1.0,-1.0)';
      PINUSE='OUT';
    'DDR0_SB_CA3':
      PIN_NUMBER='(0,0,0,0,0,0,0,E41,0,0,0,0,0,0,0,0,0,0,0,0,0,0,0,0,0,0,0,0,0,0~
,0,0,0,0,0,0,0,0,0,0,0,0)';
      OUTPUT_LOAD='(1.0,-1.0)';
      PINUSE='OUT';
    'DDR0_SB_CA2':
      PIN_NUMBER='(0,0,0,0,0,0,0,C41,0,0,0,0,0,0,0,0,0,0,0,0,0,0,0,0,0,0,0,0,0,0~
,0,0,0,0,0,0,0,0,0,0,0,0)';
      OUTPUT_LOAD='(1.0,-1.0)';
      PINUSE='OUT';
    'DDR0_SB_CA1':
      PIN_NUMBER='(0,0,0,0,0,0,0,F44,0,0,0,0,0,0,0,0,0,0,0,0,0,0,0,0,0,0,0,0,0,0~
,0,0,0,0,0,0,0,0,0,0,0,0)';
      OUTPUT_LOAD='(1.0,-1.0)';
      PINUSE='OUT';
    'DDR0_SB_CA0':
      PIN_NUMBER='(0,0,0,0,0,0,0,E43,0,0,0,0,0,0,0,0,0,0,0,0,0,0,0,0,0,0,0,0,0,0~
,0,0,0,0,0,0,0,0,0,0,0,0)';
      OUTPUT_LOAD='(1.0,-1.0)';
      PINUSE='OUT';
    'DDR0_SB_CS_N3':
      PIN_NUMBER='(0,0,0,0,0,0,0,E37,0,0,0,0,0,0,0,0,0,0,0,0,0,0,0,0,0,0,0,0,0,0~
,0,0,0,0,0,0,0,0,0,0,0,0)';
      OUTPUT_LOAD='(1.0,-1.0)';
      PINUSE='OUT';
    'DDR0_SB_CS_N2':
      PIN_NUMBER='(0,0,0,0,0,0,0,F38,0,0,0,0,0,0,0,0,0,0,0,0,0,0,0,0,0,0,0,0,0,0~
,0,0,0,0,0,0,0,0,0,0,0,0)';
      OUTPUT_LOAD='(1.0,-1.0)';
      PINUSE='OUT';
    'DDR0_SB_CS_N1':
      PIN_NUMBER='(0,0,0,0,0,0,0,C37,0,0,0,0,0,0,0,0,0,0,0,0,0,0,0,0,0,0,0,0,0,0~
,0,0,0,0,0,0,0,0,0,0,0,0)';
      OUTPUT_LOAD='(1.0,-1.0)';
      PINUSE='OUT';
    'DDR0_SB_CS_N0':
      PIN_NUMBER='(0,0,0,0,0,0,0,B38,0,0,0,0,0,0,0,0,0,0,0,0,0,0,0,0,0,0,0,0,0,0~
,0,0,0,0,0,0,0,0,0,0,0,0)';
      OUTPUT_LOAD='(1.0,-1.0)';
      PINUSE='OUT';
    'DDR0_SB_DQ31':
      PIN_NUMBER='(0,0,0,0,0,0,0,E7,0,0,0,0,0,0,0,0,0,0,0,0,0,0,0,0,0,0,0,0,0,0,~
0,0,0,0,0,0,0,0,0,0,0,0)';
      BIDIRECTIONAL='TRUE';
      INPUT_LOAD='(-0.01,0.01)';
      OUTPUT_LOAD='(1.0,-1.0)';
      PINUSE='BI';
    'DDR0_SB_DQ30':
      PIN_NUMBER='(0,0,0,0,0,0,0,F8,0,0,0,0,0,0,0,0,0,0,0,0,0,0,0,0,0,0,0,0,0,0,~
0,0,0,0,0,0,0,0,0,0,0,0)';
      BIDIRECTIONAL='TRUE';
      INPUT_LOAD='(-0.01,0.01)';
      OUTPUT_LOAD='(1.0,-1.0)';
      PINUSE='BI';
    'DDR0_SB_DQ29':
      PIN_NUMBER='(0,0,0,0,0,0,0,C7,0,0,0,0,0,0,0,0,0,0,0,0,0,0,0,0,0,0,0,0,0,0,~
0,0,0,0,0,0,0,0,0,0,0,0)';
      BIDIRECTIONAL='TRUE';
      INPUT_LOAD='(-0.01,0.01)';
      OUTPUT_LOAD='(1.0,-1.0)';
      PINUSE='BI';
    'DDR0_SB_DQ28':
      PIN_NUMBER='(0,0,0,0,0,0,0,B8,0,0,0,0,0,0,0,0,0,0,0,0,0,0,0,0,0,0,0,0,0,0,~
0,0,0,0,0,0,0,0,0,0,0,0)';
      BIDIRECTIONAL='TRUE';
      INPUT_LOAD='(-0.01,0.01)';
      OUTPUT_LOAD='(1.0,-1.0)';
      PINUSE='BI';
    'DDR0_SB_DQ27':
      PIN_NUMBER='(0,0,0,0,0,0,0,F10,0,0,0,0,0,0,0,0,0,0,0,0,0,0,0,0,0,0,0,0,0,0~
,0,0,0,0,0,0,0,0,0,0,0,0)';
      BIDIRECTIONAL='TRUE';
      INPUT_LOAD='(-0.01,0.01)';
      OUTPUT_LOAD='(1.0,-1.0)';
      PINUSE='BI';
    'DDR0_SB_DQ26':
      PIN_NUMBER='(0,0,0,0,0,0,0,E11,0,0,0,0,0,0,0,0,0,0,0,0,0,0,0,0,0,0,0,0,0,0~
,0,0,0,0,0,0,0,0,0,0,0,0)';
      BIDIRECTIONAL='TRUE';
      INPUT_LOAD='(-0.01,0.01)';
      OUTPUT_LOAD='(1.0,-1.0)';
      PINUSE='BI';
    'DDR0_SB_DQ25':
      PIN_NUMBER='(0,0,0,0,0,0,0,B10,0,0,0,0,0,0,0,0,0,0,0,0,0,0,0,0,0,0,0,0,0,0~
,0,0,0,0,0,0,0,0,0,0,0,0)';
      BIDIRECTIONAL='TRUE';
      INPUT_LOAD='(-0.01,0.01)';
      OUTPUT_LOAD='(1.0,-1.0)';
      PINUSE='BI';
    'DDR0_SB_DQ24':
      PIN_NUMBER='(0,0,0,0,0,0,0,C11,0,0,0,0,0,0,0,0,0,0,0,0,0,0,0,0,0,0,0,0,0,0~
,0,0,0,0,0,0,0,0,0,0,0,0)';
      BIDIRECTIONAL='TRUE';
      INPUT_LOAD='(-0.01,0.01)';
      OUTPUT_LOAD='(1.0,-1.0)';
      PINUSE='BI';
    'DDR0_SB_DQ23':
      PIN_NUMBER='(0,0,0,0,0,0,0,E19,0,0,0,0,0,0,0,0,0,0,0,0,0,0,0,0,0,0,0,0,0,0~
,0,0,0,0,0,0,0,0,0,0,0,0)';
      BIDIRECTIONAL='TRUE';
      INPUT_LOAD='(-0.01,0.01)';
      OUTPUT_LOAD='(1.0,-1.0)';
      PINUSE='BI';
    'DDR0_SB_DQ22':
      PIN_NUMBER='(0,0,0,0,0,0,0,F20,0,0,0,0,0,0,0,0,0,0,0,0,0,0,0,0,0,0,0,0,0,0~
,0,0,0,0,0,0,0,0,0,0,0,0)';
      BIDIRECTIONAL='TRUE';
      INPUT_LOAD='(-0.01,0.01)';
      OUTPUT_LOAD='(1.0,-1.0)';
      PINUSE='BI';
    'DDR0_SB_DQ21':
      PIN_NUMBER='(0,0,0,0,0,0,0,C19,0,0,0,0,0,0,0,0,0,0,0,0,0,0,0,0,0,0,0,0,0,0~
,0,0,0,0,0,0,0,0,0,0,0,0)';
      BIDIRECTIONAL='TRUE';
      INPUT_LOAD='(-0.01,0.01)';
      OUTPUT_LOAD='(1.0,-1.0)';
      PINUSE='BI';
    'DDR0_SB_DQ20':
      PIN_NUMBER='(0,0,0,0,0,0,0,B20,0,0,0,0,0,0,0,0,0,0,0,0,0,0,0,0,0,0,0,0,0,0~
,0,0,0,0,0,0,0,0,0,0,0,0)';
      BIDIRECTIONAL='TRUE';
      INPUT_LOAD='(-0.01,0.01)';
      OUTPUT_LOAD='(1.0,-1.0)';
      PINUSE='BI';
    'DDR0_SB_DQ19':
      PIN_NUMBER='(0,0,0,0,0,0,0,F22,0,0,0,0,0,0,0,0,0,0,0,0,0,0,0,0,0,0,0,0,0,0~
,0,0,0,0,0,0,0,0,0,0,0,0)';
      BIDIRECTIONAL='TRUE';
      INPUT_LOAD='(-0.01,0.01)';
      OUTPUT_LOAD='(1.0,-1.0)';
      PINUSE='BI';
    'DDR0_SB_DQ18':
      PIN_NUMBER='(0,0,0,0,0,0,0,E23,0,0,0,0,0,0,0,0,0,0,0,0,0,0,0,0,0,0,0,0,0,0~
,0,0,0,0,0,0,0,0,0,0,0,0)';
      BIDIRECTIONAL='TRUE';
      INPUT_LOAD='(-0.01,0.01)';
      OUTPUT_LOAD='(1.0,-1.0)';
      PINUSE='BI';
    'DDR0_SB_DQ17':
      PIN_NUMBER='(0,0,0,0,0,0,0,B22,0,0,0,0,0,0,0,0,0,0,0,0,0,0,0,0,0,0,0,0,0,0~
,0,0,0,0,0,0,0,0,0,0,0,0)';
      BIDIRECTIONAL='TRUE';
      INPUT_LOAD='(-0.01,0.01)';
      OUTPUT_LOAD='(1.0,-1.0)';
      PINUSE='BI';
    'DDR0_SB_DQ16':
      PIN_NUMBER='(0,0,0,0,0,0,0,C23,0,0,0,0,0,0,0,0,0,0,0,0,0,0,0,0,0,0,0,0,0,0~
,0,0,0,0,0,0,0,0,0,0,0,0)';
      BIDIRECTIONAL='TRUE';
      INPUT_LOAD='(-0.01,0.01)';
      OUTPUT_LOAD='(1.0,-1.0)';
      PINUSE='BI';
    'DDR0_SB_DQ15':
      PIN_NUMBER='(0,0,0,0,0,0,0,E25,0,0,0,0,0,0,0,0,0,0,0,0,0,0,0,0,0,0,0,0,0,0~
,0,0,0,0,0,0,0,0,0,0,0,0)';
      BIDIRECTIONAL='TRUE';
      INPUT_LOAD='(-0.01,0.01)';
      OUTPUT_LOAD='(1.0,-1.0)';
      PINUSE='BI';
    'DDR0_SB_DQ14':
      PIN_NUMBER='(0,0,0,0,0,0,0,F26,0,0,0,0,0,0,0,0,0,0,0,0,0,0,0,0,0,0,0,0,0,0~
,0,0,0,0,0,0,0,0,0,0,0,0)';
      BIDIRECTIONAL='TRUE';
      INPUT_LOAD='(-0.01,0.01)';
      OUTPUT_LOAD='(1.0,-1.0)';
      PINUSE='BI';
    'DDR0_SB_DQ13':
      PIN_NUMBER='(0,0,0,0,0,0,0,C25,0,0,0,0,0,0,0,0,0,0,0,0,0,0,0,0,0,0,0,0,0,0~
,0,0,0,0,0,0,0,0,0,0,0,0)';
      BIDIRECTIONAL='TRUE';
      INPUT_LOAD='(-0.01,0.01)';
      OUTPUT_LOAD='(1.0,-1.0)';
      PINUSE='BI';
    'DDR0_SB_DQ12':
      PIN_NUMBER='(0,0,0,0,0,0,0,B26,0,0,0,0,0,0,0,0,0,0,0,0,0,0,0,0,0,0,0,0,0,0~
,0,0,0,0,0,0,0,0,0,0,0,0)';
      BIDIRECTIONAL='TRUE';
      INPUT_LOAD='(-0.01,0.01)';
      OUTPUT_LOAD='(1.0,-1.0)';
      PINUSE='BI';
    'DDR0_SB_DQ11':
      PIN_NUMBER='(0,0,0,0,0,0,0,F28,0,0,0,0,0,0,0,0,0,0,0,0,0,0,0,0,0,0,0,0,0,0~
,0,0,0,0,0,0,0,0,0,0,0,0)';
      BIDIRECTIONAL='TRUE';
      INPUT_LOAD='(-0.01,0.01)';
      OUTPUT_LOAD='(1.0,-1.0)';
      PINUSE='BI';
    'DDR0_SB_DQ10':
      PIN_NUMBER='(0,0,0,0,0,0,0,E29,0,0,0,0,0,0,0,0,0,0,0,0,0,0,0,0,0,0,0,0,0,0~
,0,0,0,0,0,0,0,0,0,0,0,0)';
      BIDIRECTIONAL='TRUE';
      INPUT_LOAD='(-0.01,0.01)';
      OUTPUT_LOAD='(1.0,-1.0)';
      PINUSE='BI';
    'DDR0_SB_DQ9':
      PIN_NUMBER='(0,0,0,0,0,0,0,B28,0,0,0,0,0,0,0,0,0,0,0,0,0,0,0,0,0,0,0,0,0,0~
,0,0,0,0,0,0,0,0,0,0,0,0)';
      BIDIRECTIONAL='TRUE';
      INPUT_LOAD='(-0.01,0.01)';
      OUTPUT_LOAD='(1.0,-1.0)';
      PINUSE='BI';
    'DDR0_SB_DQ8':
      PIN_NUMBER='(0,0,0,0,0,0,0,C29,0,0,0,0,0,0,0,0,0,0,0,0,0,0,0,0,0,0,0,0,0,0~
,0,0,0,0,0,0,0,0,0,0,0,0)';
      BIDIRECTIONAL='TRUE';
      INPUT_LOAD='(-0.01,0.01)';
      OUTPUT_LOAD='(1.0,-1.0)';
      PINUSE='BI';
    'DDR0_SB_DQ7':
      PIN_NUMBER='(0,0,0,0,0,0,0,M28,0,0,0,0,0,0,0,0,0,0,0,0,0,0,0,0,0,0,0,0,0,0~
,0,0,0,0,0,0,0,0,0,0,0,0)';
      BIDIRECTIONAL='TRUE';
      INPUT_LOAD='(-0.01,0.01)';
      OUTPUT_LOAD='(1.0,-1.0)';
      PINUSE='BI';
    'DDR0_SB_DQ6':
      PIN_NUMBER='(0,0,0,0,0,0,0,N29,0,0,0,0,0,0,0,0,0,0,0,0,0,0,0,0,0,0,0,0,0,0~
,0,0,0,0,0,0,0,0,0,0,0,0)';
      BIDIRECTIONAL='TRUE';
      INPUT_LOAD='(-0.01,0.01)';
      OUTPUT_LOAD='(1.0,-1.0)';
      PINUSE='BI';
    'DDR0_SB_DQ5':
      PIN_NUMBER='(0,0,0,0,0,0,0,K28,0,0,0,0,0,0,0,0,0,0,0,0,0,0,0,0,0,0,0,0,0,0~
,0,0,0,0,0,0,0,0,0,0,0,0)';
      BIDIRECTIONAL='TRUE';
      INPUT_LOAD='(-0.01,0.01)';
      OUTPUT_LOAD='(1.0,-1.0)';
      PINUSE='BI';
    'DDR0_SB_DQ4':
      PIN_NUMBER='(0,0,0,0,0,0,0,J29,0,0,0,0,0,0,0,0,0,0,0,0,0,0,0,0,0,0,0,0,0,0~
,0,0,0,0,0,0,0,0,0,0,0,0)';
      BIDIRECTIONAL='TRUE';
      INPUT_LOAD='(-0.01,0.01)';
      OUTPUT_LOAD='(1.0,-1.0)';
      PINUSE='BI';
    'DDR0_SB_DQ3':
      PIN_NUMBER='(0,0,0,0,0,0,0,N31,0,0,0,0,0,0,0,0,0,0,0,0,0,0,0,0,0,0,0,0,0,0~
,0,0,0,0,0,0,0,0,0,0,0,0)';
      BIDIRECTIONAL='TRUE';
      INPUT_LOAD='(-0.01,0.01)';
      OUTPUT_LOAD='(1.0,-1.0)';
      PINUSE='BI';
    'DDR0_SB_DQ2':
      PIN_NUMBER='(0,0,0,0,0,0,0,M32,0,0,0,0,0,0,0,0,0,0,0,0,0,0,0,0,0,0,0,0,0,0~
,0,0,0,0,0,0,0,0,0,0,0,0)';
      BIDIRECTIONAL='TRUE';
      INPUT_LOAD='(-0.01,0.01)';
      OUTPUT_LOAD='(1.0,-1.0)';
      PINUSE='BI';
    'DDR0_SB_DQ1':
      PIN_NUMBER='(0,0,0,0,0,0,0,J31,0,0,0,0,0,0,0,0,0,0,0,0,0,0,0,0,0,0,0,0,0,0~
,0,0,0,0,0,0,0,0,0,0,0,0)';
      BIDIRECTIONAL='TRUE';
      INPUT_LOAD='(-0.01,0.01)';
      OUTPUT_LOAD='(1.0,-1.0)';
      PINUSE='BI';
    'DDR0_SB_DQ0':
      PIN_NUMBER='(0,0,0,0,0,0,0,K32,0,0,0,0,0,0,0,0,0,0,0,0,0,0,0,0,0,0,0,0,0,0~
,0,0,0,0,0,0,0,0,0,0,0,0)';
      BIDIRECTIONAL='TRUE';
      INPUT_LOAD='(-0.01,0.01)';
      OUTPUT_LOAD='(1.0,-1.0)';
      PINUSE='BI';
    'DDR0_SB_DQS_DN9':
      PIN_NUMBER='(0,0,0,0,0,0,0,A33,0,0,0,0,0,0,0,0,0,0,0,0,0,0,0,0,0,0,0,0,0,0~
,0,0,0,0,0,0,0,0,0,0,0,0)';
      BIDIRECTIONAL='TRUE';
      INPUT_LOAD='(-0.01,0.01)';
      OUTPUT_LOAD='(1.0,-1.0)';
      PINUSE='BI';
    'DDR0_SB_DQS_DN8':
      PIN_NUMBER='(0,0,0,0,0,0,0,G9,0,0,0,0,0,0,0,0,0,0,0,0,0,0,0,0,0,0,0,0,0,0,~
0,0,0,0,0,0,0,0,0,0,0,0)';
      BIDIRECTIONAL='TRUE';
      INPUT_LOAD='(-0.01,0.01)';
      OUTPUT_LOAD='(1.0,-1.0)';
      PINUSE='BI';
    'DDR0_SB_DQS_DN7':
      PIN_NUMBER='(0,0,0,0,0,0,0,G21,0,0,0,0,0,0,0,0,0,0,0,0,0,0,0,0,0,0,0,0,0,0~
,0,0,0,0,0,0,0,0,0,0,0,0)';
      BIDIRECTIONAL='TRUE';
      INPUT_LOAD='(-0.01,0.01)';
      OUTPUT_LOAD='(1.0,-1.0)';
      PINUSE='BI';
    'DDR0_SB_DQS_DN6':
      PIN_NUMBER='(0,0,0,0,0,0,0,G27,0,0,0,0,0,0,0,0,0,0,0,0,0,0,0,0,0,0,0,0,0,0~
,0,0,0,0,0,0,0,0,0,0,0,0)';
      BIDIRECTIONAL='TRUE';
      INPUT_LOAD='(-0.01,0.01)';
      OUTPUT_LOAD='(1.0,-1.0)';
      PINUSE='BI';
    'DDR0_SB_DQS_DN5':
      PIN_NUMBER='(0,0,0,0,0,0,0,M30,0,0,0,0,0,0,0,0,0,0,0,0,0,0,0,0,0,0,0,0,0,0~
,0,0,0,0,0,0,0,0,0,0,0,0)';
      BIDIRECTIONAL='TRUE';
      INPUT_LOAD='(-0.01,0.01)';
      OUTPUT_LOAD='(1.0,-1.0)';
      PINUSE='BI';
    'DDR0_SB_DQS_DN4':
      PIN_NUMBER='(0,0,0,0,0,0,0,G33,0,0,0,0,0,0,0,0,0,0,0,0,0,0,0,0,0,0,0,0,0,0~
,0,0,0,0,0,0,0,0,0,0,0,0)';
      BIDIRECTIONAL='TRUE';
      INPUT_LOAD='(-0.01,0.01)';
      OUTPUT_LOAD='(1.0,-1.0)';
      PINUSE='BI';
    'DDR0_SB_DQS_DN3':
      PIN_NUMBER='(0,0,0,0,0,0,0,A9,0,0,0,0,0,0,0,0,0,0,0,0,0,0,0,0,0,0,0,0,0,0,~
0,0,0,0,0,0,0,0,0,0,0,0)';
      BIDIRECTIONAL='TRUE';
      INPUT_LOAD='(-0.01,0.01)';
      OUTPUT_LOAD='(1.0,-1.0)';
      PINUSE='BI';
    'DDR0_SB_DQS_DN2':
      PIN_NUMBER='(0,0,0,0,0,0,0,A21,0,0,0,0,0,0,0,0,0,0,0,0,0,0,0,0,0,0,0,0,0,0~
,0,0,0,0,0,0,0,0,0,0,0,0)';
      BIDIRECTIONAL='TRUE';
      INPUT_LOAD='(-0.01,0.01)';
      OUTPUT_LOAD='(1.0,-1.0)';
      PINUSE='BI';
    'DDR0_SB_DQS_DN1':
      PIN_NUMBER='(0,0,0,0,0,0,0,A27,0,0,0,0,0,0,0,0,0,0,0,0,0,0,0,0,0,0,0,0,0,0~
,0,0,0,0,0,0,0,0,0,0,0,0)';
      BIDIRECTIONAL='TRUE';
      INPUT_LOAD='(-0.01,0.01)';
      OUTPUT_LOAD='(1.0,-1.0)';
      PINUSE='BI';
    'DDR0_SB_DQS_DN0':
      PIN_NUMBER='(0,0,0,0,0,0,0,H30,0,0,0,0,0,0,0,0,0,0,0,0,0,0,0,0,0,0,0,0,0,0~
,0,0,0,0,0,0,0,0,0,0,0,0)';
      BIDIRECTIONAL='TRUE';
      INPUT_LOAD='(-0.01,0.01)';
      OUTPUT_LOAD='(1.0,-1.0)';
      PINUSE='BI';
    'DDR0_SB_DQS_DP9':
      PIN_NUMBER='(0,0,0,0,0,0,0,C33,0,0,0,0,0,0,0,0,0,0,0,0,0,0,0,0,0,0,0,0,0,0~
,0,0,0,0,0,0,0,0,0,0,0,0)';
      BIDIRECTIONAL='TRUE';
      INPUT_LOAD='(-0.01,0.01)';
      OUTPUT_LOAD='(1.0,-1.0)';
      PINUSE='BI';
    'DDR0_SB_DQS_DP8':
      PIN_NUMBER='(0,0,0,0,0,0,0,E9,0,0,0,0,0,0,0,0,0,0,0,0,0,0,0,0,0,0,0,0,0,0,~
0,0,0,0,0,0,0,0,0,0,0,0)';
      BIDIRECTIONAL='TRUE';
      INPUT_LOAD='(-0.01,0.01)';
      OUTPUT_LOAD='(1.0,-1.0)';
      PINUSE='BI';
    'DDR0_SB_DQS_DP7':
      PIN_NUMBER='(0,0,0,0,0,0,0,E21,0,0,0,0,0,0,0,0,0,0,0,0,0,0,0,0,0,0,0,0,0,0~
,0,0,0,0,0,0,0,0,0,0,0,0)';
      BIDIRECTIONAL='TRUE';
      INPUT_LOAD='(-0.01,0.01)';
      OUTPUT_LOAD='(1.0,-1.0)';
      PINUSE='BI';
    'DDR0_SB_DQS_DP6':
      PIN_NUMBER='(0,0,0,0,0,0,0,E27,0,0,0,0,0,0,0,0,0,0,0,0,0,0,0,0,0,0,0,0,0,0~
,0,0,0,0,0,0,0,0,0,0,0,0)';
      BIDIRECTIONAL='TRUE';
      INPUT_LOAD='(-0.01,0.01)';
      OUTPUT_LOAD='(1.0,-1.0)';
      PINUSE='BI';
    'DDR0_SB_DQS_DP5':
      PIN_NUMBER='(0,0,0,0,0,0,0,P30,0,0,0,0,0,0,0,0,0,0,0,0,0,0,0,0,0,0,0,0,0,0~
,0,0,0,0,0,0,0,0,0,0,0,0)';
      BIDIRECTIONAL='TRUE';
      INPUT_LOAD='(-0.01,0.01)';
      OUTPUT_LOAD='(1.0,-1.0)';
      PINUSE='BI';
    'DDR0_SB_DQS_DP4':
      PIN_NUMBER='(0,0,0,0,0,0,0,E33,0,0,0,0,0,0,0,0,0,0,0,0,0,0,0,0,0,0,0,0,0,0~
,0,0,0,0,0,0,0,0,0,0,0,0)';
      BIDIRECTIONAL='TRUE';
      INPUT_LOAD='(-0.01,0.01)';
      OUTPUT_LOAD='(1.0,-1.0)';
      PINUSE='BI';
    'DDR0_SB_DQS_DP3':
      PIN_NUMBER='(0,0,0,0,0,0,0,C9,0,0,0,0,0,0,0,0,0,0,0,0,0,0,0,0,0,0,0,0,0,0,~
0,0,0,0,0,0,0,0,0,0,0,0)';
      BIDIRECTIONAL='TRUE';
      INPUT_LOAD='(-0.01,0.01)';
      OUTPUT_LOAD='(1.0,-1.0)';
      PINUSE='BI';
    'DDR0_SB_DQS_DP2':
      PIN_NUMBER='(0,0,0,0,0,0,0,C21,0,0,0,0,0,0,0,0,0,0,0,0,0,0,0,0,0,0,0,0,0,0~
,0,0,0,0,0,0,0,0,0,0,0,0)';
      BIDIRECTIONAL='TRUE';
      INPUT_LOAD='(-0.01,0.01)';
      OUTPUT_LOAD='(1.0,-1.0)';
      PINUSE='BI';
    'DDR0_SB_DQS_DP1':
      PIN_NUMBER='(0,0,0,0,0,0,0,C27,0,0,0,0,0,0,0,0,0,0,0,0,0,0,0,0,0,0,0,0,0,0~
,0,0,0,0,0,0,0,0,0,0,0,0)';
      BIDIRECTIONAL='TRUE';
      INPUT_LOAD='(-0.01,0.01)';
      OUTPUT_LOAD='(1.0,-1.0)';
      PINUSE='BI';
    'DDR0_SB_DQS_DP0':
      PIN_NUMBER='(0,0,0,0,0,0,0,K30,0,0,0,0,0,0,0,0,0,0,0,0,0,0,0,0,0,0,0,0,0,0~
,0,0,0,0,0,0,0,0,0,0,0,0)';
      BIDIRECTIONAL='TRUE';
      INPUT_LOAD='(-0.01,0.01)';
      OUTPUT_LOAD='(1.0,-1.0)';
      PINUSE='BI';
    'DDR0_SB_ECC7':
      PIN_NUMBER='(0,0,0,0,0,0,0,F34,0,0,0,0,0,0,0,0,0,0,0,0,0,0,0,0,0,0,0,0,0,0~
,0,0,0,0,0,0,0,0,0,0,0,0)';
      BIDIRECTIONAL='TRUE';
      INPUT_LOAD='(-0.01,0.01)';
      OUTPUT_LOAD='(1.0,-1.0)';
      PINUSE='BI';
    'DDR0_SB_ECC6':
      PIN_NUMBER='(0,0,0,0,0,0,0,E35,0,0,0,0,0,0,0,0,0,0,0,0,0,0,0,0,0,0,0,0,0,0~
,0,0,0,0,0,0,0,0,0,0,0,0)';
      BIDIRECTIONAL='TRUE';
      INPUT_LOAD='(-0.01,0.01)';
      OUTPUT_LOAD='(1.0,-1.0)';
      PINUSE='BI';
    'DDR0_SB_ECC5':
      PIN_NUMBER='(0,0,0,0,0,0,0,B34,0,0,0,0,0,0,0,0,0,0,0,0,0,0,0,0,0,0,0,0,0,0~
,0,0,0,0,0,0,0,0,0,0,0,0)';
      BIDIRECTIONAL='TRUE';
      INPUT_LOAD='(-0.01,0.01)';
      OUTPUT_LOAD='(1.0,-1.0)';
      PINUSE='BI';
    'DDR0_SB_ECC4':
      PIN_NUMBER='(0,0,0,0,0,0,0,C35,0,0,0,0,0,0,0,0,0,0,0,0,0,0,0,0,0,0,0,0,0,0~
,0,0,0,0,0,0,0,0,0,0,0,0)';
      BIDIRECTIONAL='TRUE';
      INPUT_LOAD='(-0.01,0.01)';
      OUTPUT_LOAD='(1.0,-1.0)';
      PINUSE='BI';
    'DDR0_SB_ECC3':
      PIN_NUMBER='(0,0,0,0,0,0,0,E31,0,0,0,0,0,0,0,0,0,0,0,0,0,0,0,0,0,0,0,0,0,0~
,0,0,0,0,0,0,0,0,0,0,0,0)';
      BIDIRECTIONAL='TRUE';
      INPUT_LOAD='(-0.01,0.01)';
      OUTPUT_LOAD='(1.0,-1.0)';
      PINUSE='BI';
    'DDR0_SB_ECC2':
      PIN_NUMBER='(0,0,0,0,0,0,0,F32,0,0,0,0,0,0,0,0,0,0,0,0,0,0,0,0,0,0,0,0,0,0~
,0,0,0,0,0,0,0,0,0,0,0,0)';
      BIDIRECTIONAL='TRUE';
      INPUT_LOAD='(-0.01,0.01)';
      OUTPUT_LOAD='(1.0,-1.0)';
      PINUSE='BI';
    'DDR0_SB_ECC1':
      PIN_NUMBER='(0,0,0,0,0,0,0,C31,0,0,0,0,0,0,0,0,0,0,0,0,0,0,0,0,0,0,0,0,0,0~
,0,0,0,0,0,0,0,0,0,0,0,0)';
      BIDIRECTIONAL='TRUE';
      INPUT_LOAD='(-0.01,0.01)';
      OUTPUT_LOAD='(1.0,-1.0)';
      PINUSE='BI';
    'DDR0_SB_ECC0':
      PIN_NUMBER='(0,0,0,0,0,0,0,B32,0,0,0,0,0,0,0,0,0,0,0,0,0,0,0,0,0,0,0,0,0,0~
,0,0,0,0,0,0,0,0,0,0,0,0)';
      BIDIRECTIONAL='TRUE';
      INPUT_LOAD='(-0.01,0.01)';
      OUTPUT_LOAD='(1.0,-1.0)';
      PINUSE='BI';
    'DDR0_SB_PAR':
      PIN_NUMBER='(0,0,0,0,0,0,0,G39,0,0,0,0,0,0,0,0,0,0,0,0,0,0,0,0,0,0,0,0,0,0~
,0,0,0,0,0,0,0,0,0,0,0,0)';
      OUTPUT_LOAD='(1.0,-1.0)';
      PINUSE='OUT';
    'DDR1_ALERT_N':
      PIN_NUMBER='(0,0,0,0,0,0,0,0,AV49,0,0,0,0,0,0,0,0,0,0,0,0,0,0,0,0,0,0,0,0,~
0,0,0,0,0,0,0,0,0,0,0,0,0)';
      INPUT_LOAD='(-0.01,0.01)';
      PINUSE='IN';
    'DDR1_A_RSP1':
      PIN_NUMBER='(0,0,0,0,0,0,0,0,AK47,0,0,0,0,0,0,0,0,0,0,0,0,0,0,0,0,0,0,0,0,~
0,0,0,0,0,0,0,0,0,0,0,0,0)';
      INPUT_LOAD='(-0.01,0.01)';
      PINUSE='IN';
    'DDR1_A_RSP0':
      PIN_NUMBER='(0,0,0,0,0,0,0,0,AL48,0,0,0,0,0,0,0,0,0,0,0,0,0,0,0,0,0,0,0,0,~
0,0,0,0,0,0,0,0,0,0,0,0,0)';
      INPUT_LOAD='(-0.01,0.01)';
      PINUSE='IN';
    'DDR1_B_RSP1':
      PIN_NUMBER='(0,0,0,0,0,0,0,0,AP47,0,0,0,0,0,0,0,0,0,0,0,0,0,0,0,0,0,0,0,0,~
0,0,0,0,0,0,0,0,0,0,0,0,0)';
      INPUT_LOAD='(-0.01,0.01)';
      PINUSE='IN';
    'DDR1_B_RSP0':
      PIN_NUMBER='(0,0,0,0,0,0,0,0,AN48,0,0,0,0,0,0,0,0,0,0,0,0,0,0,0,0,0,0,0,0,~
0,0,0,0,0,0,0,0,0,0,0,0,0)';
      INPUT_LOAD='(-0.01,0.01)';
      PINUSE='IN';
    'DDR1_CLK_DN1':
      PIN_NUMBER='(0,0,0,0,0,0,0,0,W45,0,0,0,0,0,0,0,0,0,0,0,0,0,0,0,0,0,0,0,0,0~
,0,0,0,0,0,0,0,0,0,0,0,0)';
      OUTPUT_LOAD='(1.0,-1.0)';
      PINUSE='OUT';
    'DDR1_CLK_DN0':
      PIN_NUMBER='(0,0,0,0,0,0,0,0,R45,0,0,0,0,0,0,0,0,0,0,0,0,0,0,0,0,0,0,0,0,0~
,0,0,0,0,0,0,0,0,0,0,0,0)';
      OUTPUT_LOAD='(1.0,-1.0)';
      PINUSE='OUT';
    'DDR1_CLK_DP1':
      PIN_NUMBER='(0,0,0,0,0,0,0,0,AA45,0,0,0,0,0,0,0,0,0,0,0,0,0,0,0,0,0,0,0,0,~
0,0,0,0,0,0,0,0,0,0,0,0,0)';
      OUTPUT_LOAD='(1.0,-1.0)';
      PINUSE='OUT';
    'DDR1_CLK_DP0':
      PIN_NUMBER='(0,0,0,0,0,0,0,0,U45,0,0,0,0,0,0,0,0,0,0,0,0,0,0,0,0,0,0,0,0,0~
,0,0,0,0,0,0,0,0,0,0,0,0)';
      OUTPUT_LOAD='(1.0,-1.0)';
      PINUSE='OUT';
    'DDR1_SA_CA6':
      PIN_NUMBER='(0,0,0,0,0,0,0,0,Y44,0,0,0,0,0,0,0,0,0,0,0,0,0,0,0,0,0,0,0,0,0~
,0,0,0,0,0,0,0,0,0,0,0,0)';
      OUTPUT_LOAD='(1.0,-1.0)';
      PINUSE='OUT';
    'DDR1_SA_CA5':
      PIN_NUMBER='(0,0,0,0,0,0,0,0,M47,0,0,0,0,0,0,0,0,0,0,0,0,0,0,0,0,0,0,0,0,0~
,0,0,0,0,0,0,0,0,0,0,0,0)';
      OUTPUT_LOAD='(1.0,-1.0)';
      PINUSE='OUT';
    'DDR1_SA_CA4':
      PIN_NUMBER='(0,0,0,0,0,0,0,0,K47,0,0,0,0,0,0,0,0,0,0,0,0,0,0,0,0,0,0,0,0,0~
,0,0,0,0,0,0,0,0,0,0,0,0)';
      OUTPUT_LOAD='(1.0,-1.0)';
      PINUSE='OUT';
    'DDR1_SA_CA3':
      PIN_NUMBER='(0,0,0,0,0,0,0,0,N48,0,0,0,0,0,0,0,0,0,0,0,0,0,0,0,0,0,0,0,0,0~
,0,0,0,0,0,0,0,0,0,0,0,0)';
      OUTPUT_LOAD='(1.0,-1.0)';
      PINUSE='OUT';
    'DDR1_SA_CA2':
      PIN_NUMBER='(0,0,0,0,0,0,0,0,J48,0,0,0,0,0,0,0,0,0,0,0,0,0,0,0,0,0,0,0,0,0~
,0,0,0,0,0,0,0,0,0,0,0,0)';
      OUTPUT_LOAD='(1.0,-1.0)';
      PINUSE='OUT';
    'DDR1_SA_CA1':
      PIN_NUMBER='(0,0,0,0,0,0,0,0,P49,0,0,0,0,0,0,0,0,0,0,0,0,0,0,0,0,0,0,0,0,0~
,0,0,0,0,0,0,0,0,0,0,0,0)';
      OUTPUT_LOAD='(1.0,-1.0)';
      PINUSE='OUT';
    'DDR1_SA_CA0':
      PIN_NUMBER='(0,0,0,0,0,0,0,0,H49,0,0,0,0,0,0,0,0,0,0,0,0,0,0,0,0,0,0,0,0,0~
,0,0,0,0,0,0,0,0,0,0,0,0)';
      OUTPUT_LOAD='(1.0,-1.0)';
      PINUSE='OUT';
    'DDR1_SA_CS_N3':
      PIN_NUMBER='(0,0,0,0,0,0,0,0,N50,0,0,0,0,0,0,0,0,0,0,0,0,0,0,0,0,0,0,0,0,0~
,0,0,0,0,0,0,0,0,0,0,0,0)';
      OUTPUT_LOAD='(1.0,-1.0)';
      PINUSE='OUT';
    'DDR1_SA_CS_N2':
      PIN_NUMBER='(0,0,0,0,0,0,0,0,M51,0,0,0,0,0,0,0,0,0,0,0,0,0,0,0,0,0,0,0,0,0~
,0,0,0,0,0,0,0,0,0,0,0,0)';
      OUTPUT_LOAD='(1.0,-1.0)';
      PINUSE='OUT';
    'DDR1_SA_CS_N1':
      PIN_NUMBER='(0,0,0,0,0,0,0,0,J50,0,0,0,0,0,0,0,0,0,0,0,0,0,0,0,0,0,0,0,0,0~
,0,0,0,0,0,0,0,0,0,0,0,0)';
      OUTPUT_LOAD='(1.0,-1.0)';
      PINUSE='OUT';
    'DDR1_SA_CS_N0':
      PIN_NUMBER='(0,0,0,0,0,0,0,0,K51,0,0,0,0,0,0,0,0,0,0,0,0,0,0,0,0,0,0,0,0,0~
,0,0,0,0,0,0,0,0,0,0,0,0)';
      OUTPUT_LOAD='(1.0,-1.0)';
      PINUSE='OUT';
    'DDR1_SA_DQ31':
      PIN_NUMBER='(0,0,0,0,0,0,0,0,W56,0,0,0,0,0,0,0,0,0,0,0,0,0,0,0,0,0,0,0,0,0~
,0,0,0,0,0,0,0,0,0,0,0,0)';
      BIDIRECTIONAL='TRUE';
      INPUT_LOAD='(-0.01,0.01)';
      OUTPUT_LOAD='(1.0,-1.0)';
      PINUSE='BI';
    'DDR1_SA_DQ30':
      PIN_NUMBER='(0,0,0,0,0,0,0,0,Y57,0,0,0,0,0,0,0,0,0,0,0,0,0,0,0,0,0,0,0,0,0~
,0,0,0,0,0,0,0,0,0,0,0,0)';
      BIDIRECTIONAL='TRUE';
      INPUT_LOAD='(-0.01,0.01)';
      OUTPUT_LOAD='(1.0,-1.0)';
      PINUSE='BI';
    'DDR1_SA_DQ29':
      PIN_NUMBER='(0,0,0,0,0,0,0,0,U56,0,0,0,0,0,0,0,0,0,0,0,0,0,0,0,0,0,0,0,0,0~
,0,0,0,0,0,0,0,0,0,0,0,0)';
      BIDIRECTIONAL='TRUE';
      INPUT_LOAD='(-0.01,0.01)';
      OUTPUT_LOAD='(1.0,-1.0)';
      PINUSE='BI';
    'DDR1_SA_DQ28':
      PIN_NUMBER='(0,0,0,0,0,0,0,0,T57,0,0,0,0,0,0,0,0,0,0,0,0,0,0,0,0,0,0,0,0,0~
,0,0,0,0,0,0,0,0,0,0,0,0)';
      BIDIRECTIONAL='TRUE';
      INPUT_LOAD='(-0.01,0.01)';
      OUTPUT_LOAD='(1.0,-1.0)';
      PINUSE='BI';
    'DDR1_SA_DQ27':
      PIN_NUMBER='(0,0,0,0,0,0,0,0,Y59,0,0,0,0,0,0,0,0,0,0,0,0,0,0,0,0,0,0,0,0,0~
,0,0,0,0,0,0,0,0,0,0,0,0)';
      BIDIRECTIONAL='TRUE';
      INPUT_LOAD='(-0.01,0.01)';
      OUTPUT_LOAD='(1.0,-1.0)';
      PINUSE='BI';
    'DDR1_SA_DQ26':
      PIN_NUMBER='(0,0,0,0,0,0,0,0,W60,0,0,0,0,0,0,0,0,0,0,0,0,0,0,0,0,0,0,0,0,0~
,0,0,0,0,0,0,0,0,0,0,0,0)';
      BIDIRECTIONAL='TRUE';
      INPUT_LOAD='(-0.01,0.01)';
      OUTPUT_LOAD='(1.0,-1.0)';
      PINUSE='BI';
    'DDR1_SA_DQ25':
      PIN_NUMBER='(0,0,0,0,0,0,0,0,T59,0,0,0,0,0,0,0,0,0,0,0,0,0,0,0,0,0,0,0,0,0~
,0,0,0,0,0,0,0,0,0,0,0,0)';
      BIDIRECTIONAL='TRUE';
      INPUT_LOAD='(-0.01,0.01)';
      OUTPUT_LOAD='(1.0,-1.0)';
      PINUSE='BI';
    'DDR1_SA_DQ24':
      PIN_NUMBER='(0,0,0,0,0,0,0,0,U60,0,0,0,0,0,0,0,0,0,0,0,0,0,0,0,0,0,0,0,0,0~
,0,0,0,0,0,0,0,0,0,0,0,0)';
      BIDIRECTIONAL='TRUE';
      INPUT_LOAD='(-0.01,0.01)';
      OUTPUT_LOAD='(1.0,-1.0)';
      PINUSE='BI';
    'DDR1_SA_DQ23':
      PIN_NUMBER='(0,0,0,0,0,0,0,0,M59,0,0,0,0,0,0,0,0,0,0,0,0,0,0,0,0,0,0,0,0,0~
,0,0,0,0,0,0,0,0,0,0,0,0)';
      BIDIRECTIONAL='TRUE';
      INPUT_LOAD='(-0.01,0.01)';
      OUTPUT_LOAD='(1.0,-1.0)';
      PINUSE='BI';
    'DDR1_SA_DQ22':
      PIN_NUMBER='(0,0,0,0,0,0,0,0,N60,0,0,0,0,0,0,0,0,0,0,0,0,0,0,0,0,0,0,0,0,0~
,0,0,0,0,0,0,0,0,0,0,0,0)';
      BIDIRECTIONAL='TRUE';
      INPUT_LOAD='(-0.01,0.01)';
      OUTPUT_LOAD='(1.0,-1.0)';
      PINUSE='BI';
    'DDR1_SA_DQ21':
      PIN_NUMBER='(0,0,0,0,0,0,0,0,K59,0,0,0,0,0,0,0,0,0,0,0,0,0,0,0,0,0,0,0,0,0~
,0,0,0,0,0,0,0,0,0,0,0,0)';
      BIDIRECTIONAL='TRUE';
      INPUT_LOAD='(-0.01,0.01)';
      OUTPUT_LOAD='(1.0,-1.0)';
      PINUSE='BI';
    'DDR1_SA_DQ20':
      PIN_NUMBER='(0,0,0,0,0,0,0,0,J60,0,0,0,0,0,0,0,0,0,0,0,0,0,0,0,0,0,0,0,0,0~
,0,0,0,0,0,0,0,0,0,0,0,0)';
      BIDIRECTIONAL='TRUE';
      INPUT_LOAD='(-0.01,0.01)';
      OUTPUT_LOAD='(1.0,-1.0)';
      PINUSE='BI';
    'DDR1_SA_DQ19':
      PIN_NUMBER='(0,0,0,0,0,0,0,0,N62,0,0,0,0,0,0,0,0,0,0,0,0,0,0,0,0,0,0,0,0,0~
,0,0,0,0,0,0,0,0,0,0,0,0)';
      BIDIRECTIONAL='TRUE';
      INPUT_LOAD='(-0.01,0.01)';
      OUTPUT_LOAD='(1.0,-1.0)';
      PINUSE='BI';
    'DDR1_SA_DQ18':
      PIN_NUMBER='(0,0,0,0,0,0,0,0,M63,0,0,0,0,0,0,0,0,0,0,0,0,0,0,0,0,0,0,0,0,0~
,0,0,0,0,0,0,0,0,0,0,0,0)';
      BIDIRECTIONAL='TRUE';
      INPUT_LOAD='(-0.01,0.01)';
      OUTPUT_LOAD='(1.0,-1.0)';
      PINUSE='BI';
    'DDR1_SA_DQ17':
      PIN_NUMBER='(0,0,0,0,0,0,0,0,J62,0,0,0,0,0,0,0,0,0,0,0,0,0,0,0,0,0,0,0,0,0~
,0,0,0,0,0,0,0,0,0,0,0,0)';
      BIDIRECTIONAL='TRUE';
      INPUT_LOAD='(-0.01,0.01)';
      OUTPUT_LOAD='(1.0,-1.0)';
      PINUSE='BI';
    'DDR1_SA_DQ16':
      PIN_NUMBER='(0,0,0,0,0,0,0,0,K63,0,0,0,0,0,0,0,0,0,0,0,0,0,0,0,0,0,0,0,0,0~
,0,0,0,0,0,0,0,0,0,0,0,0)';
      BIDIRECTIONAL='TRUE';
      INPUT_LOAD='(-0.01,0.01)';
      OUTPUT_LOAD='(1.0,-1.0)';
      PINUSE='BI';
    'DDR1_SA_DQ15':
      PIN_NUMBER='(0,0,0,0,0,0,0,0,W68,0,0,0,0,0,0,0,0,0,0,0,0,0,0,0,0,0,0,0,0,0~
,0,0,0,0,0,0,0,0,0,0,0,0)';
      BIDIRECTIONAL='TRUE';
      INPUT_LOAD='(-0.01,0.01)';
      OUTPUT_LOAD='(1.0,-1.0)';
      PINUSE='BI';
    'DDR1_SA_DQ14':
      PIN_NUMBER='(0,0,0,0,0,0,0,0,Y69,0,0,0,0,0,0,0,0,0,0,0,0,0,0,0,0,0,0,0,0,0~
,0,0,0,0,0,0,0,0,0,0,0,0)';
      BIDIRECTIONAL='TRUE';
      INPUT_LOAD='(-0.01,0.01)';
      OUTPUT_LOAD='(1.0,-1.0)';
      PINUSE='BI';
    'DDR1_SA_DQ13':
      PIN_NUMBER='(0,0,0,0,0,0,0,0,U68,0,0,0,0,0,0,0,0,0,0,0,0,0,0,0,0,0,0,0,0,0~
,0,0,0,0,0,0,0,0,0,0,0,0)';
      BIDIRECTIONAL='TRUE';
      INPUT_LOAD='(-0.01,0.01)';
      OUTPUT_LOAD='(1.0,-1.0)';
      PINUSE='BI';
    'DDR1_SA_DQ12':
      PIN_NUMBER='(0,0,0,0,0,0,0,0,T69,0,0,0,0,0,0,0,0,0,0,0,0,0,0,0,0,0,0,0,0,0~
,0,0,0,0,0,0,0,0,0,0,0,0)';
      BIDIRECTIONAL='TRUE';
      INPUT_LOAD='(-0.01,0.01)';
      OUTPUT_LOAD='(1.0,-1.0)';
      PINUSE='BI';
    'DDR1_SA_DQ11':
      PIN_NUMBER='(0,0,0,0,0,0,0,0,Y71,0,0,0,0,0,0,0,0,0,0,0,0,0,0,0,0,0,0,0,0,0~
,0,0,0,0,0,0,0,0,0,0,0,0)';
      BIDIRECTIONAL='TRUE';
      INPUT_LOAD='(-0.01,0.01)';
      OUTPUT_LOAD='(1.0,-1.0)';
      PINUSE='BI';
    'DDR1_SA_DQ10':
      PIN_NUMBER='(0,0,0,0,0,0,0,0,W72,0,0,0,0,0,0,0,0,0,0,0,0,0,0,0,0,0,0,0,0,0~
,0,0,0,0,0,0,0,0,0,0,0,0)';
      BIDIRECTIONAL='TRUE';
      INPUT_LOAD='(-0.01,0.01)';
      OUTPUT_LOAD='(1.0,-1.0)';
      PINUSE='BI';
    'DDR1_SA_DQ9':
      PIN_NUMBER='(0,0,0,0,0,0,0,0,T71,0,0,0,0,0,0,0,0,0,0,0,0,0,0,0,0,0,0,0,0,0~
,0,0,0,0,0,0,0,0,0,0,0,0)';
      BIDIRECTIONAL='TRUE';
      INPUT_LOAD='(-0.01,0.01)';
      OUTPUT_LOAD='(1.0,-1.0)';
      PINUSE='BI';
    'DDR1_SA_DQ8':
      PIN_NUMBER='(0,0,0,0,0,0,0,0,U72,0,0,0,0,0,0,0,0,0,0,0,0,0,0,0,0,0,0,0,0,0~
,0,0,0,0,0,0,0,0,0,0,0,0)';
      BIDIRECTIONAL='TRUE';
      INPUT_LOAD='(-0.01,0.01)';
      OUTPUT_LOAD='(1.0,-1.0)';
      PINUSE='BI';
    'DDR1_SA_DQ7':
      PIN_NUMBER='(0,0,0,0,0,0,0,0,M71,0,0,0,0,0,0,0,0,0,0,0,0,0,0,0,0,0,0,0,0,0~
,0,0,0,0,0,0,0,0,0,0,0,0)';
      BIDIRECTIONAL='TRUE';
      INPUT_LOAD='(-0.01,0.01)';
      OUTPUT_LOAD='(1.0,-1.0)';
      PINUSE='BI';
    'DDR1_SA_DQ6':
      PIN_NUMBER='(0,0,0,0,0,0,0,0,N72,0,0,0,0,0,0,0,0,0,0,0,0,0,0,0,0,0,0,0,0,0~
,0,0,0,0,0,0,0,0,0,0,0,0)';
      BIDIRECTIONAL='TRUE';
      INPUT_LOAD='(-0.01,0.01)';
      OUTPUT_LOAD='(1.0,-1.0)';
      PINUSE='BI';
    'DDR1_SA_DQ5':
      PIN_NUMBER='(0,0,0,0,0,0,0,0,K71,0,0,0,0,0,0,0,0,0,0,0,0,0,0,0,0,0,0,0,0,0~
,0,0,0,0,0,0,0,0,0,0,0,0)';
      BIDIRECTIONAL='TRUE';
      INPUT_LOAD='(-0.01,0.01)';
      OUTPUT_LOAD='(1.0,-1.0)';
      PINUSE='BI';
    'DDR1_SA_DQ4':
      PIN_NUMBER='(0,0,0,0,0,0,0,0,J72,0,0,0,0,0,0,0,0,0,0,0,0,0,0,0,0,0,0,0,0,0~
,0,0,0,0,0,0,0,0,0,0,0,0)';
      BIDIRECTIONAL='TRUE';
      INPUT_LOAD='(-0.01,0.01)';
      OUTPUT_LOAD='(1.0,-1.0)';
      PINUSE='BI';
    'DDR1_SA_DQ3':
      PIN_NUMBER='(0,0,0,0,0,0,0,0,N74,0,0,0,0,0,0,0,0,0,0,0,0,0,0,0,0,0,0,0,0,0~
,0,0,0,0,0,0,0,0,0,0,0,0)';
      BIDIRECTIONAL='TRUE';
      INPUT_LOAD='(-0.01,0.01)';
      OUTPUT_LOAD='(1.0,-1.0)';
      PINUSE='BI';
    'DDR1_SA_DQ2':
      PIN_NUMBER='(0,0,0,0,0,0,0,0,M75,0,0,0,0,0,0,0,0,0,0,0,0,0,0,0,0,0,0,0,0,0~
,0,0,0,0,0,0,0,0,0,0,0,0)';
      BIDIRECTIONAL='TRUE';
      INPUT_LOAD='(-0.01,0.01)';
      OUTPUT_LOAD='(1.0,-1.0)';
      PINUSE='BI';
    'DDR1_SA_DQ1':
      PIN_NUMBER='(0,0,0,0,0,0,0,0,J74,0,0,0,0,0,0,0,0,0,0,0,0,0,0,0,0,0,0,0,0,0~
,0,0,0,0,0,0,0,0,0,0,0,0)';
      BIDIRECTIONAL='TRUE';
      INPUT_LOAD='(-0.01,0.01)';
      OUTPUT_LOAD='(1.0,-1.0)';
      PINUSE='BI';
    'DDR1_SA_DQ0':
      PIN_NUMBER='(0,0,0,0,0,0,0,0,K75,0,0,0,0,0,0,0,0,0,0,0,0,0,0,0,0,0,0,0,0,0~
,0,0,0,0,0,0,0,0,0,0,0,0)';
      BIDIRECTIONAL='TRUE';
      INPUT_LOAD='(-0.01,0.01)';
      OUTPUT_LOAD='(1.0,-1.0)';
      PINUSE='BI';
    'DDR1_SA_DQS_DN9':
      PIN_NUMBER='(0,0,0,0,0,0,0,0,M55,0,0,0,0,0,0,0,0,0,0,0,0,0,0,0,0,0,0,0,0,0~
,0,0,0,0,0,0,0,0,0,0,0,0)';
      BIDIRECTIONAL='TRUE';
      INPUT_LOAD='(-0.01,0.01)';
      OUTPUT_LOAD='(1.0,-1.0)';
      PINUSE='BI';
    'DDR1_SA_DQS_DN8':
      PIN_NUMBER='(0,0,0,0,0,0,0,0,AA58,0,0,0,0,0,0,0,0,0,0,0,0,0,0,0,0,0,0,0,0,~
0,0,0,0,0,0,0,0,0,0,0,0,0)';
      BIDIRECTIONAL='TRUE';
      INPUT_LOAD='(-0.01,0.01)';
      OUTPUT_LOAD='(1.0,-1.0)';
      PINUSE='BI';
    'DDR1_SA_DQS_DN7':
      PIN_NUMBER='(0,0,0,0,0,0,0,0,M61,0,0,0,0,0,0,0,0,0,0,0,0,0,0,0,0,0,0,0,0,0~
,0,0,0,0,0,0,0,0,0,0,0,0)';
      BIDIRECTIONAL='TRUE';
      INPUT_LOAD='(-0.01,0.01)';
      OUTPUT_LOAD='(1.0,-1.0)';
      PINUSE='BI';
    'DDR1_SA_DQS_DN6':
      PIN_NUMBER='(0,0,0,0,0,0,0,0,AA70,0,0,0,0,0,0,0,0,0,0,0,0,0,0,0,0,0,0,0,0,~
0,0,0,0,0,0,0,0,0,0,0,0,0)';
      BIDIRECTIONAL='TRUE';
      INPUT_LOAD='(-0.01,0.01)';
      OUTPUT_LOAD='(1.0,-1.0)';
      PINUSE='BI';
    'DDR1_SA_DQS_DN5':
      PIN_NUMBER='(0,0,0,0,0,0,0,0,M73,0,0,0,0,0,0,0,0,0,0,0,0,0,0,0,0,0,0,0,0,0~
,0,0,0,0,0,0,0,0,0,0,0,0)';
      BIDIRECTIONAL='TRUE';
      INPUT_LOAD='(-0.01,0.01)';
      OUTPUT_LOAD='(1.0,-1.0)';
      PINUSE='BI';
    'DDR1_SA_DQS_DN4':
      PIN_NUMBER='(0,0,0,0,0,0,0,0,H55,0,0,0,0,0,0,0,0,0,0,0,0,0,0,0,0,0,0,0,0,0~
,0,0,0,0,0,0,0,0,0,0,0,0)';
      BIDIRECTIONAL='TRUE';
      INPUT_LOAD='(-0.01,0.01)';
      OUTPUT_LOAD='(1.0,-1.0)';
      PINUSE='BI';
    'DDR1_SA_DQS_DN3':
      PIN_NUMBER='(0,0,0,0,0,0,0,0,R58,0,0,0,0,0,0,0,0,0,0,0,0,0,0,0,0,0,0,0,0,0~
,0,0,0,0,0,0,0,0,0,0,0,0)';
      BIDIRECTIONAL='TRUE';
      INPUT_LOAD='(-0.01,0.01)';
      OUTPUT_LOAD='(1.0,-1.0)';
      PINUSE='BI';
    'DDR1_SA_DQS_DN2':
      PIN_NUMBER='(0,0,0,0,0,0,0,0,H61,0,0,0,0,0,0,0,0,0,0,0,0,0,0,0,0,0,0,0,0,0~
,0,0,0,0,0,0,0,0,0,0,0,0)';
      BIDIRECTIONAL='TRUE';
      INPUT_LOAD='(-0.01,0.01)';
      OUTPUT_LOAD='(1.0,-1.0)';
      PINUSE='BI';
    'DDR1_SA_DQS_DN1':
      PIN_NUMBER='(0,0,0,0,0,0,0,0,R70,0,0,0,0,0,0,0,0,0,0,0,0,0,0,0,0,0,0,0,0,0~
,0,0,0,0,0,0,0,0,0,0,0,0)';
      BIDIRECTIONAL='TRUE';
      INPUT_LOAD='(-0.01,0.01)';
      OUTPUT_LOAD='(1.0,-1.0)';
      PINUSE='BI';
    'DDR1_SA_DQS_DN0':
      PIN_NUMBER='(0,0,0,0,0,0,0,0,H73,0,0,0,0,0,0,0,0,0,0,0,0,0,0,0,0,0,0,0,0,0~
,0,0,0,0,0,0,0,0,0,0,0,0)';
      BIDIRECTIONAL='TRUE';
      INPUT_LOAD='(-0.01,0.01)';
      OUTPUT_LOAD='(1.0,-1.0)';
      PINUSE='BI';
    'DDR1_SA_DQS_DP9':
      PIN_NUMBER='(0,0,0,0,0,0,0,0,P55,0,0,0,0,0,0,0,0,0,0,0,0,0,0,0,0,0,0,0,0,0~
,0,0,0,0,0,0,0,0,0,0,0,0)';
      BIDIRECTIONAL='TRUE';
      INPUT_LOAD='(-0.01,0.01)';
      OUTPUT_LOAD='(1.0,-1.0)';
      PINUSE='BI';
    'DDR1_SA_DQS_DP8':
      PIN_NUMBER='(0,0,0,0,0,0,0,0,W58,0,0,0,0,0,0,0,0,0,0,0,0,0,0,0,0,0,0,0,0,0~
,0,0,0,0,0,0,0,0,0,0,0,0)';
      BIDIRECTIONAL='TRUE';
      INPUT_LOAD='(-0.01,0.01)';
      OUTPUT_LOAD='(1.0,-1.0)';
      PINUSE='BI';
    'DDR1_SA_DQS_DP7':
      PIN_NUMBER='(0,0,0,0,0,0,0,0,P61,0,0,0,0,0,0,0,0,0,0,0,0,0,0,0,0,0,0,0,0,0~
,0,0,0,0,0,0,0,0,0,0,0,0)';
      BIDIRECTIONAL='TRUE';
      INPUT_LOAD='(-0.01,0.01)';
      OUTPUT_LOAD='(1.0,-1.0)';
      PINUSE='BI';
    'DDR1_SA_DQS_DP6':
      PIN_NUMBER='(0,0,0,0,0,0,0,0,W70,0,0,0,0,0,0,0,0,0,0,0,0,0,0,0,0,0,0,0,0,0~
,0,0,0,0,0,0,0,0,0,0,0,0)';
      BIDIRECTIONAL='TRUE';
      INPUT_LOAD='(-0.01,0.01)';
      OUTPUT_LOAD='(1.0,-1.0)';
      PINUSE='BI';
    'DDR1_SA_DQS_DP5':
      PIN_NUMBER='(0,0,0,0,0,0,0,0,P73,0,0,0,0,0,0,0,0,0,0,0,0,0,0,0,0,0,0,0,0,0~
,0,0,0,0,0,0,0,0,0,0,0,0)';
      BIDIRECTIONAL='TRUE';
      INPUT_LOAD='(-0.01,0.01)';
      OUTPUT_LOAD='(1.0,-1.0)';
      PINUSE='BI';
    'DDR1_SA_DQS_DP4':
      PIN_NUMBER='(0,0,0,0,0,0,0,0,K55,0,0,0,0,0,0,0,0,0,0,0,0,0,0,0,0,0,0,0,0,0~
,0,0,0,0,0,0,0,0,0,0,0,0)';
      BIDIRECTIONAL='TRUE';
      INPUT_LOAD='(-0.01,0.01)';
      OUTPUT_LOAD='(1.0,-1.0)';
      PINUSE='BI';
    'DDR1_SA_DQS_DP3':
      PIN_NUMBER='(0,0,0,0,0,0,0,0,U58,0,0,0,0,0,0,0,0,0,0,0,0,0,0,0,0,0,0,0,0,0~
,0,0,0,0,0,0,0,0,0,0,0,0)';
      BIDIRECTIONAL='TRUE';
      INPUT_LOAD='(-0.01,0.01)';
      OUTPUT_LOAD='(1.0,-1.0)';
      PINUSE='BI';
    'DDR1_SA_DQS_DP2':
      PIN_NUMBER='(0,0,0,0,0,0,0,0,K61,0,0,0,0,0,0,0,0,0,0,0,0,0,0,0,0,0,0,0,0,0~
,0,0,0,0,0,0,0,0,0,0,0,0)';
      BIDIRECTIONAL='TRUE';
      INPUT_LOAD='(-0.01,0.01)';
      OUTPUT_LOAD='(1.0,-1.0)';
      PINUSE='BI';
    'DDR1_SA_DQS_DP1':
      PIN_NUMBER='(0,0,0,0,0,0,0,0,U70,0,0,0,0,0,0,0,0,0,0,0,0,0,0,0,0,0,0,0,0,0~
,0,0,0,0,0,0,0,0,0,0,0,0)';
      BIDIRECTIONAL='TRUE';
      INPUT_LOAD='(-0.01,0.01)';
      OUTPUT_LOAD='(1.0,-1.0)';
      PINUSE='BI';
    'DDR1_SA_DQS_DP0':
      PIN_NUMBER='(0,0,0,0,0,0,0,0,K73,0,0,0,0,0,0,0,0,0,0,0,0,0,0,0,0,0,0,0,0,0~
,0,0,0,0,0,0,0,0,0,0,0,0)';
      BIDIRECTIONAL='TRUE';
      INPUT_LOAD='(-0.01,0.01)';
      OUTPUT_LOAD='(1.0,-1.0)';
      PINUSE='BI';
    'DDR1_SA_ECC7':
      PIN_NUMBER='(0,0,0,0,0,0,0,0,M53,0,0,0,0,0,0,0,0,0,0,0,0,0,0,0,0,0,0,0,0,0~
,0,0,0,0,0,0,0,0,0,0,0,0)';
      BIDIRECTIONAL='TRUE';
      INPUT_LOAD='(-0.01,0.01)';
      OUTPUT_LOAD='(1.0,-1.0)';
      PINUSE='BI';
    'DDR1_SA_ECC6':
      PIN_NUMBER='(0,0,0,0,0,0,0,0,N54,0,0,0,0,0,0,0,0,0,0,0,0,0,0,0,0,0,0,0,0,0~
,0,0,0,0,0,0,0,0,0,0,0,0)';
      BIDIRECTIONAL='TRUE';
      INPUT_LOAD='(-0.01,0.01)';
      OUTPUT_LOAD='(1.0,-1.0)';
      PINUSE='BI';
    'DDR1_SA_ECC5':
      PIN_NUMBER='(0,0,0,0,0,0,0,0,K53,0,0,0,0,0,0,0,0,0,0,0,0,0,0,0,0,0,0,0,0,0~
,0,0,0,0,0,0,0,0,0,0,0,0)';
      BIDIRECTIONAL='TRUE';
      INPUT_LOAD='(-0.01,0.01)';
      OUTPUT_LOAD='(1.0,-1.0)';
      PINUSE='BI';
    'DDR1_SA_ECC4':
      PIN_NUMBER='(0,0,0,0,0,0,0,0,J54,0,0,0,0,0,0,0,0,0,0,0,0,0,0,0,0,0,0,0,0,0~
,0,0,0,0,0,0,0,0,0,0,0,0)';
      BIDIRECTIONAL='TRUE';
      INPUT_LOAD='(-0.01,0.01)';
      OUTPUT_LOAD='(1.0,-1.0)';
      PINUSE='BI';
    'DDR1_SA_ECC3':
      PIN_NUMBER='(0,0,0,0,0,0,0,0,N56,0,0,0,0,0,0,0,0,0,0,0,0,0,0,0,0,0,0,0,0,0~
,0,0,0,0,0,0,0,0,0,0,0,0)';
      BIDIRECTIONAL='TRUE';
      INPUT_LOAD='(-0.01,0.01)';
      OUTPUT_LOAD='(1.0,-1.0)';
      PINUSE='BI';
    'DDR1_SA_ECC2':
      PIN_NUMBER='(0,0,0,0,0,0,0,0,M57,0,0,0,0,0,0,0,0,0,0,0,0,0,0,0,0,0,0,0,0,0~
,0,0,0,0,0,0,0,0,0,0,0,0)';
      BIDIRECTIONAL='TRUE';
      INPUT_LOAD='(-0.01,0.01)';
      OUTPUT_LOAD='(1.0,-1.0)';
      PINUSE='BI';
    'DDR1_SA_ECC1':
      PIN_NUMBER='(0,0,0,0,0,0,0,0,J56,0,0,0,0,0,0,0,0,0,0,0,0,0,0,0,0,0,0,0,0,0~
,0,0,0,0,0,0,0,0,0,0,0,0)';
      BIDIRECTIONAL='TRUE';
      INPUT_LOAD='(-0.01,0.01)';
      OUTPUT_LOAD='(1.0,-1.0)';
      PINUSE='BI';
    'DDR1_SA_ECC0':
      PIN_NUMBER='(0,0,0,0,0,0,0,0,K57,0,0,0,0,0,0,0,0,0,0,0,0,0,0,0,0,0,0,0,0,0~
,0,0,0,0,0,0,0,0,0,0,0,0)';
      BIDIRECTIONAL='TRUE';
      INPUT_LOAD='(-0.01,0.01)';
      OUTPUT_LOAD='(1.0,-1.0)';
      PINUSE='BI';
    'DDR1_SA_PAR':
      PIN_NUMBER='(0,0,0,0,0,0,0,0,W43,0,0,0,0,0,0,0,0,0,0,0,0,0,0,0,0,0,0,0,0,0~
,0,0,0,0,0,0,0,0,0,0,0,0)';
      OUTPUT_LOAD='(1.0,-1.0)';
      PINUSE='OUT';
    'DDR1_SB_CA6':
      PIN_NUMBER='(0,0,0,0,0,0,0,0,H42,0,0,0,0,0,0,0,0,0,0,0,0,0,0,0,0,0,0,0,0,0~
,0,0,0,0,0,0,0,0,0,0,0,0)';
      OUTPUT_LOAD='(1.0,-1.0)';
      PINUSE='OUT';
    'DDR1_SB_CA5':
      PIN_NUMBER='(0,0,0,0,0,0,0,0,N43,0,0,0,0,0,0,0,0,0,0,0,0,0,0,0,0,0,0,0,0,0~
,0,0,0,0,0,0,0,0,0,0,0,0)';
      OUTPUT_LOAD='(1.0,-1.0)';
      PINUSE='OUT';
    'DDR1_SB_CA4':
      PIN_NUMBER='(0,0,0,0,0,0,0,0,J43,0,0,0,0,0,0,0,0,0,0,0,0,0,0,0,0,0,0,0,0,0~
,0,0,0,0,0,0,0,0,0,0,0,0)';
      OUTPUT_LOAD='(1.0,-1.0)';
      PINUSE='OUT';
    'DDR1_SB_CA3':
      PIN_NUMBER='(0,0,0,0,0,0,0,0,M44,0,0,0,0,0,0,0,0,0,0,0,0,0,0,0,0,0,0,0,0,0~
,0,0,0,0,0,0,0,0,0,0,0,0)';
      OUTPUT_LOAD='(1.0,-1.0)';
      PINUSE='OUT';
    'DDR1_SB_CA2':
      PIN_NUMBER='(0,0,0,0,0,0,0,0,K44,0,0,0,0,0,0,0,0,0,0,0,0,0,0,0,0,0,0,0,0,0~
,0,0,0,0,0,0,0,0,0,0,0,0)';
      OUTPUT_LOAD='(1.0,-1.0)';
      PINUSE='OUT';
    'DDR1_SB_CA1':
      PIN_NUMBER='(0,0,0,0,0,0,0,0,U43,0,0,0,0,0,0,0,0,0,0,0,0,0,0,0,0,0,0,0,0,0~
,0,0,0,0,0,0,0,0,0,0,0,0)';
      OUTPUT_LOAD='(1.0,-1.0)';
      PINUSE='OUT';
    'DDR1_SB_CA0':
      PIN_NUMBER='(0,0,0,0,0,0,0,0,T44,0,0,0,0,0,0,0,0,0,0,0,0,0,0,0,0,0,0,0,0,0~
,0,0,0,0,0,0,0,0,0,0,0,0)';
      OUTPUT_LOAD='(1.0,-1.0)';
      PINUSE='OUT';
    'DDR1_SB_CS_N3':
      PIN_NUMBER='(0,0,0,0,0,0,0,0,M40,0,0,0,0,0,0,0,0,0,0,0,0,0,0,0,0,0,0,0,0,0~
,0,0,0,0,0,0,0,0,0,0,0,0)';
      OUTPUT_LOAD='(1.0,-1.0)';
      PINUSE='OUT';
    'DDR1_SB_CS_N2':
      PIN_NUMBER='(0,0,0,0,0,0,0,0,N41,0,0,0,0,0,0,0,0,0,0,0,0,0,0,0,0,0,0,0,0,0~
,0,0,0,0,0,0,0,0,0,0,0,0)';
      OUTPUT_LOAD='(1.0,-1.0)';
      PINUSE='OUT';
    'DDR1_SB_CS_N1':
      PIN_NUMBER='(0,0,0,0,0,0,0,0,K40,0,0,0,0,0,0,0,0,0,0,0,0,0,0,0,0,0,0,0,0,0~
,0,0,0,0,0,0,0,0,0,0,0,0)';
      OUTPUT_LOAD='(1.0,-1.0)';
      PINUSE='OUT';
    'DDR1_SB_CS_N0':
      PIN_NUMBER='(0,0,0,0,0,0,0,0,J41,0,0,0,0,0,0,0,0,0,0,0,0,0,0,0,0,0,0,0,0,0~
,0,0,0,0,0,0,0,0,0,0,0,0)';
      OUTPUT_LOAD='(1.0,-1.0)';
      PINUSE='OUT';
    'DDR1_SB_DQ31':
      PIN_NUMBER='(0,0,0,0,0,0,0,0,F14,0,0,0,0,0,0,0,0,0,0,0,0,0,0,0,0,0,0,0,0,0~
,0,0,0,0,0,0,0,0,0,0,0,0)';
      BIDIRECTIONAL='TRUE';
      INPUT_LOAD='(-0.01,0.01)';
      OUTPUT_LOAD='(1.0,-1.0)';
      PINUSE='BI';
    'DDR1_SB_DQ30':
      PIN_NUMBER='(0,0,0,0,0,0,0,0,B14,0,0,0,0,0,0,0,0,0,0,0,0,0,0,0,0,0,0,0,0,0~
,0,0,0,0,0,0,0,0,0,0,0,0)';
      BIDIRECTIONAL='TRUE';
      INPUT_LOAD='(-0.01,0.01)';
      OUTPUT_LOAD='(1.0,-1.0)';
      PINUSE='BI';
    'DDR1_SB_DQ29':
      PIN_NUMBER='(0,0,0,0,0,0,0,0,E13,0,0,0,0,0,0,0,0,0,0,0,0,0,0,0,0,0,0,0,0,0~
,0,0,0,0,0,0,0,0,0,0,0,0)';
      BIDIRECTIONAL='TRUE';
      INPUT_LOAD='(-0.01,0.01)';
      OUTPUT_LOAD='(1.0,-1.0)';
      PINUSE='BI';
    'DDR1_SB_DQ28':
      PIN_NUMBER='(0,0,0,0,0,0,0,0,C13,0,0,0,0,0,0,0,0,0,0,0,0,0,0,0,0,0,0,0,0,0~
,0,0,0,0,0,0,0,0,0,0,0,0)';
      BIDIRECTIONAL='TRUE';
      INPUT_LOAD='(-0.01,0.01)';
      OUTPUT_LOAD='(1.0,-1.0)';
      PINUSE='BI';
    'DDR1_SB_DQ27':
      PIN_NUMBER='(0,0,0,0,0,0,0,0,F16,0,0,0,0,0,0,0,0,0,0,0,0,0,0,0,0,0,0,0,0,0~
,0,0,0,0,0,0,0,0,0,0,0,0)';
      BIDIRECTIONAL='TRUE';
      INPUT_LOAD='(-0.01,0.01)';
      OUTPUT_LOAD='(1.0,-1.0)';
      PINUSE='BI';
    'DDR1_SB_DQ26':
      PIN_NUMBER='(0,0,0,0,0,0,0,0,E17,0,0,0,0,0,0,0,0,0,0,0,0,0,0,0,0,0,0,0,0,0~
,0,0,0,0,0,0,0,0,0,0,0,0)';
      BIDIRECTIONAL='TRUE';
      INPUT_LOAD='(-0.01,0.01)';
      OUTPUT_LOAD='(1.0,-1.0)';
      PINUSE='BI';
    'DDR1_SB_DQ25':
      PIN_NUMBER='(0,0,0,0,0,0,0,0,B16,0,0,0,0,0,0,0,0,0,0,0,0,0,0,0,0,0,0,0,0,0~
,0,0,0,0,0,0,0,0,0,0,0,0)';
      BIDIRECTIONAL='TRUE';
      INPUT_LOAD='(-0.01,0.01)';
      OUTPUT_LOAD='(1.0,-1.0)';
      PINUSE='BI';
    'DDR1_SB_DQ24':
      PIN_NUMBER='(0,0,0,0,0,0,0,0,C17,0,0,0,0,0,0,0,0,0,0,0,0,0,0,0,0,0,0,0,0,0~
,0,0,0,0,0,0,0,0,0,0,0,0)';
      BIDIRECTIONAL='TRUE';
      INPUT_LOAD='(-0.01,0.01)';
      OUTPUT_LOAD='(1.0,-1.0)';
      PINUSE='BI';
    'DDR1_SB_DQ23':
      PIN_NUMBER='(0,0,0,0,0,0,0,0,M16,0,0,0,0,0,0,0,0,0,0,0,0,0,0,0,0,0,0,0,0,0~
,0,0,0,0,0,0,0,0,0,0,0,0)';
      BIDIRECTIONAL='TRUE';
      INPUT_LOAD='(-0.01,0.01)';
      OUTPUT_LOAD='(1.0,-1.0)';
      PINUSE='BI';
    'DDR1_SB_DQ22':
      PIN_NUMBER='(0,0,0,0,0,0,0,0,N17,0,0,0,0,0,0,0,0,0,0,0,0,0,0,0,0,0,0,0,0,0~
,0,0,0,0,0,0,0,0,0,0,0,0)';
      BIDIRECTIONAL='TRUE';
      INPUT_LOAD='(-0.01,0.01)';
      OUTPUT_LOAD='(1.0,-1.0)';
      PINUSE='BI';
    'DDR1_SB_DQ21':
      PIN_NUMBER='(0,0,0,0,0,0,0,0,K16,0,0,0,0,0,0,0,0,0,0,0,0,0,0,0,0,0,0,0,0,0~
,0,0,0,0,0,0,0,0,0,0,0,0)';
      BIDIRECTIONAL='TRUE';
      INPUT_LOAD='(-0.01,0.01)';
      OUTPUT_LOAD='(1.0,-1.0)';
      PINUSE='BI';
    'DDR1_SB_DQ20':
      PIN_NUMBER='(0,0,0,0,0,0,0,0,J17,0,0,0,0,0,0,0,0,0,0,0,0,0,0,0,0,0,0,0,0,0~
,0,0,0,0,0,0,0,0,0,0,0,0)';
      BIDIRECTIONAL='TRUE';
      INPUT_LOAD='(-0.01,0.01)';
      OUTPUT_LOAD='(1.0,-1.0)';
      PINUSE='BI';
    'DDR1_SB_DQ19':
      PIN_NUMBER='(0,0,0,0,0,0,0,0,N19,0,0,0,0,0,0,0,0,0,0,0,0,0,0,0,0,0,0,0,0,0~
,0,0,0,0,0,0,0,0,0,0,0,0)';
      BIDIRECTIONAL='TRUE';
      INPUT_LOAD='(-0.01,0.01)';
      OUTPUT_LOAD='(1.0,-1.0)';
      PINUSE='BI';
    'DDR1_SB_DQ18':
      PIN_NUMBER='(0,0,0,0,0,0,0,0,M20,0,0,0,0,0,0,0,0,0,0,0,0,0,0,0,0,0,0,0,0,0~
,0,0,0,0,0,0,0,0,0,0,0,0)';
      BIDIRECTIONAL='TRUE';
      INPUT_LOAD='(-0.01,0.01)';
      OUTPUT_LOAD='(1.0,-1.0)';
      PINUSE='BI';
    'DDR1_SB_DQ17':
      PIN_NUMBER='(0,0,0,0,0,0,0,0,J19,0,0,0,0,0,0,0,0,0,0,0,0,0,0,0,0,0,0,0,0,0~
,0,0,0,0,0,0,0,0,0,0,0,0)';
      BIDIRECTIONAL='TRUE';
      INPUT_LOAD='(-0.01,0.01)';
      OUTPUT_LOAD='(1.0,-1.0)';
      PINUSE='BI';
    'DDR1_SB_DQ16':
      PIN_NUMBER='(0,0,0,0,0,0,0,0,K20,0,0,0,0,0,0,0,0,0,0,0,0,0,0,0,0,0,0,0,0,0~
,0,0,0,0,0,0,0,0,0,0,0,0)';
      BIDIRECTIONAL='TRUE';
      INPUT_LOAD='(-0.01,0.01)';
      OUTPUT_LOAD='(1.0,-1.0)';
      PINUSE='BI';
    'DDR1_SB_DQ15':
      PIN_NUMBER='(0,0,0,0,0,0,0,0,M22,0,0,0,0,0,0,0,0,0,0,0,0,0,0,0,0,0,0,0,0,0~
,0,0,0,0,0,0,0,0,0,0,0,0)';
      BIDIRECTIONAL='TRUE';
      INPUT_LOAD='(-0.01,0.01)';
      OUTPUT_LOAD='(1.0,-1.0)';
      PINUSE='BI';
    'DDR1_SB_DQ14':
      PIN_NUMBER='(0,0,0,0,0,0,0,0,N23,0,0,0,0,0,0,0,0,0,0,0,0,0,0,0,0,0,0,0,0,0~
,0,0,0,0,0,0,0,0,0,0,0,0)';
      BIDIRECTIONAL='TRUE';
      INPUT_LOAD='(-0.01,0.01)';
      OUTPUT_LOAD='(1.0,-1.0)';
      PINUSE='BI';
    'DDR1_SB_DQ13':
      PIN_NUMBER='(0,0,0,0,0,0,0,0,K22,0,0,0,0,0,0,0,0,0,0,0,0,0,0,0,0,0,0,0,0,0~
,0,0,0,0,0,0,0,0,0,0,0,0)';
      BIDIRECTIONAL='TRUE';
      INPUT_LOAD='(-0.01,0.01)';
      OUTPUT_LOAD='(1.0,-1.0)';
      PINUSE='BI';
    'DDR1_SB_DQ12':
      PIN_NUMBER='(0,0,0,0,0,0,0,0,J23,0,0,0,0,0,0,0,0,0,0,0,0,0,0,0,0,0,0,0,0,0~
,0,0,0,0,0,0,0,0,0,0,0,0)';
      BIDIRECTIONAL='TRUE';
      INPUT_LOAD='(-0.01,0.01)';
      OUTPUT_LOAD='(1.0,-1.0)';
      PINUSE='BI';
    'DDR1_SB_DQ11':
      PIN_NUMBER='(0,0,0,0,0,0,0,0,N25,0,0,0,0,0,0,0,0,0,0,0,0,0,0,0,0,0,0,0,0,0~
,0,0,0,0,0,0,0,0,0,0,0,0)';
      BIDIRECTIONAL='TRUE';
      INPUT_LOAD='(-0.01,0.01)';
      OUTPUT_LOAD='(1.0,-1.0)';
      PINUSE='BI';
    'DDR1_SB_DQ10':
      PIN_NUMBER='(0,0,0,0,0,0,0,0,M26,0,0,0,0,0,0,0,0,0,0,0,0,0,0,0,0,0,0,0,0,0~
,0,0,0,0,0,0,0,0,0,0,0,0)';
      BIDIRECTIONAL='TRUE';
      INPUT_LOAD='(-0.01,0.01)';
      OUTPUT_LOAD='(1.0,-1.0)';
      PINUSE='BI';
    'DDR1_SB_DQ9':
      PIN_NUMBER='(0,0,0,0,0,0,0,0,J25,0,0,0,0,0,0,0,0,0,0,0,0,0,0,0,0,0,0,0,0,0~
,0,0,0,0,0,0,0,0,0,0,0,0)';
      BIDIRECTIONAL='TRUE';
      INPUT_LOAD='(-0.01,0.01)';
      OUTPUT_LOAD='(1.0,-1.0)';
      PINUSE='BI';
    'DDR1_SB_DQ8':
      PIN_NUMBER='(0,0,0,0,0,0,0,0,K26,0,0,0,0,0,0,0,0,0,0,0,0,0,0,0,0,0,0,0,0,0~
,0,0,0,0,0,0,0,0,0,0,0,0)';
      BIDIRECTIONAL='TRUE';
      INPUT_LOAD='(-0.01,0.01)';
      OUTPUT_LOAD='(1.0,-1.0)';
      PINUSE='BI';
    'DDR1_SB_DQ7':
      PIN_NUMBER='(0,0,0,0,0,0,0,0,W25,0,0,0,0,0,0,0,0,0,0,0,0,0,0,0,0,0,0,0,0,0~
,0,0,0,0,0,0,0,0,0,0,0,0)';
      BIDIRECTIONAL='TRUE';
      INPUT_LOAD='(-0.01,0.01)';
      OUTPUT_LOAD='(1.0,-1.0)';
      PINUSE='BI';
    'DDR1_SB_DQ6':
      PIN_NUMBER='(0,0,0,0,0,0,0,0,Y26,0,0,0,0,0,0,0,0,0,0,0,0,0,0,0,0,0,0,0,0,0~
,0,0,0,0,0,0,0,0,0,0,0,0)';
      BIDIRECTIONAL='TRUE';
      INPUT_LOAD='(-0.01,0.01)';
      OUTPUT_LOAD='(1.0,-1.0)';
      PINUSE='BI';
    'DDR1_SB_DQ5':
      PIN_NUMBER='(0,0,0,0,0,0,0,0,U25,0,0,0,0,0,0,0,0,0,0,0,0,0,0,0,0,0,0,0,0,0~
,0,0,0,0,0,0,0,0,0,0,0,0)';
      BIDIRECTIONAL='TRUE';
      INPUT_LOAD='(-0.01,0.01)';
      OUTPUT_LOAD='(1.0,-1.0)';
      PINUSE='BI';
    'DDR1_SB_DQ4':
      PIN_NUMBER='(0,0,0,0,0,0,0,0,T26,0,0,0,0,0,0,0,0,0,0,0,0,0,0,0,0,0,0,0,0,0~
,0,0,0,0,0,0,0,0,0,0,0,0)';
      BIDIRECTIONAL='TRUE';
      INPUT_LOAD='(-0.01,0.01)';
      OUTPUT_LOAD='(1.0,-1.0)';
      PINUSE='BI';
    'DDR1_SB_DQ3':
      PIN_NUMBER='(0,0,0,0,0,0,0,0,Y28,0,0,0,0,0,0,0,0,0,0,0,0,0,0,0,0,0,0,0,0,0~
,0,0,0,0,0,0,0,0,0,0,0,0)';
      BIDIRECTIONAL='TRUE';
      INPUT_LOAD='(-0.01,0.01)';
      OUTPUT_LOAD='(1.0,-1.0)';
      PINUSE='BI';
    'DDR1_SB_DQ2':
      PIN_NUMBER='(0,0,0,0,0,0,0,0,W29,0,0,0,0,0,0,0,0,0,0,0,0,0,0,0,0,0,0,0,0,0~
,0,0,0,0,0,0,0,0,0,0,0,0)';
      BIDIRECTIONAL='TRUE';
      INPUT_LOAD='(-0.01,0.01)';
      OUTPUT_LOAD='(1.0,-1.0)';
      PINUSE='BI';
    'DDR1_SB_DQ1':
      PIN_NUMBER='(0,0,0,0,0,0,0,0,T28,0,0,0,0,0,0,0,0,0,0,0,0,0,0,0,0,0,0,0,0,0~
,0,0,0,0,0,0,0,0,0,0,0,0)';
      BIDIRECTIONAL='TRUE';
      INPUT_LOAD='(-0.01,0.01)';
      OUTPUT_LOAD='(1.0,-1.0)';
      PINUSE='BI';
    'DDR1_SB_DQ0':
      PIN_NUMBER='(0,0,0,0,0,0,0,0,U29,0,0,0,0,0,0,0,0,0,0,0,0,0,0,0,0,0,0,0,0,0~
,0,0,0,0,0,0,0,0,0,0,0,0)';
      BIDIRECTIONAL='TRUE';
      INPUT_LOAD='(-0.01,0.01)';
      OUTPUT_LOAD='(1.0,-1.0)';
      PINUSE='BI';
    'DDR1_SB_DQS_DN9':
      PIN_NUMBER='(0,0,0,0,0,0,0,0,K36,0,0,0,0,0,0,0,0,0,0,0,0,0,0,0,0,0,0,0,0,0~
,0,0,0,0,0,0,0,0,0,0,0,0)';
      BIDIRECTIONAL='TRUE';
      INPUT_LOAD='(-0.01,0.01)';
      OUTPUT_LOAD='(1.0,-1.0)';
      PINUSE='BI';
    'DDR1_SB_DQS_DN8':
      PIN_NUMBER='(0,0,0,0,0,0,0,0,E15,0,0,0,0,0,0,0,0,0,0,0,0,0,0,0,0,0,0,0,0,0~
,0,0,0,0,0,0,0,0,0,0,0,0)';
      BIDIRECTIONAL='TRUE';
      INPUT_LOAD='(-0.01,0.01)';
      OUTPUT_LOAD='(1.0,-1.0)';
      PINUSE='BI';
    'DDR1_SB_DQS_DN7':
      PIN_NUMBER='(0,0,0,0,0,0,0,0,M18,0,0,0,0,0,0,0,0,0,0,0,0,0,0,0,0,0,0,0,0,0~
,0,0,0,0,0,0,0,0,0,0,0,0)';
      BIDIRECTIONAL='TRUE';
      INPUT_LOAD='(-0.01,0.01)';
      OUTPUT_LOAD='(1.0,-1.0)';
      PINUSE='BI';
    'DDR1_SB_DQS_DN6':
      PIN_NUMBER='(0,0,0,0,0,0,0,0,M24,0,0,0,0,0,0,0,0,0,0,0,0,0,0,0,0,0,0,0,0,0~
,0,0,0,0,0,0,0,0,0,0,0,0)';
      BIDIRECTIONAL='TRUE';
      INPUT_LOAD='(-0.01,0.01)';
      OUTPUT_LOAD='(1.0,-1.0)';
      PINUSE='BI';
    'DDR1_SB_DQS_DN5':
      PIN_NUMBER='(0,0,0,0,0,0,0,0,W27,0,0,0,0,0,0,0,0,0,0,0,0,0,0,0,0,0,0,0,0,0~
,0,0,0,0,0,0,0,0,0,0,0,0)';
      BIDIRECTIONAL='TRUE';
      INPUT_LOAD='(-0.01,0.01)';
      OUTPUT_LOAD='(1.0,-1.0)';
      PINUSE='BI';
    'DDR1_SB_DQS_DN4':
      PIN_NUMBER='(0,0,0,0,0,0,0,0,P36,0,0,0,0,0,0,0,0,0,0,0,0,0,0,0,0,0,0,0,0,0~
,0,0,0,0,0,0,0,0,0,0,0,0)';
      BIDIRECTIONAL='TRUE';
      INPUT_LOAD='(-0.01,0.01)';
      OUTPUT_LOAD='(1.0,-1.0)';
      PINUSE='BI';
    'DDR1_SB_DQS_DN3':
      PIN_NUMBER='(0,0,0,0,0,0,0,0,A15,0,0,0,0,0,0,0,0,0,0,0,0,0,0,0,0,0,0,0,0,0~
,0,0,0,0,0,0,0,0,0,0,0,0)';
      BIDIRECTIONAL='TRUE';
      INPUT_LOAD='(-0.01,0.01)';
      OUTPUT_LOAD='(1.0,-1.0)';
      PINUSE='BI';
    'DDR1_SB_DQS_DN2':
      PIN_NUMBER='(0,0,0,0,0,0,0,0,H18,0,0,0,0,0,0,0,0,0,0,0,0,0,0,0,0,0,0,0,0,0~
,0,0,0,0,0,0,0,0,0,0,0,0)';
      BIDIRECTIONAL='TRUE';
      INPUT_LOAD='(-0.01,0.01)';
      OUTPUT_LOAD='(1.0,-1.0)';
      PINUSE='BI';
    'DDR1_SB_DQS_DN1':
      PIN_NUMBER='(0,0,0,0,0,0,0,0,H24,0,0,0,0,0,0,0,0,0,0,0,0,0,0,0,0,0,0,0,0,0~
,0,0,0,0,0,0,0,0,0,0,0,0)';
      BIDIRECTIONAL='TRUE';
      INPUT_LOAD='(-0.01,0.01)';
      OUTPUT_LOAD='(1.0,-1.0)';
      PINUSE='BI';
    'DDR1_SB_DQS_DN0':
      PIN_NUMBER='(0,0,0,0,0,0,0,0,R27,0,0,0,0,0,0,0,0,0,0,0,0,0,0,0,0,0,0,0,0,0~
,0,0,0,0,0,0,0,0,0,0,0,0)';
      BIDIRECTIONAL='TRUE';
      INPUT_LOAD='(-0.01,0.01)';
      OUTPUT_LOAD='(1.0,-1.0)';
      PINUSE='BI';
    'DDR1_SB_DQS_DP9':
      PIN_NUMBER='(0,0,0,0,0,0,0,0,H36,0,0,0,0,0,0,0,0,0,0,0,0,0,0,0,0,0,0,0,0,0~
,0,0,0,0,0,0,0,0,0,0,0,0)';
      BIDIRECTIONAL='TRUE';
      INPUT_LOAD='(-0.01,0.01)';
      OUTPUT_LOAD='(1.0,-1.0)';
      PINUSE='BI';
    'DDR1_SB_DQS_DP8':
      PIN_NUMBER='(0,0,0,0,0,0,0,0,G15,0,0,0,0,0,0,0,0,0,0,0,0,0,0,0,0,0,0,0,0,0~
,0,0,0,0,0,0,0,0,0,0,0,0)';
      BIDIRECTIONAL='TRUE';
      INPUT_LOAD='(-0.01,0.01)';
      OUTPUT_LOAD='(1.0,-1.0)';
      PINUSE='BI';
    'DDR1_SB_DQS_DP7':
      PIN_NUMBER='(0,0,0,0,0,0,0,0,P18,0,0,0,0,0,0,0,0,0,0,0,0,0,0,0,0,0,0,0,0,0~
,0,0,0,0,0,0,0,0,0,0,0,0)';
      BIDIRECTIONAL='TRUE';
      INPUT_LOAD='(-0.01,0.01)';
      OUTPUT_LOAD='(1.0,-1.0)';
      PINUSE='BI';
    'DDR1_SB_DQS_DP6':
      PIN_NUMBER='(0,0,0,0,0,0,0,0,P24,0,0,0,0,0,0,0,0,0,0,0,0,0,0,0,0,0,0,0,0,0~
,0,0,0,0,0,0,0,0,0,0,0,0)';
      BIDIRECTIONAL='TRUE';
      INPUT_LOAD='(-0.01,0.01)';
      OUTPUT_LOAD='(1.0,-1.0)';
      PINUSE='BI';
    'DDR1_SB_DQS_DP5':
      PIN_NUMBER='(0,0,0,0,0,0,0,0,AA27,0,0,0,0,0,0,0,0,0,0,0,0,0,0,0,0,0,0,0,0,~
0,0,0,0,0,0,0,0,0,0,0,0,0)';
      BIDIRECTIONAL='TRUE';
      INPUT_LOAD='(-0.01,0.01)';
      OUTPUT_LOAD='(1.0,-1.0)';
      PINUSE='BI';
    'DDR1_SB_DQS_DP4':
      PIN_NUMBER='(0,0,0,0,0,0,0,0,M36,0,0,0,0,0,0,0,0,0,0,0,0,0,0,0,0,0,0,0,0,0~
,0,0,0,0,0,0,0,0,0,0,0,0)';
      BIDIRECTIONAL='TRUE';
      INPUT_LOAD='(-0.01,0.01)';
      OUTPUT_LOAD='(1.0,-1.0)';
      PINUSE='BI';
    'DDR1_SB_DQS_DP3':
      PIN_NUMBER='(0,0,0,0,0,0,0,0,C15,0,0,0,0,0,0,0,0,0,0,0,0,0,0,0,0,0,0,0,0,0~
,0,0,0,0,0,0,0,0,0,0,0,0)';
      BIDIRECTIONAL='TRUE';
      INPUT_LOAD='(-0.01,0.01)';
      OUTPUT_LOAD='(1.0,-1.0)';
      PINUSE='BI';
    'DDR1_SB_DQS_DP2':
      PIN_NUMBER='(0,0,0,0,0,0,0,0,K18,0,0,0,0,0,0,0,0,0,0,0,0,0,0,0,0,0,0,0,0,0~
,0,0,0,0,0,0,0,0,0,0,0,0)';
      BIDIRECTIONAL='TRUE';
      INPUT_LOAD='(-0.01,0.01)';
      OUTPUT_LOAD='(1.0,-1.0)';
      PINUSE='BI';
    'DDR1_SB_DQS_DP1':
      PIN_NUMBER='(0,0,0,0,0,0,0,0,K24,0,0,0,0,0,0,0,0,0,0,0,0,0,0,0,0,0,0,0,0,0~
,0,0,0,0,0,0,0,0,0,0,0,0)';
      BIDIRECTIONAL='TRUE';
      INPUT_LOAD='(-0.01,0.01)';
      OUTPUT_LOAD='(1.0,-1.0)';
      PINUSE='BI';
    'DDR1_SB_DQS_DP0':
      PIN_NUMBER='(0,0,0,0,0,0,0,0,U27,0,0,0,0,0,0,0,0,0,0,0,0,0,0,0,0,0,0,0,0,0~
,0,0,0,0,0,0,0,0,0,0,0,0)';
      BIDIRECTIONAL='TRUE';
      INPUT_LOAD='(-0.01,0.01)';
      OUTPUT_LOAD='(1.0,-1.0)';
      PINUSE='BI';
    'DDR1_SB_ECC7':
      PIN_NUMBER='(0,0,0,0,0,0,0,0,N37,0,0,0,0,0,0,0,0,0,0,0,0,0,0,0,0,0,0,0,0,0~
,0,0,0,0,0,0,0,0,0,0,0,0)';
      BIDIRECTIONAL='TRUE';
      INPUT_LOAD='(-0.01,0.01)';
      OUTPUT_LOAD='(1.0,-1.0)';
      PINUSE='BI';
    'DDR1_SB_ECC6':
      PIN_NUMBER='(0,0,0,0,0,0,0,0,M38,0,0,0,0,0,0,0,0,0,0,0,0,0,0,0,0,0,0,0,0,0~
,0,0,0,0,0,0,0,0,0,0,0,0)';
      BIDIRECTIONAL='TRUE';
      INPUT_LOAD='(-0.01,0.01)';
      OUTPUT_LOAD='(1.0,-1.0)';
      PINUSE='BI';
    'DDR1_SB_ECC5':
      PIN_NUMBER='(0,0,0,0,0,0,0,0,J37,0,0,0,0,0,0,0,0,0,0,0,0,0,0,0,0,0,0,0,0,0~
,0,0,0,0,0,0,0,0,0,0,0,0)';
      BIDIRECTIONAL='TRUE';
      INPUT_LOAD='(-0.01,0.01)';
      OUTPUT_LOAD='(1.0,-1.0)';
      PINUSE='BI';
    'DDR1_SB_ECC4':
      PIN_NUMBER='(0,0,0,0,0,0,0,0,K38,0,0,0,0,0,0,0,0,0,0,0,0,0,0,0,0,0,0,0,0,0~
,0,0,0,0,0,0,0,0,0,0,0,0)';
      BIDIRECTIONAL='TRUE';
      INPUT_LOAD='(-0.01,0.01)';
      OUTPUT_LOAD='(1.0,-1.0)';
      PINUSE='BI';
    'DDR1_SB_ECC3':
      PIN_NUMBER='(0,0,0,0,0,0,0,0,M34,0,0,0,0,0,0,0,0,0,0,0,0,0,0,0,0,0,0,0,0,0~
,0,0,0,0,0,0,0,0,0,0,0,0)';
      BIDIRECTIONAL='TRUE';
      INPUT_LOAD='(-0.01,0.01)';
      OUTPUT_LOAD='(1.0,-1.0)';
      PINUSE='BI';
    'DDR1_SB_ECC2':
      PIN_NUMBER='(0,0,0,0,0,0,0,0,N35,0,0,0,0,0,0,0,0,0,0,0,0,0,0,0,0,0,0,0,0,0~
,0,0,0,0,0,0,0,0,0,0,0,0)';
      BIDIRECTIONAL='TRUE';
      INPUT_LOAD='(-0.01,0.01)';
      OUTPUT_LOAD='(1.0,-1.0)';
      PINUSE='BI';
    'DDR1_SB_ECC1':
      PIN_NUMBER='(0,0,0,0,0,0,0,0,K34,0,0,0,0,0,0,0,0,0,0,0,0,0,0,0,0,0,0,0,0,0~
,0,0,0,0,0,0,0,0,0,0,0,0)';
      BIDIRECTIONAL='TRUE';
      INPUT_LOAD='(-0.01,0.01)';
      OUTPUT_LOAD='(1.0,-1.0)';
      PINUSE='BI';
    'DDR1_SB_ECC0':
      PIN_NUMBER='(0,0,0,0,0,0,0,0,J35,0,0,0,0,0,0,0,0,0,0,0,0,0,0,0,0,0,0,0,0,0~
,0,0,0,0,0,0,0,0,0,0,0,0)';
      BIDIRECTIONAL='TRUE';
      INPUT_LOAD='(-0.01,0.01)';
      OUTPUT_LOAD='(1.0,-1.0)';
      PINUSE='BI';
    'DDR1_SB_PAR':
      PIN_NUMBER='(0,0,0,0,0,0,0,0,P42,0,0,0,0,0,0,0,0,0,0,0,0,0,0,0,0,0,0,0,0,0~
,0,0,0,0,0,0,0,0,0,0,0,0)';
      OUTPUT_LOAD='(1.0,-1.0)';
      PINUSE='OUT';
    'DDR2_ALERT_N':
      PIN_NUMBER='(0,0,0,0,0,0,0,0,0,AT47,0,0,0,0,0,0,0,0,0,0,0,0,0,0,0,0,0,0,0,~
0,0,0,0,0,0,0,0,0,0,0,0,0)';
      INPUT_LOAD='(-0.01,0.01)';
      PINUSE='IN';
    'DDR2_A_RSP1':
      PIN_NUMBER='(0,0,0,0,0,0,0,0,0,AD47,0,0,0,0,0,0,0,0,0,0,0,0,0,0,0,0,0,0,0,~
0,0,0,0,0,0,0,0,0,0,0,0,0)';
      INPUT_LOAD='(-0.01,0.01)';
      PINUSE='IN';
    'DDR2_A_RSP0':
      PIN_NUMBER='(0,0,0,0,0,0,0,0,0,AC48,0,0,0,0,0,0,0,0,0,0,0,0,0,0,0,0,0,0,0,~
0,0,0,0,0,0,0,0,0,0,0,0,0)';
      INPUT_LOAD='(-0.01,0.01)';
      PINUSE='IN';
    'DDR2_B_RSP1':
      PIN_NUMBER='(0,0,0,0,0,0,0,0,0,AF47,0,0,0,0,0,0,0,0,0,0,0,0,0,0,0,0,0,0,0,~
0,0,0,0,0,0,0,0,0,0,0,0,0)';
      INPUT_LOAD='(-0.01,0.01)';
      PINUSE='IN';
    'DDR2_B_RSP0':
      PIN_NUMBER='(0,0,0,0,0,0,0,0,0,AG48,0,0,0,0,0,0,0,0,0,0,0,0,0,0,0,0,0,0,0,~
0,0,0,0,0,0,0,0,0,0,0,0,0)';
      INPUT_LOAD='(-0.01,0.01)';
      PINUSE='IN';
    'DDR2_CLK_DN1':
      PIN_NUMBER='(0,0,0,0,0,0,0,0,0,AF49,0,0,0,0,0,0,0,0,0,0,0,0,0,0,0,0,0,0,0,~
0,0,0,0,0,0,0,0,0,0,0,0,0)';
      OUTPUT_LOAD='(1.0,-1.0)';
      PINUSE='OUT';
    'DDR2_CLK_DN0':
      PIN_NUMBER='(0,0,0,0,0,0,0,0,0,AB49,0,0,0,0,0,0,0,0,0,0,0,0,0,0,0,0,0,0,0,~
0,0,0,0,0,0,0,0,0,0,0,0,0)';
      OUTPUT_LOAD='(1.0,-1.0)';
      PINUSE='OUT';
    'DDR2_CLK_DP1':
      PIN_NUMBER='(0,0,0,0,0,0,0,0,0,AH49,0,0,0,0,0,0,0,0,0,0,0,0,0,0,0,0,0,0,0,~
0,0,0,0,0,0,0,0,0,0,0,0,0)';
      OUTPUT_LOAD='(1.0,-1.0)';
      PINUSE='OUT';
    'DDR2_CLK_DP0':
      PIN_NUMBER='(0,0,0,0,0,0,0,0,0,AD49,0,0,0,0,0,0,0,0,0,0,0,0,0,0,0,0,0,0,0,~
0,0,0,0,0,0,0,0,0,0,0,0,0)';
      OUTPUT_LOAD='(1.0,-1.0)';
      PINUSE='OUT';
    'DDR2_SA_CA6':
      PIN_NUMBER='(0,0,0,0,0,0,0,0,0,U48,0,0,0,0,0,0,0,0,0,0,0,0,0,0,0,0,0,0,0,0~
,0,0,0,0,0,0,0,0,0,0,0,0)';
      OUTPUT_LOAD='(1.0,-1.0)';
      PINUSE='OUT';
    'DDR2_SA_CA5':
      PIN_NUMBER='(0,0,0,0,0,0,0,0,0,W50,0,0,0,0,0,0,0,0,0,0,0,0,0,0,0,0,0,0,0,0~
,0,0,0,0,0,0,0,0,0,0,0,0)';
      OUTPUT_LOAD='(1.0,-1.0)';
      PINUSE='OUT';
    'DDR2_SA_CA4':
      PIN_NUMBER='(0,0,0,0,0,0,0,0,0,U50,0,0,0,0,0,0,0,0,0,0,0,0,0,0,0,0,0,0,0,0~
,0,0,0,0,0,0,0,0,0,0,0,0)';
      OUTPUT_LOAD='(1.0,-1.0)';
      PINUSE='OUT';
    'DDR2_SA_CA3':
      PIN_NUMBER='(0,0,0,0,0,0,0,0,0,Y51,0,0,0,0,0,0,0,0,0,0,0,0,0,0,0,0,0,0,0,0~
,0,0,0,0,0,0,0,0,0,0,0,0)';
      OUTPUT_LOAD='(1.0,-1.0)';
      PINUSE='OUT';
    'DDR2_SA_CA2':
      PIN_NUMBER='(0,0,0,0,0,0,0,0,0,T51,0,0,0,0,0,0,0,0,0,0,0,0,0,0,0,0,0,0,0,0~
,0,0,0,0,0,0,0,0,0,0,0,0)';
      OUTPUT_LOAD='(1.0,-1.0)';
      PINUSE='OUT';
    'DDR2_SA_CA1':
      PIN_NUMBER='(0,0,0,0,0,0,0,0,0,AA52,0,0,0,0,0,0,0,0,0,0,0,0,0,0,0,0,0,0,0,~
0,0,0,0,0,0,0,0,0,0,0,0,0)';
      OUTPUT_LOAD='(1.0,-1.0)';
      PINUSE='OUT';
    'DDR2_SA_CA0':
      PIN_NUMBER='(0,0,0,0,0,0,0,0,0,R52,0,0,0,0,0,0,0,0,0,0,0,0,0,0,0,0,0,0,0,0~
,0,0,0,0,0,0,0,0,0,0,0,0)';
      OUTPUT_LOAD='(1.0,-1.0)';
      PINUSE='OUT';
    'DDR2_SA_CS_N3':
      PIN_NUMBER='(0,0,0,0,0,0,0,0,0,Y53,0,0,0,0,0,0,0,0,0,0,0,0,0,0,0,0,0,0,0,0~
,0,0,0,0,0,0,0,0,0,0,0,0)';
      OUTPUT_LOAD='(1.0,-1.0)';
      PINUSE='OUT';
    'DDR2_SA_CS_N2':
      PIN_NUMBER='(0,0,0,0,0,0,0,0,0,W54,0,0,0,0,0,0,0,0,0,0,0,0,0,0,0,0,0,0,0,0~
,0,0,0,0,0,0,0,0,0,0,0,0)';
      OUTPUT_LOAD='(1.0,-1.0)';
      PINUSE='OUT';
    'DDR2_SA_CS_N1':
      PIN_NUMBER='(0,0,0,0,0,0,0,0,0,T53,0,0,0,0,0,0,0,0,0,0,0,0,0,0,0,0,0,0,0,0~
,0,0,0,0,0,0,0,0,0,0,0,0)';
      OUTPUT_LOAD='(1.0,-1.0)';
      PINUSE='OUT';
    'DDR2_SA_CS_N0':
      PIN_NUMBER='(0,0,0,0,0,0,0,0,0,U54,0,0,0,0,0,0,0,0,0,0,0,0,0,0,0,0,0,0,0,0~
,0,0,0,0,0,0,0,0,0,0,0,0)';
      OUTPUT_LOAD='(1.0,-1.0)';
      PINUSE='OUT';
    'DDR2_SA_DQ31':
      PIN_NUMBER='(0,0,0,0,0,0,0,0,0,AF59,0,0,0,0,0,0,0,0,0,0,0,0,0,0,0,0,0,0,0,~
0,0,0,0,0,0,0,0,0,0,0,0,0)';
      BIDIRECTIONAL='TRUE';
      INPUT_LOAD='(-0.01,0.01)';
      OUTPUT_LOAD='(1.0,-1.0)';
      PINUSE='BI';
    'DDR2_SA_DQ30':
      PIN_NUMBER='(0,0,0,0,0,0,0,0,0,AG60,0,0,0,0,0,0,0,0,0,0,0,0,0,0,0,0,0,0,0,~
0,0,0,0,0,0,0,0,0,0,0,0,0)';
      BIDIRECTIONAL='TRUE';
      INPUT_LOAD='(-0.01,0.01)';
      OUTPUT_LOAD='(1.0,-1.0)';
      PINUSE='BI';
    'DDR2_SA_DQ29':
      PIN_NUMBER='(0,0,0,0,0,0,0,0,0,AD59,0,0,0,0,0,0,0,0,0,0,0,0,0,0,0,0,0,0,0,~
0,0,0,0,0,0,0,0,0,0,0,0,0)';
      BIDIRECTIONAL='TRUE';
      INPUT_LOAD='(-0.01,0.01)';
      OUTPUT_LOAD='(1.0,-1.0)';
      PINUSE='BI';
    'DDR2_SA_DQ28':
      PIN_NUMBER='(0,0,0,0,0,0,0,0,0,AC60,0,0,0,0,0,0,0,0,0,0,0,0,0,0,0,0,0,0,0,~
0,0,0,0,0,0,0,0,0,0,0,0,0)';
      BIDIRECTIONAL='TRUE';
      INPUT_LOAD='(-0.01,0.01)';
      OUTPUT_LOAD='(1.0,-1.0)';
      PINUSE='BI';
    'DDR2_SA_DQ27':
      PIN_NUMBER='(0,0,0,0,0,0,0,0,0,AG62,0,0,0,0,0,0,0,0,0,0,0,0,0,0,0,0,0,0,0,~
0,0,0,0,0,0,0,0,0,0,0,0,0)';
      BIDIRECTIONAL='TRUE';
      INPUT_LOAD='(-0.01,0.01)';
      OUTPUT_LOAD='(1.0,-1.0)';
      PINUSE='BI';
    'DDR2_SA_DQ26':
      PIN_NUMBER='(0,0,0,0,0,0,0,0,0,AF63,0,0,0,0,0,0,0,0,0,0,0,0,0,0,0,0,0,0,0,~
0,0,0,0,0,0,0,0,0,0,0,0,0)';
      BIDIRECTIONAL='TRUE';
      INPUT_LOAD='(-0.01,0.01)';
      OUTPUT_LOAD='(1.0,-1.0)';
      PINUSE='BI';
    'DDR2_SA_DQ25':
      PIN_NUMBER='(0,0,0,0,0,0,0,0,0,AC62,0,0,0,0,0,0,0,0,0,0,0,0,0,0,0,0,0,0,0,~
0,0,0,0,0,0,0,0,0,0,0,0,0)';
      BIDIRECTIONAL='TRUE';
      INPUT_LOAD='(-0.01,0.01)';
      OUTPUT_LOAD='(1.0,-1.0)';
      PINUSE='BI';
    'DDR2_SA_DQ24':
      PIN_NUMBER='(0,0,0,0,0,0,0,0,0,AD63,0,0,0,0,0,0,0,0,0,0,0,0,0,0,0,0,0,0,0,~
0,0,0,0,0,0,0,0,0,0,0,0,0)';
      BIDIRECTIONAL='TRUE';
      INPUT_LOAD='(-0.01,0.01)';
      OUTPUT_LOAD='(1.0,-1.0)';
      PINUSE='BI';
    'DDR2_SA_DQ23':
      PIN_NUMBER='(0,0,0,0,0,0,0,0,0,W62,0,0,0,0,0,0,0,0,0,0,0,0,0,0,0,0,0,0,0,0~
,0,0,0,0,0,0,0,0,0,0,0,0)';
      BIDIRECTIONAL='TRUE';
      INPUT_LOAD='(-0.01,0.01)';
      OUTPUT_LOAD='(1.0,-1.0)';
      PINUSE='BI';
    'DDR2_SA_DQ22':
      PIN_NUMBER='(0,0,0,0,0,0,0,0,0,Y63,0,0,0,0,0,0,0,0,0,0,0,0,0,0,0,0,0,0,0,0~
,0,0,0,0,0,0,0,0,0,0,0,0)';
      BIDIRECTIONAL='TRUE';
      INPUT_LOAD='(-0.01,0.01)';
      OUTPUT_LOAD='(1.0,-1.0)';
      PINUSE='BI';
    'DDR2_SA_DQ21':
      PIN_NUMBER='(0,0,0,0,0,0,0,0,0,U62,0,0,0,0,0,0,0,0,0,0,0,0,0,0,0,0,0,0,0,0~
,0,0,0,0,0,0,0,0,0,0,0,0)';
      BIDIRECTIONAL='TRUE';
      INPUT_LOAD='(-0.01,0.01)';
      OUTPUT_LOAD='(1.0,-1.0)';
      PINUSE='BI';
    'DDR2_SA_DQ20':
      PIN_NUMBER='(0,0,0,0,0,0,0,0,0,T63,0,0,0,0,0,0,0,0,0,0,0,0,0,0,0,0,0,0,0,0~
,0,0,0,0,0,0,0,0,0,0,0,0)';
      BIDIRECTIONAL='TRUE';
      INPUT_LOAD='(-0.01,0.01)';
      OUTPUT_LOAD='(1.0,-1.0)';
      PINUSE='BI';
    'DDR2_SA_DQ19':
      PIN_NUMBER='(0,0,0,0,0,0,0,0,0,Y65,0,0,0,0,0,0,0,0,0,0,0,0,0,0,0,0,0,0,0,0~
,0,0,0,0,0,0,0,0,0,0,0,0)';
      BIDIRECTIONAL='TRUE';
      INPUT_LOAD='(-0.01,0.01)';
      OUTPUT_LOAD='(1.0,-1.0)';
      PINUSE='BI';
    'DDR2_SA_DQ18':
      PIN_NUMBER='(0,0,0,0,0,0,0,0,0,W66,0,0,0,0,0,0,0,0,0,0,0,0,0,0,0,0,0,0,0,0~
,0,0,0,0,0,0,0,0,0,0,0,0)';
      BIDIRECTIONAL='TRUE';
      INPUT_LOAD='(-0.01,0.01)';
      OUTPUT_LOAD='(1.0,-1.0)';
      PINUSE='BI';
    'DDR2_SA_DQ17':
      PIN_NUMBER='(0,0,0,0,0,0,0,0,0,T65,0,0,0,0,0,0,0,0,0,0,0,0,0,0,0,0,0,0,0,0~
,0,0,0,0,0,0,0,0,0,0,0,0)';
      BIDIRECTIONAL='TRUE';
      INPUT_LOAD='(-0.01,0.01)';
      OUTPUT_LOAD='(1.0,-1.0)';
      PINUSE='BI';
    'DDR2_SA_DQ16':
      PIN_NUMBER='(0,0,0,0,0,0,0,0,0,U66,0,0,0,0,0,0,0,0,0,0,0,0,0,0,0,0,0,0,0,0~
,0,0,0,0,0,0,0,0,0,0,0,0)';
      BIDIRECTIONAL='TRUE';
      INPUT_LOAD='(-0.01,0.01)';
      OUTPUT_LOAD='(1.0,-1.0)';
      PINUSE='BI';
    'DDR2_SA_DQ15':
      PIN_NUMBER='(0,0,0,0,0,0,0,0,0,AF65,0,0,0,0,0,0,0,0,0,0,0,0,0,0,0,0,0,0,0,~
0,0,0,0,0,0,0,0,0,0,0,0,0)';
      BIDIRECTIONAL='TRUE';
      INPUT_LOAD='(-0.01,0.01)';
      OUTPUT_LOAD='(1.0,-1.0)';
      PINUSE='BI';
    'DDR2_SA_DQ14':
      PIN_NUMBER='(0,0,0,0,0,0,0,0,0,AG66,0,0,0,0,0,0,0,0,0,0,0,0,0,0,0,0,0,0,0,~
0,0,0,0,0,0,0,0,0,0,0,0,0)';
      BIDIRECTIONAL='TRUE';
      INPUT_LOAD='(-0.01,0.01)';
      OUTPUT_LOAD='(1.0,-1.0)';
      PINUSE='BI';
    'DDR2_SA_DQ13':
      PIN_NUMBER='(0,0,0,0,0,0,0,0,0,AD65,0,0,0,0,0,0,0,0,0,0,0,0,0,0,0,0,0,0,0,~
0,0,0,0,0,0,0,0,0,0,0,0,0)';
      BIDIRECTIONAL='TRUE';
      INPUT_LOAD='(-0.01,0.01)';
      OUTPUT_LOAD='(1.0,-1.0)';
      PINUSE='BI';
    'DDR2_SA_DQ12':
      PIN_NUMBER='(0,0,0,0,0,0,0,0,0,AC66,0,0,0,0,0,0,0,0,0,0,0,0,0,0,0,0,0,0,0,~
0,0,0,0,0,0,0,0,0,0,0,0,0)';
      BIDIRECTIONAL='TRUE';
      INPUT_LOAD='(-0.01,0.01)';
      OUTPUT_LOAD='(1.0,-1.0)';
      PINUSE='BI';
    'DDR2_SA_DQ11':
      PIN_NUMBER='(0,0,0,0,0,0,0,0,0,AG68,0,0,0,0,0,0,0,0,0,0,0,0,0,0,0,0,0,0,0,~
0,0,0,0,0,0,0,0,0,0,0,0,0)';
      BIDIRECTIONAL='TRUE';
      INPUT_LOAD='(-0.01,0.01)';
      OUTPUT_LOAD='(1.0,-1.0)';
      PINUSE='BI';
    'DDR2_SA_DQ10':
      PIN_NUMBER='(0,0,0,0,0,0,0,0,0,AF69,0,0,0,0,0,0,0,0,0,0,0,0,0,0,0,0,0,0,0,~
0,0,0,0,0,0,0,0,0,0,0,0,0)';
      BIDIRECTIONAL='TRUE';
      INPUT_LOAD='(-0.01,0.01)';
      OUTPUT_LOAD='(1.0,-1.0)';
      PINUSE='BI';
    'DDR2_SA_DQ9':
      PIN_NUMBER='(0,0,0,0,0,0,0,0,0,AC68,0,0,0,0,0,0,0,0,0,0,0,0,0,0,0,0,0,0,0,~
0,0,0,0,0,0,0,0,0,0,0,0,0)';
      BIDIRECTIONAL='TRUE';
      INPUT_LOAD='(-0.01,0.01)';
      OUTPUT_LOAD='(1.0,-1.0)';
      PINUSE='BI';
    'DDR2_SA_DQ8':
      PIN_NUMBER='(0,0,0,0,0,0,0,0,0,AD69,0,0,0,0,0,0,0,0,0,0,0,0,0,0,0,0,0,0,0,~
0,0,0,0,0,0,0,0,0,0,0,0,0)';
      BIDIRECTIONAL='TRUE';
      INPUT_LOAD='(-0.01,0.01)';
      OUTPUT_LOAD='(1.0,-1.0)';
      PINUSE='BI';
    'DDR2_SA_DQ7':
      PIN_NUMBER='(0,0,0,0,0,0,0,0,0,W74,0,0,0,0,0,0,0,0,0,0,0,0,0,0,0,0,0,0,0,0~
,0,0,0,0,0,0,0,0,0,0,0,0)';
      BIDIRECTIONAL='TRUE';
      INPUT_LOAD='(-0.01,0.01)';
      OUTPUT_LOAD='(1.0,-1.0)';
      PINUSE='BI';
    'DDR2_SA_DQ6':
      PIN_NUMBER='(0,0,0,0,0,0,0,0,0,Y75,0,0,0,0,0,0,0,0,0,0,0,0,0,0,0,0,0,0,0,0~
,0,0,0,0,0,0,0,0,0,0,0,0)';
      BIDIRECTIONAL='TRUE';
      INPUT_LOAD='(-0.01,0.01)';
      OUTPUT_LOAD='(1.0,-1.0)';
      PINUSE='BI';
    'DDR2_SA_DQ5':
      PIN_NUMBER='(0,0,0,0,0,0,0,0,0,U74,0,0,0,0,0,0,0,0,0,0,0,0,0,0,0,0,0,0,0,0~
,0,0,0,0,0,0,0,0,0,0,0,0)';
      BIDIRECTIONAL='TRUE';
      INPUT_LOAD='(-0.01,0.01)';
      OUTPUT_LOAD='(1.0,-1.0)';
      PINUSE='BI';
    'DDR2_SA_DQ4':
      PIN_NUMBER='(0,0,0,0,0,0,0,0,0,T75,0,0,0,0,0,0,0,0,0,0,0,0,0,0,0,0,0,0,0,0~
,0,0,0,0,0,0,0,0,0,0,0,0)';
      BIDIRECTIONAL='TRUE';
      INPUT_LOAD='(-0.01,0.01)';
      OUTPUT_LOAD='(1.0,-1.0)';
      PINUSE='BI';
    'DDR2_SA_DQ3':
      PIN_NUMBER='(0,0,0,0,0,0,0,0,0,Y77,0,0,0,0,0,0,0,0,0,0,0,0,0,0,0,0,0,0,0,0~
,0,0,0,0,0,0,0,0,0,0,0,0)';
      BIDIRECTIONAL='TRUE';
      INPUT_LOAD='(-0.01,0.01)';
      OUTPUT_LOAD='(1.0,-1.0)';
      PINUSE='BI';
    'DDR2_SA_DQ2':
      PIN_NUMBER='(0,0,0,0,0,0,0,0,0,W78,0,0,0,0,0,0,0,0,0,0,0,0,0,0,0,0,0,0,0,0~
,0,0,0,0,0,0,0,0,0,0,0,0)';
      BIDIRECTIONAL='TRUE';
      INPUT_LOAD='(-0.01,0.01)';
      OUTPUT_LOAD='(1.0,-1.0)';
      PINUSE='BI';
    'DDR2_SA_DQ1':
      PIN_NUMBER='(0,0,0,0,0,0,0,0,0,T77,0,0,0,0,0,0,0,0,0,0,0,0,0,0,0,0,0,0,0,0~
,0,0,0,0,0,0,0,0,0,0,0,0)';
      BIDIRECTIONAL='TRUE';
      INPUT_LOAD='(-0.01,0.01)';
      OUTPUT_LOAD='(1.0,-1.0)';
      PINUSE='BI';
    'DDR2_SA_DQ0':
      PIN_NUMBER='(0,0,0,0,0,0,0,0,0,U78,0,0,0,0,0,0,0,0,0,0,0,0,0,0,0,0,0,0,0,0~
,0,0,0,0,0,0,0,0,0,0,0,0)';
      BIDIRECTIONAL='TRUE';
      INPUT_LOAD='(-0.01,0.01)';
      OUTPUT_LOAD='(1.0,-1.0)';
      PINUSE='BI';
    'DDR2_SA_DQS_DN9':
      PIN_NUMBER='(0,0,0,0,0,0,0,0,0,AH55,0,0,0,0,0,0,0,0,0,0,0,0,0,0,0,0,0,0,0,~
0,0,0,0,0,0,0,0,0,0,0,0,0)';
      BIDIRECTIONAL='TRUE';
      INPUT_LOAD='(-0.01,0.01)';
      OUTPUT_LOAD='(1.0,-1.0)';
      PINUSE='BI';
    'DDR2_SA_DQS_DN8':
      PIN_NUMBER='(0,0,0,0,0,0,0,0,0,AF61,0,0,0,0,0,0,0,0,0,0,0,0,0,0,0,0,0,0,0,~
0,0,0,0,0,0,0,0,0,0,0,0,0)';
      BIDIRECTIONAL='TRUE';
      INPUT_LOAD='(-0.01,0.01)';
      OUTPUT_LOAD='(1.0,-1.0)';
      PINUSE='BI';
    'DDR2_SA_DQS_DN7':
      PIN_NUMBER='(0,0,0,0,0,0,0,0,0,AA64,0,0,0,0,0,0,0,0,0,0,0,0,0,0,0,0,0,0,0,~
0,0,0,0,0,0,0,0,0,0,0,0,0)';
      BIDIRECTIONAL='TRUE';
      INPUT_LOAD='(-0.01,0.01)';
      OUTPUT_LOAD='(1.0,-1.0)';
      PINUSE='BI';
    'DDR2_SA_DQS_DN6':
      PIN_NUMBER='(0,0,0,0,0,0,0,0,0,AH67,0,0,0,0,0,0,0,0,0,0,0,0,0,0,0,0,0,0,0,~
0,0,0,0,0,0,0,0,0,0,0,0,0)';
      BIDIRECTIONAL='TRUE';
      INPUT_LOAD='(-0.01,0.01)';
      OUTPUT_LOAD='(1.0,-1.0)';
      PINUSE='BI';
    'DDR2_SA_DQS_DN5':
      PIN_NUMBER='(0,0,0,0,0,0,0,0,0,W76,0,0,0,0,0,0,0,0,0,0,0,0,0,0,0,0,0,0,0,0~
,0,0,0,0,0,0,0,0,0,0,0,0)';
      BIDIRECTIONAL='TRUE';
      INPUT_LOAD='(-0.01,0.01)';
      OUTPUT_LOAD='(1.0,-1.0)';
      PINUSE='BI';
    'DDR2_SA_DQS_DN4':
      PIN_NUMBER='(0,0,0,0,0,0,0,0,0,AD55,0,0,0,0,0,0,0,0,0,0,0,0,0,0,0,0,0,0,0,~
0,0,0,0,0,0,0,0,0,0,0,0,0)';
      BIDIRECTIONAL='TRUE';
      INPUT_LOAD='(-0.01,0.01)';
      OUTPUT_LOAD='(1.0,-1.0)';
      PINUSE='BI';
    'DDR2_SA_DQS_DN3':
      PIN_NUMBER='(0,0,0,0,0,0,0,0,0,AB61,0,0,0,0,0,0,0,0,0,0,0,0,0,0,0,0,0,0,0,~
0,0,0,0,0,0,0,0,0,0,0,0,0)';
      BIDIRECTIONAL='TRUE';
      INPUT_LOAD='(-0.01,0.01)';
      OUTPUT_LOAD='(1.0,-1.0)';
      PINUSE='BI';
    'DDR2_SA_DQS_DN2':
      PIN_NUMBER='(0,0,0,0,0,0,0,0,0,R64,0,0,0,0,0,0,0,0,0,0,0,0,0,0,0,0,0,0,0,0~
,0,0,0,0,0,0,0,0,0,0,0,0)';
      BIDIRECTIONAL='TRUE';
      INPUT_LOAD='(-0.01,0.01)';
      OUTPUT_LOAD='(1.0,-1.0)';
      PINUSE='BI';
    'DDR2_SA_DQS_DN1':
      PIN_NUMBER='(0,0,0,0,0,0,0,0,0,AB67,0,0,0,0,0,0,0,0,0,0,0,0,0,0,0,0,0,0,0,~
0,0,0,0,0,0,0,0,0,0,0,0,0)';
      BIDIRECTIONAL='TRUE';
      INPUT_LOAD='(-0.01,0.01)';
      OUTPUT_LOAD='(1.0,-1.0)';
      PINUSE='BI';
    'DDR2_SA_DQS_DN0':
      PIN_NUMBER='(0,0,0,0,0,0,0,0,0,R76,0,0,0,0,0,0,0,0,0,0,0,0,0,0,0,0,0,0,0,0~
,0,0,0,0,0,0,0,0,0,0,0,0)';
      BIDIRECTIONAL='TRUE';
      INPUT_LOAD='(-0.01,0.01)';
      OUTPUT_LOAD='(1.0,-1.0)';
      PINUSE='BI';
    'DDR2_SA_DQS_DP9':
      PIN_NUMBER='(0,0,0,0,0,0,0,0,0,AF55,0,0,0,0,0,0,0,0,0,0,0,0,0,0,0,0,0,0,0,~
0,0,0,0,0,0,0,0,0,0,0,0,0)';
      BIDIRECTIONAL='TRUE';
      INPUT_LOAD='(-0.01,0.01)';
      OUTPUT_LOAD='(1.0,-1.0)';
      PINUSE='BI';
    'DDR2_SA_DQS_DP8':
      PIN_NUMBER='(0,0,0,0,0,0,0,0,0,AH61,0,0,0,0,0,0,0,0,0,0,0,0,0,0,0,0,0,0,0,~
0,0,0,0,0,0,0,0,0,0,0,0,0)';
      BIDIRECTIONAL='TRUE';
      INPUT_LOAD='(-0.01,0.01)';
      OUTPUT_LOAD='(1.0,-1.0)';
      PINUSE='BI';
    'DDR2_SA_DQS_DP7':
      PIN_NUMBER='(0,0,0,0,0,0,0,0,0,W64,0,0,0,0,0,0,0,0,0,0,0,0,0,0,0,0,0,0,0,0~
,0,0,0,0,0,0,0,0,0,0,0,0)';
      BIDIRECTIONAL='TRUE';
      INPUT_LOAD='(-0.01,0.01)';
      OUTPUT_LOAD='(1.0,-1.0)';
      PINUSE='BI';
    'DDR2_SA_DQS_DP6':
      PIN_NUMBER='(0,0,0,0,0,0,0,0,0,AF67,0,0,0,0,0,0,0,0,0,0,0,0,0,0,0,0,0,0,0,~
0,0,0,0,0,0,0,0,0,0,0,0,0)';
      BIDIRECTIONAL='TRUE';
      INPUT_LOAD='(-0.01,0.01)';
      OUTPUT_LOAD='(1.0,-1.0)';
      PINUSE='BI';
    'DDR2_SA_DQS_DP5':
      PIN_NUMBER='(0,0,0,0,0,0,0,0,0,AA76,0,0,0,0,0,0,0,0,0,0,0,0,0,0,0,0,0,0,0,~
0,0,0,0,0,0,0,0,0,0,0,0,0)';
      BIDIRECTIONAL='TRUE';
      INPUT_LOAD='(-0.01,0.01)';
      OUTPUT_LOAD='(1.0,-1.0)';
      PINUSE='BI';
    'DDR2_SA_DQS_DP4':
      PIN_NUMBER='(0,0,0,0,0,0,0,0,0,AB55,0,0,0,0,0,0,0,0,0,0,0,0,0,0,0,0,0,0,0,~
0,0,0,0,0,0,0,0,0,0,0,0,0)';
      BIDIRECTIONAL='TRUE';
      INPUT_LOAD='(-0.01,0.01)';
      OUTPUT_LOAD='(1.0,-1.0)';
      PINUSE='BI';
    'DDR2_SA_DQS_DP3':
      PIN_NUMBER='(0,0,0,0,0,0,0,0,0,AD61,0,0,0,0,0,0,0,0,0,0,0,0,0,0,0,0,0,0,0,~
0,0,0,0,0,0,0,0,0,0,0,0,0)';
      BIDIRECTIONAL='TRUE';
      INPUT_LOAD='(-0.01,0.01)';
      OUTPUT_LOAD='(1.0,-1.0)';
      PINUSE='BI';
    'DDR2_SA_DQS_DP2':
      PIN_NUMBER='(0,0,0,0,0,0,0,0,0,U64,0,0,0,0,0,0,0,0,0,0,0,0,0,0,0,0,0,0,0,0~
,0,0,0,0,0,0,0,0,0,0,0,0)';
      BIDIRECTIONAL='TRUE';
      INPUT_LOAD='(-0.01,0.01)';
      OUTPUT_LOAD='(1.0,-1.0)';
      PINUSE='BI';
    'DDR2_SA_DQS_DP1':
      PIN_NUMBER='(0,0,0,0,0,0,0,0,0,AD67,0,0,0,0,0,0,0,0,0,0,0,0,0,0,0,0,0,0,0,~
0,0,0,0,0,0,0,0,0,0,0,0,0)';
      BIDIRECTIONAL='TRUE';
      INPUT_LOAD='(-0.01,0.01)';
      OUTPUT_LOAD='(1.0,-1.0)';
      PINUSE='BI';
    'DDR2_SA_DQS_DP0':
      PIN_NUMBER='(0,0,0,0,0,0,0,0,0,U76,0,0,0,0,0,0,0,0,0,0,0,0,0,0,0,0,0,0,0,0~
,0,0,0,0,0,0,0,0,0,0,0,0)';
      BIDIRECTIONAL='TRUE';
      INPUT_LOAD='(-0.01,0.01)';
      OUTPUT_LOAD='(1.0,-1.0)';
      PINUSE='BI';
    'DDR2_SA_ECC7':
      PIN_NUMBER='(0,0,0,0,0,0,0,0,0,AF53,0,0,0,0,0,0,0,0,0,0,0,0,0,0,0,0,0,0,0,~
0,0,0,0,0,0,0,0,0,0,0,0,0)';
      BIDIRECTIONAL='TRUE';
      INPUT_LOAD='(-0.01,0.01)';
      OUTPUT_LOAD='(1.0,-1.0)';
      PINUSE='BI';
    'DDR2_SA_ECC6':
      PIN_NUMBER='(0,0,0,0,0,0,0,0,0,AG54,0,0,0,0,0,0,0,0,0,0,0,0,0,0,0,0,0,0,0,~
0,0,0,0,0,0,0,0,0,0,0,0,0)';
      BIDIRECTIONAL='TRUE';
      INPUT_LOAD='(-0.01,0.01)';
      OUTPUT_LOAD='(1.0,-1.0)';
      PINUSE='BI';
    'DDR2_SA_ECC5':
      PIN_NUMBER='(0,0,0,0,0,0,0,0,0,AD53,0,0,0,0,0,0,0,0,0,0,0,0,0,0,0,0,0,0,0,~
0,0,0,0,0,0,0,0,0,0,0,0,0)';
      BIDIRECTIONAL='TRUE';
      INPUT_LOAD='(-0.01,0.01)';
      OUTPUT_LOAD='(1.0,-1.0)';
      PINUSE='BI';
    'DDR2_SA_ECC4':
      PIN_NUMBER='(0,0,0,0,0,0,0,0,0,AC54,0,0,0,0,0,0,0,0,0,0,0,0,0,0,0,0,0,0,0,~
0,0,0,0,0,0,0,0,0,0,0,0,0)';
      BIDIRECTIONAL='TRUE';
      INPUT_LOAD='(-0.01,0.01)';
      OUTPUT_LOAD='(1.0,-1.0)';
      PINUSE='BI';
    'DDR2_SA_ECC3':
      PIN_NUMBER='(0,0,0,0,0,0,0,0,0,AG56,0,0,0,0,0,0,0,0,0,0,0,0,0,0,0,0,0,0,0,~
0,0,0,0,0,0,0,0,0,0,0,0,0)';
      BIDIRECTIONAL='TRUE';
      INPUT_LOAD='(-0.01,0.01)';
      OUTPUT_LOAD='(1.0,-1.0)';
      PINUSE='BI';
    'DDR2_SA_ECC2':
      PIN_NUMBER='(0,0,0,0,0,0,0,0,0,AF57,0,0,0,0,0,0,0,0,0,0,0,0,0,0,0,0,0,0,0,~
0,0,0,0,0,0,0,0,0,0,0,0,0)';
      BIDIRECTIONAL='TRUE';
      INPUT_LOAD='(-0.01,0.01)';
      OUTPUT_LOAD='(1.0,-1.0)';
      PINUSE='BI';
    'DDR2_SA_ECC1':
      PIN_NUMBER='(0,0,0,0,0,0,0,0,0,AC56,0,0,0,0,0,0,0,0,0,0,0,0,0,0,0,0,0,0,0,~
0,0,0,0,0,0,0,0,0,0,0,0,0)';
      BIDIRECTIONAL='TRUE';
      INPUT_LOAD='(-0.01,0.01)';
      OUTPUT_LOAD='(1.0,-1.0)';
      PINUSE='BI';
    'DDR2_SA_ECC0':
      PIN_NUMBER='(0,0,0,0,0,0,0,0,0,AD57,0,0,0,0,0,0,0,0,0,0,0,0,0,0,0,0,0,0,0,~
0,0,0,0,0,0,0,0,0,0,0,0,0)';
      BIDIRECTIONAL='TRUE';
      INPUT_LOAD='(-0.01,0.01)';
      OUTPUT_LOAD='(1.0,-1.0)';
      PINUSE='BI';
    'DDR2_SA_PAR':
      PIN_NUMBER='(0,0,0,0,0,0,0,0,0,T47,0,0,0,0,0,0,0,0,0,0,0,0,0,0,0,0,0,0,0,0~
,0,0,0,0,0,0,0,0,0,0,0,0)';
      OUTPUT_LOAD='(1.0,-1.0)';
      PINUSE='OUT';
    'DDR2_SB_CA6':
      PIN_NUMBER='(0,0,0,0,0,0,0,0,0,R39,0,0,0,0,0,0,0,0,0,0,0,0,0,0,0,0,0,0,0,0~
,0,0,0,0,0,0,0,0,0,0,0,0)';
      OUTPUT_LOAD='(1.0,-1.0)';
      PINUSE='OUT';
    'DDR2_SB_CA5':
      PIN_NUMBER='(0,0,0,0,0,0,0,0,0,Y40,0,0,0,0,0,0,0,0,0,0,0,0,0,0,0,0,0,0,0,0~
,0,0,0,0,0,0,0,0,0,0,0,0)';
      OUTPUT_LOAD='(1.0,-1.0)';
      PINUSE='OUT';
    'DDR2_SB_CA4':
      PIN_NUMBER='(0,0,0,0,0,0,0,0,0,T40,0,0,0,0,0,0,0,0,0,0,0,0,0,0,0,0,0,0,0,0~
,0,0,0,0,0,0,0,0,0,0,0,0)';
      OUTPUT_LOAD='(1.0,-1.0)';
      PINUSE='OUT';
    'DDR2_SB_CA3':
      PIN_NUMBER='(0,0,0,0,0,0,0,0,0,W41,0,0,0,0,0,0,0,0,0,0,0,0,0,0,0,0,0,0,0,0~
,0,0,0,0,0,0,0,0,0,0,0,0)';
      OUTPUT_LOAD='(1.0,-1.0)';
      PINUSE='OUT';
    'DDR2_SB_CA2':
      PIN_NUMBER='(0,0,0,0,0,0,0,0,0,U41,0,0,0,0,0,0,0,0,0,0,0,0,0,0,0,0,0,0,0,0~
,0,0,0,0,0,0,0,0,0,0,0,0)';
      OUTPUT_LOAD='(1.0,-1.0)';
      PINUSE='OUT';
    'DDR2_SB_CA1':
      PIN_NUMBER='(0,0,0,0,0,0,0,0,0,Y47,0,0,0,0,0,0,0,0,0,0,0,0,0,0,0,0,0,0,0,0~
,0,0,0,0,0,0,0,0,0,0,0,0)';
      OUTPUT_LOAD='(1.0,-1.0)';
      PINUSE='OUT';
    'DDR2_SB_CA0':
      PIN_NUMBER='(0,0,0,0,0,0,0,0,0,W48,0,0,0,0,0,0,0,0,0,0,0,0,0,0,0,0,0,0,0,0~
,0,0,0,0,0,0,0,0,0,0,0,0)';
      OUTPUT_LOAD='(1.0,-1.0)';
      PINUSE='OUT';
    'DDR2_SB_CS_N3':
      PIN_NUMBER='(0,0,0,0,0,0,0,0,0,W37,0,0,0,0,0,0,0,0,0,0,0,0,0,0,0,0,0,0,0,0~
,0,0,0,0,0,0,0,0,0,0,0,0)';
      OUTPUT_LOAD='(1.0,-1.0)';
      PINUSE='OUT';
    'DDR2_SB_CS_N2':
      PIN_NUMBER='(0,0,0,0,0,0,0,0,0,Y38,0,0,0,0,0,0,0,0,0,0,0,0,0,0,0,0,0,0,0,0~
,0,0,0,0,0,0,0,0,0,0,0,0)';
      OUTPUT_LOAD='(1.0,-1.0)';
      PINUSE='OUT';
    'DDR2_SB_CS_N1':
      PIN_NUMBER='(0,0,0,0,0,0,0,0,0,U37,0,0,0,0,0,0,0,0,0,0,0,0,0,0,0,0,0,0,0,0~
,0,0,0,0,0,0,0,0,0,0,0,0)';
      OUTPUT_LOAD='(1.0,-1.0)';
      PINUSE='OUT';
    'DDR2_SB_CS_N0':
      PIN_NUMBER='(0,0,0,0,0,0,0,0,0,T38,0,0,0,0,0,0,0,0,0,0,0,0,0,0,0,0,0,0,0,0~
,0,0,0,0,0,0,0,0,0,0,0,0)';
      OUTPUT_LOAD='(1.0,-1.0)';
      PINUSE='OUT';
    'DDR2_SB_DQ31':
      PIN_NUMBER='(0,0,0,0,0,0,0,0,0,AJ17,0,0,0,0,0,0,0,0,0,0,0,0,0,0,0,0,0,0,0,~
0,0,0,0,0,0,0,0,0,0,0,0,0)';
      BIDIRECTIONAL='TRUE';
      INPUT_LOAD='(-0.01,0.01)';
      OUTPUT_LOAD='(1.0,-1.0)';
      PINUSE='BI';
    'DDR2_SB_DQ30':
      PIN_NUMBER='(0,0,0,0,0,0,0,0,0,AC17,0,0,0,0,0,0,0,0,0,0,0,0,0,0,0,0,0,0,0,~
0,0,0,0,0,0,0,0,0,0,0,0,0)';
      BIDIRECTIONAL='TRUE';
      INPUT_LOAD='(-0.01,0.01)';
      OUTPUT_LOAD='(1.0,-1.0)';
      PINUSE='BI';
    'DDR2_SB_DQ29':
      PIN_NUMBER='(0,0,0,0,0,0,0,0,0,AG17,0,0,0,0,0,0,0,0,0,0,0,0,0,0,0,0,0,0,0,~
0,0,0,0,0,0,0,0,0,0,0,0,0)';
      BIDIRECTIONAL='TRUE';
      INPUT_LOAD='(-0.01,0.01)';
      OUTPUT_LOAD='(1.0,-1.0)';
      PINUSE='BI';
    'DDR2_SB_DQ28':
      PIN_NUMBER='(0,0,0,0,0,0,0,0,0,AA17,0,0,0,0,0,0,0,0,0,0,0,0,0,0,0,0,0,0,0,~
0,0,0,0,0,0,0,0,0,0,0,0,0)';
      BIDIRECTIONAL='TRUE';
      INPUT_LOAD='(-0.01,0.01)';
      OUTPUT_LOAD='(1.0,-1.0)';
      PINUSE='BI';
    'DDR2_SB_DQ27':
      PIN_NUMBER='(0,0,0,0,0,0,0,0,0,AG19,0,0,0,0,0,0,0,0,0,0,0,0,0,0,0,0,0,0,0,~
0,0,0,0,0,0,0,0,0,0,0,0,0)';
      BIDIRECTIONAL='TRUE';
      INPUT_LOAD='(-0.01,0.01)';
      OUTPUT_LOAD='(1.0,-1.0)';
      PINUSE='BI';
    'DDR2_SB_DQ26':
      PIN_NUMBER='(0,0,0,0,0,0,0,0,0,AF20,0,0,0,0,0,0,0,0,0,0,0,0,0,0,0,0,0,0,0,~
0,0,0,0,0,0,0,0,0,0,0,0,0)';
      BIDIRECTIONAL='TRUE';
      INPUT_LOAD='(-0.01,0.01)';
      OUTPUT_LOAD='(1.0,-1.0)';
      PINUSE='BI';
    'DDR2_SB_DQ25':
      PIN_NUMBER='(0,0,0,0,0,0,0,0,0,AC19,0,0,0,0,0,0,0,0,0,0,0,0,0,0,0,0,0,0,0,~
0,0,0,0,0,0,0,0,0,0,0,0,0)';
      BIDIRECTIONAL='TRUE';
      INPUT_LOAD='(-0.01,0.01)';
      OUTPUT_LOAD='(1.0,-1.0)';
      PINUSE='BI';
    'DDR2_SB_DQ24':
      PIN_NUMBER='(0,0,0,0,0,0,0,0,0,AD20,0,0,0,0,0,0,0,0,0,0,0,0,0,0,0,0,0,0,0,~
0,0,0,0,0,0,0,0,0,0,0,0,0)';
      BIDIRECTIONAL='TRUE';
      INPUT_LOAD='(-0.01,0.01)';
      OUTPUT_LOAD='(1.0,-1.0)';
      PINUSE='BI';
    'DDR2_SB_DQ23':
      PIN_NUMBER='(0,0,0,0,0,0,0,0,0,W19,0,0,0,0,0,0,0,0,0,0,0,0,0,0,0,0,0,0,0,0~
,0,0,0,0,0,0,0,0,0,0,0,0)';
      BIDIRECTIONAL='TRUE';
      INPUT_LOAD='(-0.01,0.01)';
      OUTPUT_LOAD='(1.0,-1.0)';
      PINUSE='BI';
    'DDR2_SB_DQ22':
      PIN_NUMBER='(0,0,0,0,0,0,0,0,0,Y20,0,0,0,0,0,0,0,0,0,0,0,0,0,0,0,0,0,0,0,0~
,0,0,0,0,0,0,0,0,0,0,0,0)';
      BIDIRECTIONAL='TRUE';
      INPUT_LOAD='(-0.01,0.01)';
      OUTPUT_LOAD='(1.0,-1.0)';
      PINUSE='BI';
    'DDR2_SB_DQ21':
      PIN_NUMBER='(0,0,0,0,0,0,0,0,0,U19,0,0,0,0,0,0,0,0,0,0,0,0,0,0,0,0,0,0,0,0~
,0,0,0,0,0,0,0,0,0,0,0,0)';
      BIDIRECTIONAL='TRUE';
      INPUT_LOAD='(-0.01,0.01)';
      OUTPUT_LOAD='(1.0,-1.0)';
      PINUSE='BI';
    'DDR2_SB_DQ20':
      PIN_NUMBER='(0,0,0,0,0,0,0,0,0,T20,0,0,0,0,0,0,0,0,0,0,0,0,0,0,0,0,0,0,0,0~
,0,0,0,0,0,0,0,0,0,0,0,0)';
      BIDIRECTIONAL='TRUE';
      INPUT_LOAD='(-0.01,0.01)';
      OUTPUT_LOAD='(1.0,-1.0)';
      PINUSE='BI';
    'DDR2_SB_DQ19':
      PIN_NUMBER='(0,0,0,0,0,0,0,0,0,Y22,0,0,0,0,0,0,0,0,0,0,0,0,0,0,0,0,0,0,0,0~
,0,0,0,0,0,0,0,0,0,0,0,0)';
      BIDIRECTIONAL='TRUE';
      INPUT_LOAD='(-0.01,0.01)';
      OUTPUT_LOAD='(1.0,-1.0)';
      PINUSE='BI';
    'DDR2_SB_DQ18':
      PIN_NUMBER='(0,0,0,0,0,0,0,0,0,W23,0,0,0,0,0,0,0,0,0,0,0,0,0,0,0,0,0,0,0,0~
,0,0,0,0,0,0,0,0,0,0,0,0)';
      BIDIRECTIONAL='TRUE';
      INPUT_LOAD='(-0.01,0.01)';
      OUTPUT_LOAD='(1.0,-1.0)';
      PINUSE='BI';
    'DDR2_SB_DQ17':
      PIN_NUMBER='(0,0,0,0,0,0,0,0,0,T22,0,0,0,0,0,0,0,0,0,0,0,0,0,0,0,0,0,0,0,0~
,0,0,0,0,0,0,0,0,0,0,0,0)';
      BIDIRECTIONAL='TRUE';
      INPUT_LOAD='(-0.01,0.01)';
      OUTPUT_LOAD='(1.0,-1.0)';
      PINUSE='BI';
    'DDR2_SB_DQ16':
      PIN_NUMBER='(0,0,0,0,0,0,0,0,0,U23,0,0,0,0,0,0,0,0,0,0,0,0,0,0,0,0,0,0,0,0~
,0,0,0,0,0,0,0,0,0,0,0,0)';
      BIDIRECTIONAL='TRUE';
      INPUT_LOAD='(-0.01,0.01)';
      OUTPUT_LOAD='(1.0,-1.0)';
      PINUSE='BI';
    'DDR2_SB_DQ15':
      PIN_NUMBER='(0,0,0,0,0,0,0,0,0,AF28,0,0,0,0,0,0,0,0,0,0,0,0,0,0,0,0,0,0,0,~
0,0,0,0,0,0,0,0,0,0,0,0,0)';
      BIDIRECTIONAL='TRUE';
      INPUT_LOAD='(-0.01,0.01)';
      OUTPUT_LOAD='(1.0,-1.0)';
      PINUSE='BI';
    'DDR2_SB_DQ14':
      PIN_NUMBER='(0,0,0,0,0,0,0,0,0,AG29,0,0,0,0,0,0,0,0,0,0,0,0,0,0,0,0,0,0,0,~
0,0,0,0,0,0,0,0,0,0,0,0,0)';
      BIDIRECTIONAL='TRUE';
      INPUT_LOAD='(-0.01,0.01)';
      OUTPUT_LOAD='(1.0,-1.0)';
      PINUSE='BI';
    'DDR2_SB_DQ13':
      PIN_NUMBER='(0,0,0,0,0,0,0,0,0,AD28,0,0,0,0,0,0,0,0,0,0,0,0,0,0,0,0,0,0,0,~
0,0,0,0,0,0,0,0,0,0,0,0,0)';
      BIDIRECTIONAL='TRUE';
      INPUT_LOAD='(-0.01,0.01)';
      OUTPUT_LOAD='(1.0,-1.0)';
      PINUSE='BI';
    'DDR2_SB_DQ12':
      PIN_NUMBER='(0,0,0,0,0,0,0,0,0,AC29,0,0,0,0,0,0,0,0,0,0,0,0,0,0,0,0,0,0,0,~
0,0,0,0,0,0,0,0,0,0,0,0,0)';
      BIDIRECTIONAL='TRUE';
      INPUT_LOAD='(-0.01,0.01)';
      OUTPUT_LOAD='(1.0,-1.0)';
      PINUSE='BI';
    'DDR2_SB_DQ11':
      PIN_NUMBER='(0,0,0,0,0,0,0,0,0,AG31,0,0,0,0,0,0,0,0,0,0,0,0,0,0,0,0,0,0,0,~
0,0,0,0,0,0,0,0,0,0,0,0,0)';
      BIDIRECTIONAL='TRUE';
      INPUT_LOAD='(-0.01,0.01)';
      OUTPUT_LOAD='(1.0,-1.0)';
      PINUSE='BI';
    'DDR2_SB_DQ10':
      PIN_NUMBER='(0,0,0,0,0,0,0,0,0,AF32,0,0,0,0,0,0,0,0,0,0,0,0,0,0,0,0,0,0,0,~
0,0,0,0,0,0,0,0,0,0,0,0,0)';
      BIDIRECTIONAL='TRUE';
      INPUT_LOAD='(-0.01,0.01)';
      OUTPUT_LOAD='(1.0,-1.0)';
      PINUSE='BI';
    'DDR2_SB_DQ9':
      PIN_NUMBER='(0,0,0,0,0,0,0,0,0,AC31,0,0,0,0,0,0,0,0,0,0,0,0,0,0,0,0,0,0,0,~
0,0,0,0,0,0,0,0,0,0,0,0,0)';
      BIDIRECTIONAL='TRUE';
      INPUT_LOAD='(-0.01,0.01)';
      OUTPUT_LOAD='(1.0,-1.0)';
      PINUSE='BI';
    'DDR2_SB_DQ8':
      PIN_NUMBER='(0,0,0,0,0,0,0,0,0,AD32,0,0,0,0,0,0,0,0,0,0,0,0,0,0,0,0,0,0,0,~
0,0,0,0,0,0,0,0,0,0,0,0,0)';
      BIDIRECTIONAL='TRUE';
      INPUT_LOAD='(-0.01,0.01)';
      OUTPUT_LOAD='(1.0,-1.0)';
      PINUSE='BI';
    'DDR2_SB_DQ7':
      PIN_NUMBER='(0,0,0,0,0,0,0,0,0,AF34,0,0,0,0,0,0,0,0,0,0,0,0,0,0,0,0,0,0,0,~
0,0,0,0,0,0,0,0,0,0,0,0,0)';
      BIDIRECTIONAL='TRUE';
      INPUT_LOAD='(-0.01,0.01)';
      OUTPUT_LOAD='(1.0,-1.0)';
      PINUSE='BI';
    'DDR2_SB_DQ6':
      PIN_NUMBER='(0,0,0,0,0,0,0,0,0,AG35,0,0,0,0,0,0,0,0,0,0,0,0,0,0,0,0,0,0,0,~
0,0,0,0,0,0,0,0,0,0,0,0,0)';
      BIDIRECTIONAL='TRUE';
      INPUT_LOAD='(-0.01,0.01)';
      OUTPUT_LOAD='(1.0,-1.0)';
      PINUSE='BI';
    'DDR2_SB_DQ5':
      PIN_NUMBER='(0,0,0,0,0,0,0,0,0,AD34,0,0,0,0,0,0,0,0,0,0,0,0,0,0,0,0,0,0,0,~
0,0,0,0,0,0,0,0,0,0,0,0,0)';
      BIDIRECTIONAL='TRUE';
      INPUT_LOAD='(-0.01,0.01)';
      OUTPUT_LOAD='(1.0,-1.0)';
      PINUSE='BI';
    'DDR2_SB_DQ4':
      PIN_NUMBER='(0,0,0,0,0,0,0,0,0,AC35,0,0,0,0,0,0,0,0,0,0,0,0,0,0,0,0,0,0,0,~
0,0,0,0,0,0,0,0,0,0,0,0,0)';
      BIDIRECTIONAL='TRUE';
      INPUT_LOAD='(-0.01,0.01)';
      OUTPUT_LOAD='(1.0,-1.0)';
      PINUSE='BI';
    'DDR2_SB_DQ3':
      PIN_NUMBER='(0,0,0,0,0,0,0,0,0,AG37,0,0,0,0,0,0,0,0,0,0,0,0,0,0,0,0,0,0,0,~
0,0,0,0,0,0,0,0,0,0,0,0,0)';
      BIDIRECTIONAL='TRUE';
      INPUT_LOAD='(-0.01,0.01)';
      OUTPUT_LOAD='(1.0,-1.0)';
      PINUSE='BI';
    'DDR2_SB_DQ2':
      PIN_NUMBER='(0,0,0,0,0,0,0,0,0,AF38,0,0,0,0,0,0,0,0,0,0,0,0,0,0,0,0,0,0,0,~
0,0,0,0,0,0,0,0,0,0,0,0,0)';
      BIDIRECTIONAL='TRUE';
      INPUT_LOAD='(-0.01,0.01)';
      OUTPUT_LOAD='(1.0,-1.0)';
      PINUSE='BI';
    'DDR2_SB_DQ1':
      PIN_NUMBER='(0,0,0,0,0,0,0,0,0,AC37,0,0,0,0,0,0,0,0,0,0,0,0,0,0,0,0,0,0,0,~
0,0,0,0,0,0,0,0,0,0,0,0,0)';
      BIDIRECTIONAL='TRUE';
      INPUT_LOAD='(-0.01,0.01)';
      OUTPUT_LOAD='(1.0,-1.0)';
      PINUSE='BI';
    'DDR2_SB_DQ0':
      PIN_NUMBER='(0,0,0,0,0,0,0,0,0,AD38,0,0,0,0,0,0,0,0,0,0,0,0,0,0,0,0,0,0,0,~
0,0,0,0,0,0,0,0,0,0,0,0,0)';
      BIDIRECTIONAL='TRUE';
      INPUT_LOAD='(-0.01,0.01)';
      OUTPUT_LOAD='(1.0,-1.0)';
      PINUSE='BI';
    'DDR2_SB_DQS_DN9':
      PIN_NUMBER='(0,0,0,0,0,0,0,0,0,R33,0,0,0,0,0,0,0,0,0,0,0,0,0,0,0,0,0,0,0,0~
,0,0,0,0,0,0,0,0,0,0,0,0)';
      BIDIRECTIONAL='TRUE';
      INPUT_LOAD='(-0.01,0.01)';
      OUTPUT_LOAD='(1.0,-1.0)';
      PINUSE='BI';
    'DDR2_SB_DQS_DN8':
      PIN_NUMBER='(0,0,0,0,0,0,0,0,0,AF18,0,0,0,0,0,0,0,0,0,0,0,0,0,0,0,0,0,0,0,~
0,0,0,0,0,0,0,0,0,0,0,0,0)';
      BIDIRECTIONAL='TRUE';
      INPUT_LOAD='(-0.01,0.01)';
      OUTPUT_LOAD='(1.0,-1.0)';
      PINUSE='BI';
    'DDR2_SB_DQS_DN7':
      PIN_NUMBER='(0,0,0,0,0,0,0,0,0,W21,0,0,0,0,0,0,0,0,0,0,0,0,0,0,0,0,0,0,0,0~
,0,0,0,0,0,0,0,0,0,0,0,0)';
      BIDIRECTIONAL='TRUE';
      INPUT_LOAD='(-0.01,0.01)';
      OUTPUT_LOAD='(1.0,-1.0)';
      PINUSE='BI';
    'DDR2_SB_DQS_DN6':
      PIN_NUMBER='(0,0,0,0,0,0,0,0,0,AF30,0,0,0,0,0,0,0,0,0,0,0,0,0,0,0,0,0,0,0,~
0,0,0,0,0,0,0,0,0,0,0,0,0)';
      BIDIRECTIONAL='TRUE';
      INPUT_LOAD='(-0.01,0.01)';
      OUTPUT_LOAD='(1.0,-1.0)';
      PINUSE='BI';
    'DDR2_SB_DQS_DN5':
      PIN_NUMBER='(0,0,0,0,0,0,0,0,0,AF36,0,0,0,0,0,0,0,0,0,0,0,0,0,0,0,0,0,0,0,~
0,0,0,0,0,0,0,0,0,0,0,0,0)';
      BIDIRECTIONAL='TRUE';
      INPUT_LOAD='(-0.01,0.01)';
      OUTPUT_LOAD='(1.0,-1.0)';
      PINUSE='BI';
    'DDR2_SB_DQS_DN4':
      PIN_NUMBER='(0,0,0,0,0,0,0,0,0,W33,0,0,0,0,0,0,0,0,0,0,0,0,0,0,0,0,0,0,0,0~
,0,0,0,0,0,0,0,0,0,0,0,0)';
      BIDIRECTIONAL='TRUE';
      INPUT_LOAD='(-0.01,0.01)';
      OUTPUT_LOAD='(1.0,-1.0)';
      PINUSE='BI';
    'DDR2_SB_DQS_DN3':
      PIN_NUMBER='(0,0,0,0,0,0,0,0,0,AB18,0,0,0,0,0,0,0,0,0,0,0,0,0,0,0,0,0,0,0,~
0,0,0,0,0,0,0,0,0,0,0,0,0)';
      BIDIRECTIONAL='TRUE';
      INPUT_LOAD='(-0.01,0.01)';
      OUTPUT_LOAD='(1.0,-1.0)';
      PINUSE='BI';
    'DDR2_SB_DQS_DN2':
      PIN_NUMBER='(0,0,0,0,0,0,0,0,0,R21,0,0,0,0,0,0,0,0,0,0,0,0,0,0,0,0,0,0,0,0~
,0,0,0,0,0,0,0,0,0,0,0,0)';
      BIDIRECTIONAL='TRUE';
      INPUT_LOAD='(-0.01,0.01)';
      OUTPUT_LOAD='(1.0,-1.0)';
      PINUSE='BI';
    'DDR2_SB_DQS_DN1':
      PIN_NUMBER='(0,0,0,0,0,0,0,0,0,AB30,0,0,0,0,0,0,0,0,0,0,0,0,0,0,0,0,0,0,0,~
0,0,0,0,0,0,0,0,0,0,0,0,0)';
      BIDIRECTIONAL='TRUE';
      INPUT_LOAD='(-0.01,0.01)';
      OUTPUT_LOAD='(1.0,-1.0)';
      PINUSE='BI';
    'DDR2_SB_DQS_DN0':
      PIN_NUMBER='(0,0,0,0,0,0,0,0,0,AB36,0,0,0,0,0,0,0,0,0,0,0,0,0,0,0,0,0,0,0,~
0,0,0,0,0,0,0,0,0,0,0,0,0)';
      BIDIRECTIONAL='TRUE';
      INPUT_LOAD='(-0.01,0.01)';
      OUTPUT_LOAD='(1.0,-1.0)';
      PINUSE='BI';
    'DDR2_SB_DQS_DP9':
      PIN_NUMBER='(0,0,0,0,0,0,0,0,0,U33,0,0,0,0,0,0,0,0,0,0,0,0,0,0,0,0,0,0,0,0~
,0,0,0,0,0,0,0,0,0,0,0,0)';
      BIDIRECTIONAL='TRUE';
      INPUT_LOAD='(-0.01,0.01)';
      OUTPUT_LOAD='(1.0,-1.0)';
      PINUSE='BI';
    'DDR2_SB_DQS_DP8':
      PIN_NUMBER='(0,0,0,0,0,0,0,0,0,AH18,0,0,0,0,0,0,0,0,0,0,0,0,0,0,0,0,0,0,0,~
0,0,0,0,0,0,0,0,0,0,0,0,0)';
      BIDIRECTIONAL='TRUE';
      INPUT_LOAD='(-0.01,0.01)';
      OUTPUT_LOAD='(1.0,-1.0)';
      PINUSE='BI';
    'DDR2_SB_DQS_DP7':
      PIN_NUMBER='(0,0,0,0,0,0,0,0,0,AA21,0,0,0,0,0,0,0,0,0,0,0,0,0,0,0,0,0,0,0,~
0,0,0,0,0,0,0,0,0,0,0,0,0)';
      BIDIRECTIONAL='TRUE';
      INPUT_LOAD='(-0.01,0.01)';
      OUTPUT_LOAD='(1.0,-1.0)';
      PINUSE='BI';
    'DDR2_SB_DQS_DP6':
      PIN_NUMBER='(0,0,0,0,0,0,0,0,0,AH30,0,0,0,0,0,0,0,0,0,0,0,0,0,0,0,0,0,0,0,~
0,0,0,0,0,0,0,0,0,0,0,0,0)';
      BIDIRECTIONAL='TRUE';
      INPUT_LOAD='(-0.01,0.01)';
      OUTPUT_LOAD='(1.0,-1.0)';
      PINUSE='BI';
    'DDR2_SB_DQS_DP5':
      PIN_NUMBER='(0,0,0,0,0,0,0,0,0,AH36,0,0,0,0,0,0,0,0,0,0,0,0,0,0,0,0,0,0,0,~
0,0,0,0,0,0,0,0,0,0,0,0,0)';
      BIDIRECTIONAL='TRUE';
      INPUT_LOAD='(-0.01,0.01)';
      OUTPUT_LOAD='(1.0,-1.0)';
      PINUSE='BI';
    'DDR2_SB_DQS_DP4':
      PIN_NUMBER='(0,0,0,0,0,0,0,0,0,AA33,0,0,0,0,0,0,0,0,0,0,0,0,0,0,0,0,0,0,0,~
0,0,0,0,0,0,0,0,0,0,0,0,0)';
      BIDIRECTIONAL='TRUE';
      INPUT_LOAD='(-0.01,0.01)';
      OUTPUT_LOAD='(1.0,-1.0)';
      PINUSE='BI';
    'DDR2_SB_DQS_DP3':
      PIN_NUMBER='(0,0,0,0,0,0,0,0,0,AD18,0,0,0,0,0,0,0,0,0,0,0,0,0,0,0,0,0,0,0,~
0,0,0,0,0,0,0,0,0,0,0,0,0)';
      BIDIRECTIONAL='TRUE';
      INPUT_LOAD='(-0.01,0.01)';
      OUTPUT_LOAD='(1.0,-1.0)';
      PINUSE='BI';
    'DDR2_SB_DQS_DP2':
      PIN_NUMBER='(0,0,0,0,0,0,0,0,0,U21,0,0,0,0,0,0,0,0,0,0,0,0,0,0,0,0,0,0,0,0~
,0,0,0,0,0,0,0,0,0,0,0,0)';
      BIDIRECTIONAL='TRUE';
      INPUT_LOAD='(-0.01,0.01)';
      OUTPUT_LOAD='(1.0,-1.0)';
      PINUSE='BI';
    'DDR2_SB_DQS_DP1':
      PIN_NUMBER='(0,0,0,0,0,0,0,0,0,AD30,0,0,0,0,0,0,0,0,0,0,0,0,0,0,0,0,0,0,0,~
0,0,0,0,0,0,0,0,0,0,0,0,0)';
      BIDIRECTIONAL='TRUE';
      INPUT_LOAD='(-0.01,0.01)';
      OUTPUT_LOAD='(1.0,-1.0)';
      PINUSE='BI';
    'DDR2_SB_DQS_DP0':
      PIN_NUMBER='(0,0,0,0,0,0,0,0,0,AD36,0,0,0,0,0,0,0,0,0,0,0,0,0,0,0,0,0,0,0,~
0,0,0,0,0,0,0,0,0,0,0,0,0)';
      BIDIRECTIONAL='TRUE';
      INPUT_LOAD='(-0.01,0.01)';
      OUTPUT_LOAD='(1.0,-1.0)';
      PINUSE='BI';
    'DDR2_SB_ECC7':
      PIN_NUMBER='(0,0,0,0,0,0,0,0,0,Y34,0,0,0,0,0,0,0,0,0,0,0,0,0,0,0,0,0,0,0,0~
,0,0,0,0,0,0,0,0,0,0,0,0)';
      BIDIRECTIONAL='TRUE';
      INPUT_LOAD='(-0.01,0.01)';
      OUTPUT_LOAD='(1.0,-1.0)';
      PINUSE='BI';
    'DDR2_SB_ECC6':
      PIN_NUMBER='(0,0,0,0,0,0,0,0,0,W35,0,0,0,0,0,0,0,0,0,0,0,0,0,0,0,0,0,0,0,0~
,0,0,0,0,0,0,0,0,0,0,0,0)';
      BIDIRECTIONAL='TRUE';
      INPUT_LOAD='(-0.01,0.01)';
      OUTPUT_LOAD='(1.0,-1.0)';
      PINUSE='BI';
    'DDR2_SB_ECC5':
      PIN_NUMBER='(0,0,0,0,0,0,0,0,0,T34,0,0,0,0,0,0,0,0,0,0,0,0,0,0,0,0,0,0,0,0~
,0,0,0,0,0,0,0,0,0,0,0,0)';
      BIDIRECTIONAL='TRUE';
      INPUT_LOAD='(-0.01,0.01)';
      OUTPUT_LOAD='(1.0,-1.0)';
      PINUSE='BI';
    'DDR2_SB_ECC4':
      PIN_NUMBER='(0,0,0,0,0,0,0,0,0,U35,0,0,0,0,0,0,0,0,0,0,0,0,0,0,0,0,0,0,0,0~
,0,0,0,0,0,0,0,0,0,0,0,0)';
      BIDIRECTIONAL='TRUE';
      INPUT_LOAD='(-0.01,0.01)';
      OUTPUT_LOAD='(1.0,-1.0)';
      PINUSE='BI';
    'DDR2_SB_ECC3':
      PIN_NUMBER='(0,0,0,0,0,0,0,0,0,W31,0,0,0,0,0,0,0,0,0,0,0,0,0,0,0,0,0,0,0,0~
,0,0,0,0,0,0,0,0,0,0,0,0)';
      BIDIRECTIONAL='TRUE';
      INPUT_LOAD='(-0.01,0.01)';
      OUTPUT_LOAD='(1.0,-1.0)';
      PINUSE='BI';
    'DDR2_SB_ECC2':
      PIN_NUMBER='(0,0,0,0,0,0,0,0,0,Y32,0,0,0,0,0,0,0,0,0,0,0,0,0,0,0,0,0,0,0,0~
,0,0,0,0,0,0,0,0,0,0,0,0)';
      BIDIRECTIONAL='TRUE';
      INPUT_LOAD='(-0.01,0.01)';
      OUTPUT_LOAD='(1.0,-1.0)';
      PINUSE='BI';
    'DDR2_SB_ECC1':
      PIN_NUMBER='(0,0,0,0,0,0,0,0,0,U31,0,0,0,0,0,0,0,0,0,0,0,0,0,0,0,0,0,0,0,0~
,0,0,0,0,0,0,0,0,0,0,0,0)';
      BIDIRECTIONAL='TRUE';
      INPUT_LOAD='(-0.01,0.01)';
      OUTPUT_LOAD='(1.0,-1.0)';
      PINUSE='BI';
    'DDR2_SB_ECC0':
      PIN_NUMBER='(0,0,0,0,0,0,0,0,0,T32,0,0,0,0,0,0,0,0,0,0,0,0,0,0,0,0,0,0,0,0~
,0,0,0,0,0,0,0,0,0,0,0,0)';
      BIDIRECTIONAL='TRUE';
      INPUT_LOAD='(-0.01,0.01)';
      OUTPUT_LOAD='(1.0,-1.0)';
      PINUSE='BI';
    'DDR2_SB_PAR':
      PIN_NUMBER='(0,0,0,0,0,0,0,0,0,AA39,0,0,0,0,0,0,0,0,0,0,0,0,0,0,0,0,0,0,0,~
0,0,0,0,0,0,0,0,0,0,0,0,0)';
      OUTPUT_LOAD='(1.0,-1.0)';
      PINUSE='OUT';
    'DDR3_ALERT_N':
      PIN_NUMBER='(0,0,0,0,0,0,0,0,0,0,AV47,0,0,0,0,0,0,0,0,0,0,0,0,0,0,0,0,0,0,~
0,0,0,0,0,0,0,0,0,0,0,0,0)';
      INPUT_LOAD='(-0.01,0.01)';
      PINUSE='IN';
    'DDR3_A_RSP1':
      PIN_NUMBER='(0,0,0,0,0,0,0,0,0,0,AC50,0,0,0,0,0,0,0,0,0,0,0,0,0,0,0,0,0,0,~
0,0,0,0,0,0,0,0,0,0,0,0,0)';
      INPUT_LOAD='(-0.01,0.01)';
      PINUSE='IN';
    'DDR3_A_RSP0':
      PIN_NUMBER='(0,0,0,0,0,0,0,0,0,0,AD51,0,0,0,0,0,0,0,0,0,0,0,0,0,0,0,0,0,0,~
0,0,0,0,0,0,0,0,0,0,0,0,0)';
      INPUT_LOAD='(-0.01,0.01)';
      PINUSE='IN';
    'DDR3_B_RSP1':
      PIN_NUMBER='(0,0,0,0,0,0,0,0,0,0,AG50,0,0,0,0,0,0,0,0,0,0,0,0,0,0,0,0,0,0,~
0,0,0,0,0,0,0,0,0,0,0,0,0)';
      INPUT_LOAD='(-0.01,0.01)';
      PINUSE='IN';
    'DDR3_B_RSP0':
      PIN_NUMBER='(0,0,0,0,0,0,0,0,0,0,AF51,0,0,0,0,0,0,0,0,0,0,0,0,0,0,0,0,0,0,~
0,0,0,0,0,0,0,0,0,0,0,0,0)';
      INPUT_LOAD='(-0.01,0.01)';
      PINUSE='IN';
    'DDR3_CLK_DN1':
      PIN_NUMBER='(0,0,0,0,0,0,0,0,0,0,AN45,0,0,0,0,0,0,0,0,0,0,0,0,0,0,0,0,0,0,~
0,0,0,0,0,0,0,0,0,0,0,0,0)';
      OUTPUT_LOAD='(1.0,-1.0)';
      PINUSE='OUT';
    'DDR3_CLK_DN0':
      PIN_NUMBER='(0,0,0,0,0,0,0,0,0,0,AJ45,0,0,0,0,0,0,0,0,0,0,0,0,0,0,0,0,0,0,~
0,0,0,0,0,0,0,0,0,0,0,0,0)';
      OUTPUT_LOAD='(1.0,-1.0)';
      PINUSE='OUT';
    'DDR3_CLK_DP1':
      PIN_NUMBER='(0,0,0,0,0,0,0,0,0,0,AR45,0,0,0,0,0,0,0,0,0,0,0,0,0,0,0,0,0,0,~
0,0,0,0,0,0,0,0,0,0,0,0,0)';
      OUTPUT_LOAD='(1.0,-1.0)';
      PINUSE='OUT';
    'DDR3_CLK_DP0':
      PIN_NUMBER='(0,0,0,0,0,0,0,0,0,0,AL45,0,0,0,0,0,0,0,0,0,0,0,0,0,0,0,0,0,0,~
0,0,0,0,0,0,0,0,0,0,0,0,0)';
      OUTPUT_LOAD='(1.0,-1.0)';
      PINUSE='OUT';
    'DDR3_SA_CA6':
      PIN_NUMBER='(0,0,0,0,0,0,0,0,0,0,AN43,0,0,0,0,0,0,0,0,0,0,0,0,0,0,0,0,0,0,~
0,0,0,0,0,0,0,0,0,0,0,0,0)';
      OUTPUT_LOAD='(1.0,-1.0)';
      PINUSE='OUT';
    'DDR3_SA_CA5':
      PIN_NUMBER='(0,0,0,0,0,0,0,0,0,0,AN50,0,0,0,0,0,0,0,0,0,0,0,0,0,0,0,0,0,0,~
0,0,0,0,0,0,0,0,0,0,0,0,0)';
      OUTPUT_LOAD='(1.0,-1.0)';
      PINUSE='OUT';
    'DDR3_SA_CA4':
      PIN_NUMBER='(0,0,0,0,0,0,0,0,0,0,AL50,0,0,0,0,0,0,0,0,0,0,0,0,0,0,0,0,0,0,~
0,0,0,0,0,0,0,0,0,0,0,0,0)';
      OUTPUT_LOAD='(1.0,-1.0)';
      PINUSE='OUT';
    'DDR3_SA_CA3':
      PIN_NUMBER='(0,0,0,0,0,0,0,0,0,0,AP51,0,0,0,0,0,0,0,0,0,0,0,0,0,0,0,0,0,0,~
0,0,0,0,0,0,0,0,0,0,0,0,0)';
      OUTPUT_LOAD='(1.0,-1.0)';
      PINUSE='OUT';
    'DDR3_SA_CA2':
      PIN_NUMBER='(0,0,0,0,0,0,0,0,0,0,AK51,0,0,0,0,0,0,0,0,0,0,0,0,0,0,0,0,0,0,~
0,0,0,0,0,0,0,0,0,0,0,0,0)';
      OUTPUT_LOAD='(1.0,-1.0)';
      PINUSE='OUT';
    'DDR3_SA_CA1':
      PIN_NUMBER='(0,0,0,0,0,0,0,0,0,0,AR52,0,0,0,0,0,0,0,0,0,0,0,0,0,0,0,0,0,0,~
0,0,0,0,0,0,0,0,0,0,0,0,0)';
      OUTPUT_LOAD='(1.0,-1.0)';
      PINUSE='OUT';
    'DDR3_SA_CA0':
      PIN_NUMBER='(0,0,0,0,0,0,0,0,0,0,AJ52,0,0,0,0,0,0,0,0,0,0,0,0,0,0,0,0,0,0,~
0,0,0,0,0,0,0,0,0,0,0,0,0)';
      OUTPUT_LOAD='(1.0,-1.0)';
      PINUSE='OUT';
    'DDR3_SA_CS_N3':
      PIN_NUMBER='(0,0,0,0,0,0,0,0,0,0,AP53,0,0,0,0,0,0,0,0,0,0,0,0,0,0,0,0,0,0,~
0,0,0,0,0,0,0,0,0,0,0,0,0)';
      OUTPUT_LOAD='(1.0,-1.0)';
      PINUSE='OUT';
    'DDR3_SA_CS_N2':
      PIN_NUMBER='(0,0,0,0,0,0,0,0,0,0,AN54,0,0,0,0,0,0,0,0,0,0,0,0,0,0,0,0,0,0,~
0,0,0,0,0,0,0,0,0,0,0,0,0)';
      OUTPUT_LOAD='(1.0,-1.0)';
      PINUSE='OUT';
    'DDR3_SA_CS_N1':
      PIN_NUMBER='(0,0,0,0,0,0,0,0,0,0,AK53,0,0,0,0,0,0,0,0,0,0,0,0,0,0,0,0,0,0,~
0,0,0,0,0,0,0,0,0,0,0,0,0)';
      OUTPUT_LOAD='(1.0,-1.0)';
      PINUSE='OUT';
    'DDR3_SA_CS_N0':
      PIN_NUMBER='(0,0,0,0,0,0,0,0,0,0,AL54,0,0,0,0,0,0,0,0,0,0,0,0,0,0,0,0,0,0,~
0,0,0,0,0,0,0,0,0,0,0,0,0)';
      OUTPUT_LOAD='(1.0,-1.0)';
      PINUSE='OUT';
    'DDR3_SA_DQ31':
      PIN_NUMBER='(0,0,0,0,0,0,0,0,0,0,AN62,0,0,0,0,0,0,0,0,0,0,0,0,0,0,0,0,0,0,~
0,0,0,0,0,0,0,0,0,0,0,0,0)';
      BIDIRECTIONAL='TRUE';
      INPUT_LOAD='(-0.01,0.01)';
      OUTPUT_LOAD='(1.0,-1.0)';
      PINUSE='BI';
    'DDR3_SA_DQ30':
      PIN_NUMBER='(0,0,0,0,0,0,0,0,0,0,AP63,0,0,0,0,0,0,0,0,0,0,0,0,0,0,0,0,0,0,~
0,0,0,0,0,0,0,0,0,0,0,0,0)';
      BIDIRECTIONAL='TRUE';
      INPUT_LOAD='(-0.01,0.01)';
      OUTPUT_LOAD='(1.0,-1.0)';
      PINUSE='BI';
    'DDR3_SA_DQ29':
      PIN_NUMBER='(0,0,0,0,0,0,0,0,0,0,AL62,0,0,0,0,0,0,0,0,0,0,0,0,0,0,0,0,0,0,~
0,0,0,0,0,0,0,0,0,0,0,0,0)';
      BIDIRECTIONAL='TRUE';
      INPUT_LOAD='(-0.01,0.01)';
      OUTPUT_LOAD='(1.0,-1.0)';
      PINUSE='BI';
    'DDR3_SA_DQ28':
      PIN_NUMBER='(0,0,0,0,0,0,0,0,0,0,AK63,0,0,0,0,0,0,0,0,0,0,0,0,0,0,0,0,0,0,~
0,0,0,0,0,0,0,0,0,0,0,0,0)';
      BIDIRECTIONAL='TRUE';
      INPUT_LOAD='(-0.01,0.01)';
      OUTPUT_LOAD='(1.0,-1.0)';
      PINUSE='BI';
    'DDR3_SA_DQ27':
      PIN_NUMBER='(0,0,0,0,0,0,0,0,0,0,AP65,0,0,0,0,0,0,0,0,0,0,0,0,0,0,0,0,0,0,~
0,0,0,0,0,0,0,0,0,0,0,0,0)';
      BIDIRECTIONAL='TRUE';
      INPUT_LOAD='(-0.01,0.01)';
      OUTPUT_LOAD='(1.0,-1.0)';
      PINUSE='BI';
    'DDR3_SA_DQ26':
      PIN_NUMBER='(0,0,0,0,0,0,0,0,0,0,AN66,0,0,0,0,0,0,0,0,0,0,0,0,0,0,0,0,0,0,~
0,0,0,0,0,0,0,0,0,0,0,0,0)';
      BIDIRECTIONAL='TRUE';
      INPUT_LOAD='(-0.01,0.01)';
      OUTPUT_LOAD='(1.0,-1.0)';
      PINUSE='BI';
    'DDR3_SA_DQ25':
      PIN_NUMBER='(0,0,0,0,0,0,0,0,0,0,AK65,0,0,0,0,0,0,0,0,0,0,0,0,0,0,0,0,0,0,~
0,0,0,0,0,0,0,0,0,0,0,0,0)';
      BIDIRECTIONAL='TRUE';
      INPUT_LOAD='(-0.01,0.01)';
      OUTPUT_LOAD='(1.0,-1.0)';
      PINUSE='BI';
    'DDR3_SA_DQ24':
      PIN_NUMBER='(0,0,0,0,0,0,0,0,0,0,AL66,0,0,0,0,0,0,0,0,0,0,0,0,0,0,0,0,0,0,~
0,0,0,0,0,0,0,0,0,0,0,0,0)';
      BIDIRECTIONAL='TRUE';
      INPUT_LOAD='(-0.01,0.01)';
      OUTPUT_LOAD='(1.0,-1.0)';
      PINUSE='BI';
    'DDR3_SA_DQ23':
      PIN_NUMBER='(0,0,0,0,0,0,0,0,0,0,AN68,0,0,0,0,0,0,0,0,0,0,0,0,0,0,0,0,0,0,~
0,0,0,0,0,0,0,0,0,0,0,0,0)';
      BIDIRECTIONAL='TRUE';
      INPUT_LOAD='(-0.01,0.01)';
      OUTPUT_LOAD='(1.0,-1.0)';
      PINUSE='BI';
    'DDR3_SA_DQ22':
      PIN_NUMBER='(0,0,0,0,0,0,0,0,0,0,AP69,0,0,0,0,0,0,0,0,0,0,0,0,0,0,0,0,0,0,~
0,0,0,0,0,0,0,0,0,0,0,0,0)';
      BIDIRECTIONAL='TRUE';
      INPUT_LOAD='(-0.01,0.01)';
      OUTPUT_LOAD='(1.0,-1.0)';
      PINUSE='BI';
    'DDR3_SA_DQ21':
      PIN_NUMBER='(0,0,0,0,0,0,0,0,0,0,AL68,0,0,0,0,0,0,0,0,0,0,0,0,0,0,0,0,0,0,~
0,0,0,0,0,0,0,0,0,0,0,0,0)';
      BIDIRECTIONAL='TRUE';
      INPUT_LOAD='(-0.01,0.01)';
      OUTPUT_LOAD='(1.0,-1.0)';
      PINUSE='BI';
    'DDR3_SA_DQ20':
      PIN_NUMBER='(0,0,0,0,0,0,0,0,0,0,AK69,0,0,0,0,0,0,0,0,0,0,0,0,0,0,0,0,0,0,~
0,0,0,0,0,0,0,0,0,0,0,0,0)';
      BIDIRECTIONAL='TRUE';
      INPUT_LOAD='(-0.01,0.01)';
      OUTPUT_LOAD='(1.0,-1.0)';
      PINUSE='BI';
    'DDR3_SA_DQ19':
      PIN_NUMBER='(0,0,0,0,0,0,0,0,0,0,AP71,0,0,0,0,0,0,0,0,0,0,0,0,0,0,0,0,0,0,~
0,0,0,0,0,0,0,0,0,0,0,0,0)';
      BIDIRECTIONAL='TRUE';
      INPUT_LOAD='(-0.01,0.01)';
      OUTPUT_LOAD='(1.0,-1.0)';
      PINUSE='BI';
    'DDR3_SA_DQ18':
      PIN_NUMBER='(0,0,0,0,0,0,0,0,0,0,AN72,0,0,0,0,0,0,0,0,0,0,0,0,0,0,0,0,0,0,~
0,0,0,0,0,0,0,0,0,0,0,0,0)';
      BIDIRECTIONAL='TRUE';
      INPUT_LOAD='(-0.01,0.01)';
      OUTPUT_LOAD='(1.0,-1.0)';
      PINUSE='BI';
    'DDR3_SA_DQ17':
      PIN_NUMBER='(0,0,0,0,0,0,0,0,0,0,AK71,0,0,0,0,0,0,0,0,0,0,0,0,0,0,0,0,0,0,~
0,0,0,0,0,0,0,0,0,0,0,0,0)';
      BIDIRECTIONAL='TRUE';
      INPUT_LOAD='(-0.01,0.01)';
      OUTPUT_LOAD='(1.0,-1.0)';
      PINUSE='BI';
    'DDR3_SA_DQ16':
      PIN_NUMBER='(0,0,0,0,0,0,0,0,0,0,AL72,0,0,0,0,0,0,0,0,0,0,0,0,0,0,0,0,0,0,~
0,0,0,0,0,0,0,0,0,0,0,0,0)';
      BIDIRECTIONAL='TRUE';
      INPUT_LOAD='(-0.01,0.01)';
      OUTPUT_LOAD='(1.0,-1.0)';
      PINUSE='BI';
    'DDR3_SA_DQ15':
      PIN_NUMBER='(0,0,0,0,0,0,0,0,0,0,AN74,0,0,0,0,0,0,0,0,0,0,0,0,0,0,0,0,0,0,~
0,0,0,0,0,0,0,0,0,0,0,0,0)';
      BIDIRECTIONAL='TRUE';
      INPUT_LOAD='(-0.01,0.01)';
      OUTPUT_LOAD='(1.0,-1.0)';
      PINUSE='BI';
    'DDR3_SA_DQ14':
      PIN_NUMBER='(0,0,0,0,0,0,0,0,0,0,AP75,0,0,0,0,0,0,0,0,0,0,0,0,0,0,0,0,0,0,~
0,0,0,0,0,0,0,0,0,0,0,0,0)';
      BIDIRECTIONAL='TRUE';
      INPUT_LOAD='(-0.01,0.01)';
      OUTPUT_LOAD='(1.0,-1.0)';
      PINUSE='BI';
    'DDR3_SA_DQ13':
      PIN_NUMBER='(0,0,0,0,0,0,0,0,0,0,AL74,0,0,0,0,0,0,0,0,0,0,0,0,0,0,0,0,0,0,~
0,0,0,0,0,0,0,0,0,0,0,0,0)';
      BIDIRECTIONAL='TRUE';
      INPUT_LOAD='(-0.01,0.01)';
      OUTPUT_LOAD='(1.0,-1.0)';
      PINUSE='BI';
    'DDR3_SA_DQ12':
      PIN_NUMBER='(0,0,0,0,0,0,0,0,0,0,AK75,0,0,0,0,0,0,0,0,0,0,0,0,0,0,0,0,0,0,~
0,0,0,0,0,0,0,0,0,0,0,0,0)';
      BIDIRECTIONAL='TRUE';
      INPUT_LOAD='(-0.01,0.01)';
      OUTPUT_LOAD='(1.0,-1.0)';
      PINUSE='BI';
    'DDR3_SA_DQ11':
      PIN_NUMBER='(0,0,0,0,0,0,0,0,0,0,AP77,0,0,0,0,0,0,0,0,0,0,0,0,0,0,0,0,0,0,~
0,0,0,0,0,0,0,0,0,0,0,0,0)';
      BIDIRECTIONAL='TRUE';
      INPUT_LOAD='(-0.01,0.01)';
      OUTPUT_LOAD='(1.0,-1.0)';
      PINUSE='BI';
    'DDR3_SA_DQ10':
      PIN_NUMBER='(0,0,0,0,0,0,0,0,0,0,AN78,0,0,0,0,0,0,0,0,0,0,0,0,0,0,0,0,0,0,~
0,0,0,0,0,0,0,0,0,0,0,0,0)';
      BIDIRECTIONAL='TRUE';
      INPUT_LOAD='(-0.01,0.01)';
      OUTPUT_LOAD='(1.0,-1.0)';
      PINUSE='BI';
    'DDR3_SA_DQ9':
      PIN_NUMBER='(0,0,0,0,0,0,0,0,0,0,AK77,0,0,0,0,0,0,0,0,0,0,0,0,0,0,0,0,0,0,~
0,0,0,0,0,0,0,0,0,0,0,0,0)';
      BIDIRECTIONAL='TRUE';
      INPUT_LOAD='(-0.01,0.01)';
      OUTPUT_LOAD='(1.0,-1.0)';
      PINUSE='BI';
    'DDR3_SA_DQ8':
      PIN_NUMBER='(0,0,0,0,0,0,0,0,0,0,AL78,0,0,0,0,0,0,0,0,0,0,0,0,0,0,0,0,0,0,~
0,0,0,0,0,0,0,0,0,0,0,0,0)';
      BIDIRECTIONAL='TRUE';
      INPUT_LOAD='(-0.01,0.01)';
      OUTPUT_LOAD='(1.0,-1.0)';
      PINUSE='BI';
    'DDR3_SA_DQ7':
      PIN_NUMBER='(0,0,0,0,0,0,0,0,0,0,AF71,0,0,0,0,0,0,0,0,0,0,0,0,0,0,0,0,0,0,~
0,0,0,0,0,0,0,0,0,0,0,0,0)';
      BIDIRECTIONAL='TRUE';
      INPUT_LOAD='(-0.01,0.01)';
      OUTPUT_LOAD='(1.0,-1.0)';
      PINUSE='BI';
    'DDR3_SA_DQ6':
      PIN_NUMBER='(0,0,0,0,0,0,0,0,0,0,AG72,0,0,0,0,0,0,0,0,0,0,0,0,0,0,0,0,0,0,~
0,0,0,0,0,0,0,0,0,0,0,0,0)';
      BIDIRECTIONAL='TRUE';
      INPUT_LOAD='(-0.01,0.01)';
      OUTPUT_LOAD='(1.0,-1.0)';
      PINUSE='BI';
    'DDR3_SA_DQ5':
      PIN_NUMBER='(0,0,0,0,0,0,0,0,0,0,AD71,0,0,0,0,0,0,0,0,0,0,0,0,0,0,0,0,0,0,~
0,0,0,0,0,0,0,0,0,0,0,0,0)';
      BIDIRECTIONAL='TRUE';
      INPUT_LOAD='(-0.01,0.01)';
      OUTPUT_LOAD='(1.0,-1.0)';
      PINUSE='BI';
    'DDR3_SA_DQ4':
      PIN_NUMBER='(0,0,0,0,0,0,0,0,0,0,AC72,0,0,0,0,0,0,0,0,0,0,0,0,0,0,0,0,0,0,~
0,0,0,0,0,0,0,0,0,0,0,0,0)';
      BIDIRECTIONAL='TRUE';
      INPUT_LOAD='(-0.01,0.01)';
      OUTPUT_LOAD='(1.0,-1.0)';
      PINUSE='BI';
    'DDR3_SA_DQ3':
      PIN_NUMBER='(0,0,0,0,0,0,0,0,0,0,AG74,0,0,0,0,0,0,0,0,0,0,0,0,0,0,0,0,0,0,~
0,0,0,0,0,0,0,0,0,0,0,0,0)';
      BIDIRECTIONAL='TRUE';
      INPUT_LOAD='(-0.01,0.01)';
      OUTPUT_LOAD='(1.0,-1.0)';
      PINUSE='BI';
    'DDR3_SA_DQ2':
      PIN_NUMBER='(0,0,0,0,0,0,0,0,0,0,AF75,0,0,0,0,0,0,0,0,0,0,0,0,0,0,0,0,0,0,~
0,0,0,0,0,0,0,0,0,0,0,0,0)';
      BIDIRECTIONAL='TRUE';
      INPUT_LOAD='(-0.01,0.01)';
      OUTPUT_LOAD='(1.0,-1.0)';
      PINUSE='BI';
    'DDR3_SA_DQ1':
      PIN_NUMBER='(0,0,0,0,0,0,0,0,0,0,AC74,0,0,0,0,0,0,0,0,0,0,0,0,0,0,0,0,0,0,~
0,0,0,0,0,0,0,0,0,0,0,0,0)';
      BIDIRECTIONAL='TRUE';
      INPUT_LOAD='(-0.01,0.01)';
      OUTPUT_LOAD='(1.0,-1.0)';
      PINUSE='BI';
    'DDR3_SA_DQ0':
      PIN_NUMBER='(0,0,0,0,0,0,0,0,0,0,AD75,0,0,0,0,0,0,0,0,0,0,0,0,0,0,0,0,0,0,~
0,0,0,0,0,0,0,0,0,0,0,0,0)';
      BIDIRECTIONAL='TRUE';
      INPUT_LOAD='(-0.01,0.01)';
      OUTPUT_LOAD='(1.0,-1.0)';
      PINUSE='BI';
    'DDR3_SA_DQS_DN9':
      PIN_NUMBER='(0,0,0,0,0,0,0,0,0,0,AN58,0,0,0,0,0,0,0,0,0,0,0,0,0,0,0,0,0,0,~
0,0,0,0,0,0,0,0,0,0,0,0,0)';
      BIDIRECTIONAL='TRUE';
      INPUT_LOAD='(-0.01,0.01)';
      OUTPUT_LOAD='(1.0,-1.0)';
      PINUSE='BI';
    'DDR3_SA_DQS_DN8':
      PIN_NUMBER='(0,0,0,0,0,0,0,0,0,0,AN64,0,0,0,0,0,0,0,0,0,0,0,0,0,0,0,0,0,0,~
0,0,0,0,0,0,0,0,0,0,0,0,0)';
      BIDIRECTIONAL='TRUE';
      INPUT_LOAD='(-0.01,0.01)';
      OUTPUT_LOAD='(1.0,-1.0)';
      PINUSE='BI';
    'DDR3_SA_DQS_DN7':
      PIN_NUMBER='(0,0,0,0,0,0,0,0,0,0,AN70,0,0,0,0,0,0,0,0,0,0,0,0,0,0,0,0,0,0,~
0,0,0,0,0,0,0,0,0,0,0,0,0)';
      BIDIRECTIONAL='TRUE';
      INPUT_LOAD='(-0.01,0.01)';
      OUTPUT_LOAD='(1.0,-1.0)';
      PINUSE='BI';
    'DDR3_SA_DQS_DN6':
      PIN_NUMBER='(0,0,0,0,0,0,0,0,0,0,AN76,0,0,0,0,0,0,0,0,0,0,0,0,0,0,0,0,0,0,~
0,0,0,0,0,0,0,0,0,0,0,0,0)';
      BIDIRECTIONAL='TRUE';
      INPUT_LOAD='(-0.01,0.01)';
      OUTPUT_LOAD='(1.0,-1.0)';
      PINUSE='BI';
    'DDR3_SA_DQS_DN5':
      PIN_NUMBER='(0,0,0,0,0,0,0,0,0,0,AH73,0,0,0,0,0,0,0,0,0,0,0,0,0,0,0,0,0,0,~
0,0,0,0,0,0,0,0,0,0,0,0,0)';
      BIDIRECTIONAL='TRUE';
      INPUT_LOAD='(-0.01,0.01)';
      OUTPUT_LOAD='(1.0,-1.0)';
      PINUSE='BI';
    'DDR3_SA_DQS_DN4':
      PIN_NUMBER='(0,0,0,0,0,0,0,0,0,0,AJ58,0,0,0,0,0,0,0,0,0,0,0,0,0,0,0,0,0,0,~
0,0,0,0,0,0,0,0,0,0,0,0,0)';
      BIDIRECTIONAL='TRUE';
      INPUT_LOAD='(-0.01,0.01)';
      OUTPUT_LOAD='(1.0,-1.0)';
      PINUSE='BI';
    'DDR3_SA_DQS_DN3':
      PIN_NUMBER='(0,0,0,0,0,0,0,0,0,0,AJ64,0,0,0,0,0,0,0,0,0,0,0,0,0,0,0,0,0,0,~
0,0,0,0,0,0,0,0,0,0,0,0,0)';
      BIDIRECTIONAL='TRUE';
      INPUT_LOAD='(-0.01,0.01)';
      OUTPUT_LOAD='(1.0,-1.0)';
      PINUSE='BI';
    'DDR3_SA_DQS_DN2':
      PIN_NUMBER='(0,0,0,0,0,0,0,0,0,0,AJ70,0,0,0,0,0,0,0,0,0,0,0,0,0,0,0,0,0,0,~
0,0,0,0,0,0,0,0,0,0,0,0,0)';
      BIDIRECTIONAL='TRUE';
      INPUT_LOAD='(-0.01,0.01)';
      OUTPUT_LOAD='(1.0,-1.0)';
      PINUSE='BI';
    'DDR3_SA_DQS_DN1':
      PIN_NUMBER='(0,0,0,0,0,0,0,0,0,0,AJ76,0,0,0,0,0,0,0,0,0,0,0,0,0,0,0,0,0,0,~
0,0,0,0,0,0,0,0,0,0,0,0,0)';
      BIDIRECTIONAL='TRUE';
      INPUT_LOAD='(-0.01,0.01)';
      OUTPUT_LOAD='(1.0,-1.0)';
      PINUSE='BI';
    'DDR3_SA_DQS_DN0':
      PIN_NUMBER='(0,0,0,0,0,0,0,0,0,0,AB73,0,0,0,0,0,0,0,0,0,0,0,0,0,0,0,0,0,0,~
0,0,0,0,0,0,0,0,0,0,0,0,0)';
      BIDIRECTIONAL='TRUE';
      INPUT_LOAD='(-0.01,0.01)';
      OUTPUT_LOAD='(1.0,-1.0)';
      PINUSE='BI';
    'DDR3_SA_DQS_DP9':
      PIN_NUMBER='(0,0,0,0,0,0,0,0,0,0,AR58,0,0,0,0,0,0,0,0,0,0,0,0,0,0,0,0,0,0,~
0,0,0,0,0,0,0,0,0,0,0,0,0)';
      BIDIRECTIONAL='TRUE';
      INPUT_LOAD='(-0.01,0.01)';
      OUTPUT_LOAD='(1.0,-1.0)';
      PINUSE='BI';
    'DDR3_SA_DQS_DP8':
      PIN_NUMBER='(0,0,0,0,0,0,0,0,0,0,AR64,0,0,0,0,0,0,0,0,0,0,0,0,0,0,0,0,0,0,~
0,0,0,0,0,0,0,0,0,0,0,0,0)';
      BIDIRECTIONAL='TRUE';
      INPUT_LOAD='(-0.01,0.01)';
      OUTPUT_LOAD='(1.0,-1.0)';
      PINUSE='BI';
    'DDR3_SA_DQS_DP7':
      PIN_NUMBER='(0,0,0,0,0,0,0,0,0,0,AR70,0,0,0,0,0,0,0,0,0,0,0,0,0,0,0,0,0,0,~
0,0,0,0,0,0,0,0,0,0,0,0,0)';
      BIDIRECTIONAL='TRUE';
      INPUT_LOAD='(-0.01,0.01)';
      OUTPUT_LOAD='(1.0,-1.0)';
      PINUSE='BI';
    'DDR3_SA_DQS_DP6':
      PIN_NUMBER='(0,0,0,0,0,0,0,0,0,0,AR76,0,0,0,0,0,0,0,0,0,0,0,0,0,0,0,0,0,0,~
0,0,0,0,0,0,0,0,0,0,0,0,0)';
      BIDIRECTIONAL='TRUE';
      INPUT_LOAD='(-0.01,0.01)';
      OUTPUT_LOAD='(1.0,-1.0)';
      PINUSE='BI';
    'DDR3_SA_DQS_DP5':
      PIN_NUMBER='(0,0,0,0,0,0,0,0,0,0,AF73,0,0,0,0,0,0,0,0,0,0,0,0,0,0,0,0,0,0,~
0,0,0,0,0,0,0,0,0,0,0,0,0)';
      BIDIRECTIONAL='TRUE';
      INPUT_LOAD='(-0.01,0.01)';
      OUTPUT_LOAD='(1.0,-1.0)';
      PINUSE='BI';
    'DDR3_SA_DQS_DP4':
      PIN_NUMBER='(0,0,0,0,0,0,0,0,0,0,AL58,0,0,0,0,0,0,0,0,0,0,0,0,0,0,0,0,0,0,~
0,0,0,0,0,0,0,0,0,0,0,0,0)';
      BIDIRECTIONAL='TRUE';
      INPUT_LOAD='(-0.01,0.01)';
      OUTPUT_LOAD='(1.0,-1.0)';
      PINUSE='BI';
    'DDR3_SA_DQS_DP3':
      PIN_NUMBER='(0,0,0,0,0,0,0,0,0,0,AL64,0,0,0,0,0,0,0,0,0,0,0,0,0,0,0,0,0,0,~
0,0,0,0,0,0,0,0,0,0,0,0,0)';
      BIDIRECTIONAL='TRUE';
      INPUT_LOAD='(-0.01,0.01)';
      OUTPUT_LOAD='(1.0,-1.0)';
      PINUSE='BI';
    'DDR3_SA_DQS_DP2':
      PIN_NUMBER='(0,0,0,0,0,0,0,0,0,0,AL70,0,0,0,0,0,0,0,0,0,0,0,0,0,0,0,0,0,0,~
0,0,0,0,0,0,0,0,0,0,0,0,0)';
      BIDIRECTIONAL='TRUE';
      INPUT_LOAD='(-0.01,0.01)';
      OUTPUT_LOAD='(1.0,-1.0)';
      PINUSE='BI';
    'DDR3_SA_DQS_DP1':
      PIN_NUMBER='(0,0,0,0,0,0,0,0,0,0,AL76,0,0,0,0,0,0,0,0,0,0,0,0,0,0,0,0,0,0,~
0,0,0,0,0,0,0,0,0,0,0,0,0)';
      BIDIRECTIONAL='TRUE';
      INPUT_LOAD='(-0.01,0.01)';
      OUTPUT_LOAD='(1.0,-1.0)';
      PINUSE='BI';
    'DDR3_SA_DQS_DP0':
      PIN_NUMBER='(0,0,0,0,0,0,0,0,0,0,AD73,0,0,0,0,0,0,0,0,0,0,0,0,0,0,0,0,0,0,~
0,0,0,0,0,0,0,0,0,0,0,0,0)';
      BIDIRECTIONAL='TRUE';
      INPUT_LOAD='(-0.01,0.01)';
      OUTPUT_LOAD='(1.0,-1.0)';
      PINUSE='BI';
    'DDR3_SA_ECC7':
      PIN_NUMBER='(0,0,0,0,0,0,0,0,0,0,AN56,0,0,0,0,0,0,0,0,0,0,0,0,0,0,0,0,0,0,~
0,0,0,0,0,0,0,0,0,0,0,0,0)';
      BIDIRECTIONAL='TRUE';
      INPUT_LOAD='(-0.01,0.01)';
      OUTPUT_LOAD='(1.0,-1.0)';
      PINUSE='BI';
    'DDR3_SA_ECC6':
      PIN_NUMBER='(0,0,0,0,0,0,0,0,0,0,AP57,0,0,0,0,0,0,0,0,0,0,0,0,0,0,0,0,0,0,~
0,0,0,0,0,0,0,0,0,0,0,0,0)';
      BIDIRECTIONAL='TRUE';
      INPUT_LOAD='(-0.01,0.01)';
      OUTPUT_LOAD='(1.0,-1.0)';
      PINUSE='BI';
    'DDR3_SA_ECC5':
      PIN_NUMBER='(0,0,0,0,0,0,0,0,0,0,AL56,0,0,0,0,0,0,0,0,0,0,0,0,0,0,0,0,0,0,~
0,0,0,0,0,0,0,0,0,0,0,0,0)';
      BIDIRECTIONAL='TRUE';
      INPUT_LOAD='(-0.01,0.01)';
      OUTPUT_LOAD='(1.0,-1.0)';
      PINUSE='BI';
    'DDR3_SA_ECC4':
      PIN_NUMBER='(0,0,0,0,0,0,0,0,0,0,AK57,0,0,0,0,0,0,0,0,0,0,0,0,0,0,0,0,0,0,~
0,0,0,0,0,0,0,0,0,0,0,0,0)';
      BIDIRECTIONAL='TRUE';
      INPUT_LOAD='(-0.01,0.01)';
      OUTPUT_LOAD='(1.0,-1.0)';
      PINUSE='BI';
    'DDR3_SA_ECC3':
      PIN_NUMBER='(0,0,0,0,0,0,0,0,0,0,AP59,0,0,0,0,0,0,0,0,0,0,0,0,0,0,0,0,0,0,~
0,0,0,0,0,0,0,0,0,0,0,0,0)';
      BIDIRECTIONAL='TRUE';
      INPUT_LOAD='(-0.01,0.01)';
      OUTPUT_LOAD='(1.0,-1.0)';
      PINUSE='BI';
    'DDR3_SA_ECC2':
      PIN_NUMBER='(0,0,0,0,0,0,0,0,0,0,AN60,0,0,0,0,0,0,0,0,0,0,0,0,0,0,0,0,0,0,~
0,0,0,0,0,0,0,0,0,0,0,0,0)';
      BIDIRECTIONAL='TRUE';
      INPUT_LOAD='(-0.01,0.01)';
      OUTPUT_LOAD='(1.0,-1.0)';
      PINUSE='BI';
    'DDR3_SA_ECC1':
      PIN_NUMBER='(0,0,0,0,0,0,0,0,0,0,AK59,0,0,0,0,0,0,0,0,0,0,0,0,0,0,0,0,0,0,~
0,0,0,0,0,0,0,0,0,0,0,0,0)';
      BIDIRECTIONAL='TRUE';
      INPUT_LOAD='(-0.01,0.01)';
      OUTPUT_LOAD='(1.0,-1.0)';
      PINUSE='BI';
    'DDR3_SA_ECC0':
      PIN_NUMBER='(0,0,0,0,0,0,0,0,0,0,AL60,0,0,0,0,0,0,0,0,0,0,0,0,0,0,0,0,0,0,~
0,0,0,0,0,0,0,0,0,0,0,0,0)';
      BIDIRECTIONAL='TRUE';
      INPUT_LOAD='(-0.01,0.01)';
      OUTPUT_LOAD='(1.0,-1.0)';
      PINUSE='BI';
    'DDR3_SA_PAR':
      PIN_NUMBER='(0,0,0,0,0,0,0,0,0,0,AP44,0,0,0,0,0,0,0,0,0,0,0,0,0,0,0,0,0,0,~
0,0,0,0,0,0,0,0,0,0,0,0,0)';
      OUTPUT_LOAD='(1.0,-1.0)';
      PINUSE='OUT';
    'DDR3_SB_CA6':
      PIN_NUMBER='(0,0,0,0,0,0,0,0,0,0,AB42,0,0,0,0,0,0,0,0,0,0,0,0,0,0,0,0,0,0,~
0,0,0,0,0,0,0,0,0,0,0,0,0)';
      OUTPUT_LOAD='(1.0,-1.0)';
      PINUSE='OUT';
    'DDR3_SB_CA5':
      PIN_NUMBER='(0,0,0,0,0,0,0,0,0,0,AG43,0,0,0,0,0,0,0,0,0,0,0,0,0,0,0,0,0,0,~
0,0,0,0,0,0,0,0,0,0,0,0,0)';
      OUTPUT_LOAD='(1.0,-1.0)';
      PINUSE='OUT';
    'DDR3_SB_CA4':
      PIN_NUMBER='(0,0,0,0,0,0,0,0,0,0,AC43,0,0,0,0,0,0,0,0,0,0,0,0,0,0,0,0,0,0,~
0,0,0,0,0,0,0,0,0,0,0,0,0)';
      OUTPUT_LOAD='(1.0,-1.0)';
      PINUSE='OUT';
    'DDR3_SB_CA3':
      PIN_NUMBER='(0,0,0,0,0,0,0,0,0,0,AF44,0,0,0,0,0,0,0,0,0,0,0,0,0,0,0,0,0,0,~
0,0,0,0,0,0,0,0,0,0,0,0,0)';
      OUTPUT_LOAD='(1.0,-1.0)';
      PINUSE='OUT';
    'DDR3_SB_CA2':
      PIN_NUMBER='(0,0,0,0,0,0,0,0,0,0,AD44,0,0,0,0,0,0,0,0,0,0,0,0,0,0,0,0,0,0,~
0,0,0,0,0,0,0,0,0,0,0,0,0)';
      OUTPUT_LOAD='(1.0,-1.0)';
      PINUSE='OUT';
    'DDR3_SB_CA1':
      PIN_NUMBER='(0,0,0,0,0,0,0,0,0,0,AL43,0,0,0,0,0,0,0,0,0,0,0,0,0,0,0,0,0,0,~
0,0,0,0,0,0,0,0,0,0,0,0,0)';
      OUTPUT_LOAD='(1.0,-1.0)';
      PINUSE='OUT';
    'DDR3_SB_CA0':
      PIN_NUMBER='(0,0,0,0,0,0,0,0,0,0,AK44,0,0,0,0,0,0,0,0,0,0,0,0,0,0,0,0,0,0,~
0,0,0,0,0,0,0,0,0,0,0,0,0)';
      OUTPUT_LOAD='(1.0,-1.0)';
      PINUSE='OUT';
    'DDR3_SB_CS_N3':
      PIN_NUMBER='(0,0,0,0,0,0,0,0,0,0,AD40,0,0,0,0,0,0,0,0,0,0,0,0,0,0,0,0,0,0,~
0,0,0,0,0,0,0,0,0,0,0,0,0)';
      OUTPUT_LOAD='(1.0,-1.0)';
      PINUSE='OUT';
    'DDR3_SB_CS_N2':
      PIN_NUMBER='(0,0,0,0,0,0,0,0,0,0,AF40,0,0,0,0,0,0,0,0,0,0,0,0,0,0,0,0,0,0,~
0,0,0,0,0,0,0,0,0,0,0,0,0)';
      OUTPUT_LOAD='(1.0,-1.0)';
      PINUSE='OUT';
    'DDR3_SB_CS_N1':
      PIN_NUMBER='(0,0,0,0,0,0,0,0,0,0,AG41,0,0,0,0,0,0,0,0,0,0,0,0,0,0,0,0,0,0,~
0,0,0,0,0,0,0,0,0,0,0,0,0)';
      OUTPUT_LOAD='(1.0,-1.0)';
      PINUSE='OUT';
    'DDR3_SB_CS_N0':
      PIN_NUMBER='(0,0,0,0,0,0,0,0,0,0,AC41,0,0,0,0,0,0,0,0,0,0,0,0,0,0,0,0,0,0,~
0,0,0,0,0,0,0,0,0,0,0,0,0)';
      OUTPUT_LOAD='(1.0,-1.0)';
      PINUSE='OUT';
    'DDR3_SB_DQ31':
      PIN_NUMBER='(0,0,0,0,0,0,0,0,0,0,AN19,0,0,0,0,0,0,0,0,0,0,0,0,0,0,0,0,0,0,~
0,0,0,0,0,0,0,0,0,0,0,0,0)';
      BIDIRECTIONAL='TRUE';
      INPUT_LOAD='(-0.01,0.01)';
      OUTPUT_LOAD='(1.0,-1.0)';
      PINUSE='BI';
    'DDR3_SB_DQ30':
      PIN_NUMBER='(0,0,0,0,0,0,0,0,0,0,AP20,0,0,0,0,0,0,0,0,0,0,0,0,0,0,0,0,0,0,~
0,0,0,0,0,0,0,0,0,0,0,0,0)';
      BIDIRECTIONAL='TRUE';
      INPUT_LOAD='(-0.01,0.01)';
      OUTPUT_LOAD='(1.0,-1.0)';
      PINUSE='BI';
    'DDR3_SB_DQ29':
      PIN_NUMBER='(0,0,0,0,0,0,0,0,0,0,AL19,0,0,0,0,0,0,0,0,0,0,0,0,0,0,0,0,0,0,~
0,0,0,0,0,0,0,0,0,0,0,0,0)';
      BIDIRECTIONAL='TRUE';
      INPUT_LOAD='(-0.01,0.01)';
      OUTPUT_LOAD='(1.0,-1.0)';
      PINUSE='BI';
    'DDR3_SB_DQ28':
      PIN_NUMBER='(0,0,0,0,0,0,0,0,0,0,AK20,0,0,0,0,0,0,0,0,0,0,0,0,0,0,0,0,0,0,~
0,0,0,0,0,0,0,0,0,0,0,0,0)';
      BIDIRECTIONAL='TRUE';
      INPUT_LOAD='(-0.01,0.01)';
      OUTPUT_LOAD='(1.0,-1.0)';
      PINUSE='BI';
    'DDR3_SB_DQ27':
      PIN_NUMBER='(0,0,0,0,0,0,0,0,0,0,AP22,0,0,0,0,0,0,0,0,0,0,0,0,0,0,0,0,0,0,~
0,0,0,0,0,0,0,0,0,0,0,0,0)';
      BIDIRECTIONAL='TRUE';
      INPUT_LOAD='(-0.01,0.01)';
      OUTPUT_LOAD='(1.0,-1.0)';
      PINUSE='BI';
    'DDR3_SB_DQ26':
      PIN_NUMBER='(0,0,0,0,0,0,0,0,0,0,AN23,0,0,0,0,0,0,0,0,0,0,0,0,0,0,0,0,0,0,~
0,0,0,0,0,0,0,0,0,0,0,0,0)';
      BIDIRECTIONAL='TRUE';
      INPUT_LOAD='(-0.01,0.01)';
      OUTPUT_LOAD='(1.0,-1.0)';
      PINUSE='BI';
    'DDR3_SB_DQ25':
      PIN_NUMBER='(0,0,0,0,0,0,0,0,0,0,AK22,0,0,0,0,0,0,0,0,0,0,0,0,0,0,0,0,0,0,~
0,0,0,0,0,0,0,0,0,0,0,0,0)';
      BIDIRECTIONAL='TRUE';
      INPUT_LOAD='(-0.01,0.01)';
      OUTPUT_LOAD='(1.0,-1.0)';
      PINUSE='BI';
    'DDR3_SB_DQ24':
      PIN_NUMBER='(0,0,0,0,0,0,0,0,0,0,AL23,0,0,0,0,0,0,0,0,0,0,0,0,0,0,0,0,0,0,~
0,0,0,0,0,0,0,0,0,0,0,0,0)';
      BIDIRECTIONAL='TRUE';
      INPUT_LOAD='(-0.01,0.01)';
      OUTPUT_LOAD='(1.0,-1.0)';
      PINUSE='BI';
    'DDR3_SB_DQ23':
      PIN_NUMBER='(0,0,0,0,0,0,0,0,0,0,AF22,0,0,0,0,0,0,0,0,0,0,0,0,0,0,0,0,0,0,~
0,0,0,0,0,0,0,0,0,0,0,0,0)';
      BIDIRECTIONAL='TRUE';
      INPUT_LOAD='(-0.01,0.01)';
      OUTPUT_LOAD='(1.0,-1.0)';
      PINUSE='BI';
    'DDR3_SB_DQ22':
      PIN_NUMBER='(0,0,0,0,0,0,0,0,0,0,AG23,0,0,0,0,0,0,0,0,0,0,0,0,0,0,0,0,0,0,~
0,0,0,0,0,0,0,0,0,0,0,0,0)';
      BIDIRECTIONAL='TRUE';
      INPUT_LOAD='(-0.01,0.01)';
      OUTPUT_LOAD='(1.0,-1.0)';
      PINUSE='BI';
    'DDR3_SB_DQ21':
      PIN_NUMBER='(0,0,0,0,0,0,0,0,0,0,AD22,0,0,0,0,0,0,0,0,0,0,0,0,0,0,0,0,0,0,~
0,0,0,0,0,0,0,0,0,0,0,0,0)';
      BIDIRECTIONAL='TRUE';
      INPUT_LOAD='(-0.01,0.01)';
      OUTPUT_LOAD='(1.0,-1.0)';
      PINUSE='BI';
    'DDR3_SB_DQ20':
      PIN_NUMBER='(0,0,0,0,0,0,0,0,0,0,AC23,0,0,0,0,0,0,0,0,0,0,0,0,0,0,0,0,0,0,~
0,0,0,0,0,0,0,0,0,0,0,0,0)';
      BIDIRECTIONAL='TRUE';
      INPUT_LOAD='(-0.01,0.01)';
      OUTPUT_LOAD='(1.0,-1.0)';
      PINUSE='BI';
    'DDR3_SB_DQ19':
      PIN_NUMBER='(0,0,0,0,0,0,0,0,0,0,AG25,0,0,0,0,0,0,0,0,0,0,0,0,0,0,0,0,0,0,~
0,0,0,0,0,0,0,0,0,0,0,0,0)';
      BIDIRECTIONAL='TRUE';
      INPUT_LOAD='(-0.01,0.01)';
      OUTPUT_LOAD='(1.0,-1.0)';
      PINUSE='BI';
    'DDR3_SB_DQ18':
      PIN_NUMBER='(0,0,0,0,0,0,0,0,0,0,AF26,0,0,0,0,0,0,0,0,0,0,0,0,0,0,0,0,0,0,~
0,0,0,0,0,0,0,0,0,0,0,0,0)';
      BIDIRECTIONAL='TRUE';
      INPUT_LOAD='(-0.01,0.01)';
      OUTPUT_LOAD='(1.0,-1.0)';
      PINUSE='BI';
    'DDR3_SB_DQ17':
      PIN_NUMBER='(0,0,0,0,0,0,0,0,0,0,AC25,0,0,0,0,0,0,0,0,0,0,0,0,0,0,0,0,0,0,~
0,0,0,0,0,0,0,0,0,0,0,0,0)';
      BIDIRECTIONAL='TRUE';
      INPUT_LOAD='(-0.01,0.01)';
      OUTPUT_LOAD='(1.0,-1.0)';
      PINUSE='BI';
    'DDR3_SB_DQ16':
      PIN_NUMBER='(0,0,0,0,0,0,0,0,0,0,AD26,0,0,0,0,0,0,0,0,0,0,0,0,0,0,0,0,0,0,~
0,0,0,0,0,0,0,0,0,0,0,0,0)';
      BIDIRECTIONAL='TRUE';
      INPUT_LOAD='(-0.01,0.01)';
      OUTPUT_LOAD='(1.0,-1.0)';
      PINUSE='BI';
    'DDR3_SB_DQ15':
      PIN_NUMBER='(0,0,0,0,0,0,0,0,0,0,AN25,0,0,0,0,0,0,0,0,0,0,0,0,0,0,0,0,0,0,~
0,0,0,0,0,0,0,0,0,0,0,0,0)';
      BIDIRECTIONAL='TRUE';
      INPUT_LOAD='(-0.01,0.01)';
      OUTPUT_LOAD='(1.0,-1.0)';
      PINUSE='BI';
    'DDR3_SB_DQ14':
      PIN_NUMBER='(0,0,0,0,0,0,0,0,0,0,AP26,0,0,0,0,0,0,0,0,0,0,0,0,0,0,0,0,0,0,~
0,0,0,0,0,0,0,0,0,0,0,0,0)';
      BIDIRECTIONAL='TRUE';
      INPUT_LOAD='(-0.01,0.01)';
      OUTPUT_LOAD='(1.0,-1.0)';
      PINUSE='BI';
    'DDR3_SB_DQ13':
      PIN_NUMBER='(0,0,0,0,0,0,0,0,0,0,AL25,0,0,0,0,0,0,0,0,0,0,0,0,0,0,0,0,0,0,~
0,0,0,0,0,0,0,0,0,0,0,0,0)';
      BIDIRECTIONAL='TRUE';
      INPUT_LOAD='(-0.01,0.01)';
      OUTPUT_LOAD='(1.0,-1.0)';
      PINUSE='BI';
    'DDR3_SB_DQ12':
      PIN_NUMBER='(0,0,0,0,0,0,0,0,0,0,AK26,0,0,0,0,0,0,0,0,0,0,0,0,0,0,0,0,0,0,~
0,0,0,0,0,0,0,0,0,0,0,0,0)';
      BIDIRECTIONAL='TRUE';
      INPUT_LOAD='(-0.01,0.01)';
      OUTPUT_LOAD='(1.0,-1.0)';
      PINUSE='BI';
    'DDR3_SB_DQ11':
      PIN_NUMBER='(0,0,0,0,0,0,0,0,0,0,AP28,0,0,0,0,0,0,0,0,0,0,0,0,0,0,0,0,0,0,~
0,0,0,0,0,0,0,0,0,0,0,0,0)';
      BIDIRECTIONAL='TRUE';
      INPUT_LOAD='(-0.01,0.01)';
      OUTPUT_LOAD='(1.0,-1.0)';
      PINUSE='BI';
    'DDR3_SB_DQ10':
      PIN_NUMBER='(0,0,0,0,0,0,0,0,0,0,AN29,0,0,0,0,0,0,0,0,0,0,0,0,0,0,0,0,0,0,~
0,0,0,0,0,0,0,0,0,0,0,0,0)';
      BIDIRECTIONAL='TRUE';
      INPUT_LOAD='(-0.01,0.01)';
      OUTPUT_LOAD='(1.0,-1.0)';
      PINUSE='BI';
    'DDR3_SB_DQ9':
      PIN_NUMBER='(0,0,0,0,0,0,0,0,0,0,AK28,0,0,0,0,0,0,0,0,0,0,0,0,0,0,0,0,0,0,~
0,0,0,0,0,0,0,0,0,0,0,0,0)';
      BIDIRECTIONAL='TRUE';
      INPUT_LOAD='(-0.01,0.01)';
      OUTPUT_LOAD='(1.0,-1.0)';
      PINUSE='BI';
    'DDR3_SB_DQ8':
      PIN_NUMBER='(0,0,0,0,0,0,0,0,0,0,AL29,0,0,0,0,0,0,0,0,0,0,0,0,0,0,0,0,0,0,~
0,0,0,0,0,0,0,0,0,0,0,0,0)';
      BIDIRECTIONAL='TRUE';
      INPUT_LOAD='(-0.01,0.01)';
      OUTPUT_LOAD='(1.0,-1.0)';
      PINUSE='BI';
    'DDR3_SB_DQ7':
      PIN_NUMBER='(0,0,0,0,0,0,0,0,0,0,AN31,0,0,0,0,0,0,0,0,0,0,0,0,0,0,0,0,0,0,~
0,0,0,0,0,0,0,0,0,0,0,0,0)';
      BIDIRECTIONAL='TRUE';
      INPUT_LOAD='(-0.01,0.01)';
      OUTPUT_LOAD='(1.0,-1.0)';
      PINUSE='BI';
    'DDR3_SB_DQ6':
      PIN_NUMBER='(0,0,0,0,0,0,0,0,0,0,AP32,0,0,0,0,0,0,0,0,0,0,0,0,0,0,0,0,0,0,~
0,0,0,0,0,0,0,0,0,0,0,0,0)';
      BIDIRECTIONAL='TRUE';
      INPUT_LOAD='(-0.01,0.01)';
      OUTPUT_LOAD='(1.0,-1.0)';
      PINUSE='BI';
    'DDR3_SB_DQ5':
      PIN_NUMBER='(0,0,0,0,0,0,0,0,0,0,AL31,0,0,0,0,0,0,0,0,0,0,0,0,0,0,0,0,0,0,~
0,0,0,0,0,0,0,0,0,0,0,0,0)';
      BIDIRECTIONAL='TRUE';
      INPUT_LOAD='(-0.01,0.01)';
      OUTPUT_LOAD='(1.0,-1.0)';
      PINUSE='BI';
    'DDR3_SB_DQ4':
      PIN_NUMBER='(0,0,0,0,0,0,0,0,0,0,AK32,0,0,0,0,0,0,0,0,0,0,0,0,0,0,0,0,0,0,~
0,0,0,0,0,0,0,0,0,0,0,0,0)';
      BIDIRECTIONAL='TRUE';
      INPUT_LOAD='(-0.01,0.01)';
      OUTPUT_LOAD='(1.0,-1.0)';
      PINUSE='BI';
    'DDR3_SB_DQ3':
      PIN_NUMBER='(0,0,0,0,0,0,0,0,0,0,AP34,0,0,0,0,0,0,0,0,0,0,0,0,0,0,0,0,0,0,~
0,0,0,0,0,0,0,0,0,0,0,0,0)';
      BIDIRECTIONAL='TRUE';
      INPUT_LOAD='(-0.01,0.01)';
      OUTPUT_LOAD='(1.0,-1.0)';
      PINUSE='BI';
    'DDR3_SB_DQ2':
      PIN_NUMBER='(0,0,0,0,0,0,0,0,0,0,AN35,0,0,0,0,0,0,0,0,0,0,0,0,0,0,0,0,0,0,~
0,0,0,0,0,0,0,0,0,0,0,0,0)';
      BIDIRECTIONAL='TRUE';
      INPUT_LOAD='(-0.01,0.01)';
      OUTPUT_LOAD='(1.0,-1.0)';
      PINUSE='BI';
    'DDR3_SB_DQ1':
      PIN_NUMBER='(0,0,0,0,0,0,0,0,0,0,AK34,0,0,0,0,0,0,0,0,0,0,0,0,0,0,0,0,0,0,~
0,0,0,0,0,0,0,0,0,0,0,0,0)';
      BIDIRECTIONAL='TRUE';
      INPUT_LOAD='(-0.01,0.01)';
      OUTPUT_LOAD='(1.0,-1.0)';
      PINUSE='BI';
    'DDR3_SB_DQ0':
      PIN_NUMBER='(0,0,0,0,0,0,0,0,0,0,AL35,0,0,0,0,0,0,0,0,0,0,0,0,0,0,0,0,0,0,~
0,0,0,0,0,0,0,0,0,0,0,0,0)';
      BIDIRECTIONAL='TRUE';
      INPUT_LOAD='(-0.01,0.01)';
      OUTPUT_LOAD='(1.0,-1.0)';
      PINUSE='BI';
    'DDR3_SB_DQS_DN9':
      PIN_NUMBER='(0,0,0,0,0,0,0,0,0,0,AJ39,0,0,0,0,0,0,0,0,0,0,0,0,0,0,0,0,0,0,~
0,0,0,0,0,0,0,0,0,0,0,0,0)';
      BIDIRECTIONAL='TRUE';
      INPUT_LOAD='(-0.01,0.01)';
      OUTPUT_LOAD='(1.0,-1.0)';
      PINUSE='BI';
    'DDR3_SB_DQS_DN8':
      PIN_NUMBER='(0,0,0,0,0,0,0,0,0,0,AN21,0,0,0,0,0,0,0,0,0,0,0,0,0,0,0,0,0,0,~
0,0,0,0,0,0,0,0,0,0,0,0,0)';
      BIDIRECTIONAL='TRUE';
      INPUT_LOAD='(-0.01,0.01)';
      OUTPUT_LOAD='(1.0,-1.0)';
      PINUSE='BI';
    'DDR3_SB_DQS_DN7':
      PIN_NUMBER='(0,0,0,0,0,0,0,0,0,0,AF24,0,0,0,0,0,0,0,0,0,0,0,0,0,0,0,0,0,0,~
0,0,0,0,0,0,0,0,0,0,0,0,0)';
      BIDIRECTIONAL='TRUE';
      INPUT_LOAD='(-0.01,0.01)';
      OUTPUT_LOAD='(1.0,-1.0)';
      PINUSE='BI';
    'DDR3_SB_DQS_DN6':
      PIN_NUMBER='(0,0,0,0,0,0,0,0,0,0,AN27,0,0,0,0,0,0,0,0,0,0,0,0,0,0,0,0,0,0,~
0,0,0,0,0,0,0,0,0,0,0,0,0)';
      BIDIRECTIONAL='TRUE';
      INPUT_LOAD='(-0.01,0.01)';
      OUTPUT_LOAD='(1.0,-1.0)';
      PINUSE='BI';
    'DDR3_SB_DQS_DN5':
      PIN_NUMBER='(0,0,0,0,0,0,0,0,0,0,AN33,0,0,0,0,0,0,0,0,0,0,0,0,0,0,0,0,0,0,~
0,0,0,0,0,0,0,0,0,0,0,0,0)';
      BIDIRECTIONAL='TRUE';
      INPUT_LOAD='(-0.01,0.01)';
      OUTPUT_LOAD='(1.0,-1.0)';
      PINUSE='BI';
    'DDR3_SB_DQS_DN4':
      PIN_NUMBER='(0,0,0,0,0,0,0,0,0,0,AR39,0,0,0,0,0,0,0,0,0,0,0,0,0,0,0,0,0,0,~
0,0,0,0,0,0,0,0,0,0,0,0,0)';
      BIDIRECTIONAL='TRUE';
      INPUT_LOAD='(-0.01,0.01)';
      OUTPUT_LOAD='(1.0,-1.0)';
      PINUSE='BI';
    'DDR3_SB_DQS_DN3':
      PIN_NUMBER='(0,0,0,0,0,0,0,0,0,0,AJ21,0,0,0,0,0,0,0,0,0,0,0,0,0,0,0,0,0,0,~
0,0,0,0,0,0,0,0,0,0,0,0,0)';
      BIDIRECTIONAL='TRUE';
      INPUT_LOAD='(-0.01,0.01)';
      OUTPUT_LOAD='(1.0,-1.0)';
      PINUSE='BI';
    'DDR3_SB_DQS_DN2':
      PIN_NUMBER='(0,0,0,0,0,0,0,0,0,0,AB24,0,0,0,0,0,0,0,0,0,0,0,0,0,0,0,0,0,0,~
0,0,0,0,0,0,0,0,0,0,0,0,0)';
      BIDIRECTIONAL='TRUE';
      INPUT_LOAD='(-0.01,0.01)';
      OUTPUT_LOAD='(1.0,-1.0)';
      PINUSE='BI';
    'DDR3_SB_DQS_DN1':
      PIN_NUMBER='(0,0,0,0,0,0,0,0,0,0,AJ27,0,0,0,0,0,0,0,0,0,0,0,0,0,0,0,0,0,0,~
0,0,0,0,0,0,0,0,0,0,0,0,0)';
      BIDIRECTIONAL='TRUE';
      INPUT_LOAD='(-0.01,0.01)';
      OUTPUT_LOAD='(1.0,-1.0)';
      PINUSE='BI';
    'DDR3_SB_DQS_DN0':
      PIN_NUMBER='(0,0,0,0,0,0,0,0,0,0,AJ33,0,0,0,0,0,0,0,0,0,0,0,0,0,0,0,0,0,0,~
0,0,0,0,0,0,0,0,0,0,0,0,0)';
      BIDIRECTIONAL='TRUE';
      INPUT_LOAD='(-0.01,0.01)';
      OUTPUT_LOAD='(1.0,-1.0)';
      PINUSE='BI';
    'DDR3_SB_DQS_DP9':
      PIN_NUMBER='(0,0,0,0,0,0,0,0,0,0,AL39,0,0,0,0,0,0,0,0,0,0,0,0,0,0,0,0,0,0,~
0,0,0,0,0,0,0,0,0,0,0,0,0)';
      BIDIRECTIONAL='TRUE';
      INPUT_LOAD='(-0.01,0.01)';
      OUTPUT_LOAD='(1.0,-1.0)';
      PINUSE='BI';
    'DDR3_SB_DQS_DP8':
      PIN_NUMBER='(0,0,0,0,0,0,0,0,0,0,AR21,0,0,0,0,0,0,0,0,0,0,0,0,0,0,0,0,0,0,~
0,0,0,0,0,0,0,0,0,0,0,0,0)';
      BIDIRECTIONAL='TRUE';
      INPUT_LOAD='(-0.01,0.01)';
      OUTPUT_LOAD='(1.0,-1.0)';
      PINUSE='BI';
    'DDR3_SB_DQS_DP7':
      PIN_NUMBER='(0,0,0,0,0,0,0,0,0,0,AH24,0,0,0,0,0,0,0,0,0,0,0,0,0,0,0,0,0,0,~
0,0,0,0,0,0,0,0,0,0,0,0,0)';
      BIDIRECTIONAL='TRUE';
      INPUT_LOAD='(-0.01,0.01)';
      OUTPUT_LOAD='(1.0,-1.0)';
      PINUSE='BI';
    'DDR3_SB_DQS_DP6':
      PIN_NUMBER='(0,0,0,0,0,0,0,0,0,0,AR27,0,0,0,0,0,0,0,0,0,0,0,0,0,0,0,0,0,0,~
0,0,0,0,0,0,0,0,0,0,0,0,0)';
      BIDIRECTIONAL='TRUE';
      INPUT_LOAD='(-0.01,0.01)';
      OUTPUT_LOAD='(1.0,-1.0)';
      PINUSE='BI';
    'DDR3_SB_DQS_DP5':
      PIN_NUMBER='(0,0,0,0,0,0,0,0,0,0,AR33,0,0,0,0,0,0,0,0,0,0,0,0,0,0,0,0,0,0,~
0,0,0,0,0,0,0,0,0,0,0,0,0)';
      BIDIRECTIONAL='TRUE';
      INPUT_LOAD='(-0.01,0.01)';
      OUTPUT_LOAD='(1.0,-1.0)';
      PINUSE='BI';
    'DDR3_SB_DQS_DP4':
      PIN_NUMBER='(0,0,0,0,0,0,0,0,0,0,AN39,0,0,0,0,0,0,0,0,0,0,0,0,0,0,0,0,0,0,~
0,0,0,0,0,0,0,0,0,0,0,0,0)';
      BIDIRECTIONAL='TRUE';
      INPUT_LOAD='(-0.01,0.01)';
      OUTPUT_LOAD='(1.0,-1.0)';
      PINUSE='BI';
    'DDR3_SB_DQS_DP3':
      PIN_NUMBER='(0,0,0,0,0,0,0,0,0,0,AL21,0,0,0,0,0,0,0,0,0,0,0,0,0,0,0,0,0,0,~
0,0,0,0,0,0,0,0,0,0,0,0,0)';
      BIDIRECTIONAL='TRUE';
      INPUT_LOAD='(-0.01,0.01)';
      OUTPUT_LOAD='(1.0,-1.0)';
      PINUSE='BI';
    'DDR3_SB_DQS_DP2':
      PIN_NUMBER='(0,0,0,0,0,0,0,0,0,0,AD24,0,0,0,0,0,0,0,0,0,0,0,0,0,0,0,0,0,0,~
0,0,0,0,0,0,0,0,0,0,0,0,0)';
      BIDIRECTIONAL='TRUE';
      INPUT_LOAD='(-0.01,0.01)';
      OUTPUT_LOAD='(1.0,-1.0)';
      PINUSE='BI';
    'DDR3_SB_DQS_DP1':
      PIN_NUMBER='(0,0,0,0,0,0,0,0,0,0,AL27,0,0,0,0,0,0,0,0,0,0,0,0,0,0,0,0,0,0,~
0,0,0,0,0,0,0,0,0,0,0,0,0)';
      BIDIRECTIONAL='TRUE';
      INPUT_LOAD='(-0.01,0.01)';
      OUTPUT_LOAD='(1.0,-1.0)';
      PINUSE='BI';
    'DDR3_SB_DQS_DP0':
      PIN_NUMBER='(0,0,0,0,0,0,0,0,0,0,AL33,0,0,0,0,0,0,0,0,0,0,0,0,0,0,0,0,0,0,~
0,0,0,0,0,0,0,0,0,0,0,0,0)';
      BIDIRECTIONAL='TRUE';
      INPUT_LOAD='(-0.01,0.01)';
      OUTPUT_LOAD='(1.0,-1.0)';
      PINUSE='BI';
    'DDR3_SB_ECC7':
      PIN_NUMBER='(0,0,0,0,0,0,0,0,0,0,AP40,0,0,0,0,0,0,0,0,0,0,0,0,0,0,0,0,0,0,~
0,0,0,0,0,0,0,0,0,0,0,0,0)';
      BIDIRECTIONAL='TRUE';
      INPUT_LOAD='(-0.01,0.01)';
      OUTPUT_LOAD='(1.0,-1.0)';
      PINUSE='BI';
    'DDR3_SB_ECC6':
      PIN_NUMBER='(0,0,0,0,0,0,0,0,0,0,AN41,0,0,0,0,0,0,0,0,0,0,0,0,0,0,0,0,0,0,~
0,0,0,0,0,0,0,0,0,0,0,0,0)';
      BIDIRECTIONAL='TRUE';
      INPUT_LOAD='(-0.01,0.01)';
      OUTPUT_LOAD='(1.0,-1.0)';
      PINUSE='BI';
    'DDR3_SB_ECC5':
      PIN_NUMBER='(0,0,0,0,0,0,0,0,0,0,AK40,0,0,0,0,0,0,0,0,0,0,0,0,0,0,0,0,0,0,~
0,0,0,0,0,0,0,0,0,0,0,0,0)';
      BIDIRECTIONAL='TRUE';
      INPUT_LOAD='(-0.01,0.01)';
      OUTPUT_LOAD='(1.0,-1.0)';
      PINUSE='BI';
    'DDR3_SB_ECC4':
      PIN_NUMBER='(0,0,0,0,0,0,0,0,0,0,AL41,0,0,0,0,0,0,0,0,0,0,0,0,0,0,0,0,0,0,~
0,0,0,0,0,0,0,0,0,0,0,0,0)';
      BIDIRECTIONAL='TRUE';
      INPUT_LOAD='(-0.01,0.01)';
      OUTPUT_LOAD='(1.0,-1.0)';
      PINUSE='BI';
    'DDR3_SB_ECC3':
      PIN_NUMBER='(0,0,0,0,0,0,0,0,0,0,AN37,0,0,0,0,0,0,0,0,0,0,0,0,0,0,0,0,0,0,~
0,0,0,0,0,0,0,0,0,0,0,0,0)';
      BIDIRECTIONAL='TRUE';
      INPUT_LOAD='(-0.01,0.01)';
      OUTPUT_LOAD='(1.0,-1.0)';
      PINUSE='BI';
    'DDR3_SB_ECC2':
      PIN_NUMBER='(0,0,0,0,0,0,0,0,0,0,AP38,0,0,0,0,0,0,0,0,0,0,0,0,0,0,0,0,0,0,~
0,0,0,0,0,0,0,0,0,0,0,0,0)';
      BIDIRECTIONAL='TRUE';
      INPUT_LOAD='(-0.01,0.01)';
      OUTPUT_LOAD='(1.0,-1.0)';
      PINUSE='BI';
    'DDR3_SB_ECC1':
      PIN_NUMBER='(0,0,0,0,0,0,0,0,0,0,AL37,0,0,0,0,0,0,0,0,0,0,0,0,0,0,0,0,0,0,~
0,0,0,0,0,0,0,0,0,0,0,0,0)';
      BIDIRECTIONAL='TRUE';
      INPUT_LOAD='(-0.01,0.01)';
      OUTPUT_LOAD='(1.0,-1.0)';
      PINUSE='BI';
    'DDR3_SB_ECC0':
      PIN_NUMBER='(0,0,0,0,0,0,0,0,0,0,AK38,0,0,0,0,0,0,0,0,0,0,0,0,0,0,0,0,0,0,~
0,0,0,0,0,0,0,0,0,0,0,0,0)';
      BIDIRECTIONAL='TRUE';
      INPUT_LOAD='(-0.01,0.01)';
      OUTPUT_LOAD='(1.0,-1.0)';
      PINUSE='BI';
    'DDR3_SB_PAR':
      PIN_NUMBER='(0,0,0,0,0,0,0,0,0,0,AH42,0,0,0,0,0,0,0,0,0,0,0,0,0,0,0,0,0,0,~
0,0,0,0,0,0,0,0,0,0,0,0,0)';
      OUTPUT_LOAD='(1.0,-1.0)';
      PINUSE='OUT';
    'DDR4_ALERT_N':
      PIN_NUMBER='(0,0,0,0,0,0,0,0,0,0,0,CY47,0,0,0,0,0,0,0,0,0,0,0,0,0,0,0,0,0,~
0,0,0,0,0,0,0,0,0,0,0,0,0)';
      INPUT_LOAD='(-0.01,0.01)';
      PINUSE='IN';
    'DDR4_A_RSP1':
      PIN_NUMBER='(0,0,0,0,0,0,0,0,0,0,0,DC43,0,0,0,0,0,0,0,0,0,0,0,0,0,0,0,0,0,~
0,0,0,0,0,0,0,0,0,0,0,0,0)';
      INPUT_LOAD='(-0.01,0.01)';
      PINUSE='IN';
    'DDR4_A_RSP0':
      PIN_NUMBER='(0,0,0,0,0,0,0,0,0,0,0,DD44,0,0,0,0,0,0,0,0,0,0,0,0,0,0,0,0,0,~
0,0,0,0,0,0,0,0,0,0,0,0,0)';
      INPUT_LOAD='(-0.01,0.01)';
      PINUSE='IN';
    'DDR4_B_RSP1':
      PIN_NUMBER='(0,0,0,0,0,0,0,0,0,0,0,DG43,0,0,0,0,0,0,0,0,0,0,0,0,0,0,0,0,0,~
0,0,0,0,0,0,0,0,0,0,0,0,0)';
      INPUT_LOAD='(-0.01,0.01)';
      PINUSE='IN';
    'DDR4_B_RSP0':
      PIN_NUMBER='(0,0,0,0,0,0,0,0,0,0,0,DF44,0,0,0,0,0,0,0,0,0,0,0,0,0,0,0,0,0,~
0,0,0,0,0,0,0,0,0,0,0,0,0)';
      INPUT_LOAD='(-0.01,0.01)';
      PINUSE='IN';
    'DDR4_CLK_DN1':
      PIN_NUMBER='(0,0,0,0,0,0,0,0,0,0,0,EE45,0,0,0,0,0,0,0,0,0,0,0,0,0,0,0,0,0,~
0,0,0,0,0,0,0,0,0,0,0,0,0)';
      OUTPUT_LOAD='(1.0,-1.0)';
      PINUSE='OUT';
    'DDR4_CLK_DN0':
      PIN_NUMBER='(0,0,0,0,0,0,0,0,0,0,0,EJ45,0,0,0,0,0,0,0,0,0,0,0,0,0,0,0,0,0,~
0,0,0,0,0,0,0,0,0,0,0,0,0)';
      OUTPUT_LOAD='(1.0,-1.0)';
      PINUSE='OUT';
    'DDR4_CLK_DP1':
      PIN_NUMBER='(0,0,0,0,0,0,0,0,0,0,0,EC45,0,0,0,0,0,0,0,0,0,0,0,0,0,0,0,0,0,~
0,0,0,0,0,0,0,0,0,0,0,0,0)';
      OUTPUT_LOAD='(1.0,-1.0)';
      PINUSE='OUT';
    'DDR4_CLK_DP0':
      PIN_NUMBER='(0,0,0,0,0,0,0,0,0,0,0,EG45,0,0,0,0,0,0,0,0,0,0,0,0,0,0,0,0,0,~
0,0,0,0,0,0,0,0,0,0,0,0,0)';
      OUTPUT_LOAD='(1.0,-1.0)';
      PINUSE='OUT';
    'DDR4_SA_CA6':
      PIN_NUMBER='(0,0,0,0,0,0,0,0,0,0,0,ED44,0,0,0,0,0,0,0,0,0,0,0,0,0,0,0,0,0,~
0,0,0,0,0,0,0,0,0,0,0,0,0)';
      OUTPUT_LOAD='(1.0,-1.0)';
      PINUSE='OUT';
    'DDR4_SA_CA5':
      PIN_NUMBER='(0,0,0,0,0,0,0,0,0,0,0,EP47,0,0,0,0,0,0,0,0,0,0,0,0,0,0,0,0,0,~
0,0,0,0,0,0,0,0,0,0,0,0,0)';
      OUTPUT_LOAD='(1.0,-1.0)';
      PINUSE='OUT';
    'DDR4_SA_CA4':
      PIN_NUMBER='(0,0,0,0,0,0,0,0,0,0,0,EM47,0,0,0,0,0,0,0,0,0,0,0,0,0,0,0,0,0,~
0,0,0,0,0,0,0,0,0,0,0,0,0)';
      OUTPUT_LOAD='(1.0,-1.0)';
      PINUSE='OUT';
    'DDR4_SA_CA3':
      PIN_NUMBER='(0,0,0,0,0,0,0,0,0,0,0,EL48,0,0,0,0,0,0,0,0,0,0,0,0,0,0,0,0,0,~
0,0,0,0,0,0,0,0,0,0,0,0,0)';
      OUTPUT_LOAD='(1.0,-1.0)';
      PINUSE='OUT';
    'DDR4_SA_CA2':
      PIN_NUMBER='(0,0,0,0,0,0,0,0,0,0,0,EK49,0,0,0,0,0,0,0,0,0,0,0,0,0,0,0,0,0,~
0,0,0,0,0,0,0,0,0,0,0,0,0)';
      OUTPUT_LOAD='(1.0,-1.0)';
      PINUSE='OUT';
    'DDR4_SA_CA1':
      PIN_NUMBER='(0,0,0,0,0,0,0,0,0,0,0,ET49,0,0,0,0,0,0,0,0,0,0,0,0,0,0,0,0,0,~
0,0,0,0,0,0,0,0,0,0,0,0,0)';
      OUTPUT_LOAD='(1.0,-1.0)';
      PINUSE='OUT';
    'DDR4_SA_CA0':
      PIN_NUMBER='(0,0,0,0,0,0,0,0,0,0,0,EP49,0,0,0,0,0,0,0,0,0,0,0,0,0,0,0,0,0,~
0,0,0,0,0,0,0,0,0,0,0,0,0)';
      OUTPUT_LOAD='(1.0,-1.0)';
      PINUSE='OUT';
    'DDR4_SA_CS_N3':
      PIN_NUMBER='(0,0,0,0,0,0,0,0,0,0,0,EL50,0,0,0,0,0,0,0,0,0,0,0,0,0,0,0,0,0,~
0,0,0,0,0,0,0,0,0,0,0,0,0)';
      OUTPUT_LOAD='(1.0,-1.0)';
      PINUSE='OUT';
    'DDR4_SA_CS_N2':
      PIN_NUMBER='(0,0,0,0,0,0,0,0,0,0,0,EM51,0,0,0,0,0,0,0,0,0,0,0,0,0,0,0,0,0,~
0,0,0,0,0,0,0,0,0,0,0,0,0)';
      OUTPUT_LOAD='(1.0,-1.0)';
      PINUSE='OUT';
    'DDR4_SA_CS_N1':
      PIN_NUMBER='(0,0,0,0,0,0,0,0,0,0,0,ET51,0,0,0,0,0,0,0,0,0,0,0,0,0,0,0,0,0,~
0,0,0,0,0,0,0,0,0,0,0,0,0)';
      OUTPUT_LOAD='(1.0,-1.0)';
      PINUSE='OUT';
    'DDR4_SA_CS_N0':
      PIN_NUMBER='(0,0,0,0,0,0,0,0,0,0,0,EP51,0,0,0,0,0,0,0,0,0,0,0,0,0,0,0,0,0,~
0,0,0,0,0,0,0,0,0,0,0,0,0)';
      OUTPUT_LOAD='(1.0,-1.0)';
      PINUSE='OUT';
    'DDR4_SA_DQ31':
      PIN_NUMBER='(0,0,0,0,0,0,0,0,0,0,0,EP59,0,0,0,0,0,0,0,0,0,0,0,0,0,0,0,0,0,~
0,0,0,0,0,0,0,0,0,0,0,0,0)';
      BIDIRECTIONAL='TRUE';
      INPUT_LOAD='(-0.01,0.01)';
      OUTPUT_LOAD='(1.0,-1.0)';
      PINUSE='BI';
    'DDR4_SA_DQ30':
      PIN_NUMBER='(0,0,0,0,0,0,0,0,0,0,0,ER60,0,0,0,0,0,0,0,0,0,0,0,0,0,0,0,0,0,~
0,0,0,0,0,0,0,0,0,0,0,0,0)';
      BIDIRECTIONAL='TRUE';
      INPUT_LOAD='(-0.01,0.01)';
      OUTPUT_LOAD='(1.0,-1.0)';
      PINUSE='BI';
    'DDR4_SA_DQ29':
      PIN_NUMBER='(0,0,0,0,0,0,0,0,0,0,0,EM59,0,0,0,0,0,0,0,0,0,0,0,0,0,0,0,0,0,~
0,0,0,0,0,0,0,0,0,0,0,0,0)';
      BIDIRECTIONAL='TRUE';
      INPUT_LOAD='(-0.01,0.01)';
      OUTPUT_LOAD='(1.0,-1.0)';
      PINUSE='BI';
    'DDR4_SA_DQ28':
      PIN_NUMBER='(0,0,0,0,0,0,0,0,0,0,0,EL60,0,0,0,0,0,0,0,0,0,0,0,0,0,0,0,0,0,~
0,0,0,0,0,0,0,0,0,0,0,0,0)';
      BIDIRECTIONAL='TRUE';
      INPUT_LOAD='(-0.01,0.01)';
      OUTPUT_LOAD='(1.0,-1.0)';
      PINUSE='BI';
    'DDR4_SA_DQ27':
      PIN_NUMBER='(0,0,0,0,0,0,0,0,0,0,0,ER62,0,0,0,0,0,0,0,0,0,0,0,0,0,0,0,0,0,~
0,0,0,0,0,0,0,0,0,0,0,0,0)';
      BIDIRECTIONAL='TRUE';
      INPUT_LOAD='(-0.01,0.01)';
      OUTPUT_LOAD='(1.0,-1.0)';
      PINUSE='BI';
    'DDR4_SA_DQ26':
      PIN_NUMBER='(0,0,0,0,0,0,0,0,0,0,0,EP63,0,0,0,0,0,0,0,0,0,0,0,0,0,0,0,0,0,~
0,0,0,0,0,0,0,0,0,0,0,0,0)';
      BIDIRECTIONAL='TRUE';
      INPUT_LOAD='(-0.01,0.01)';
      OUTPUT_LOAD='(1.0,-1.0)';
      PINUSE='BI';
    'DDR4_SA_DQ25':
      PIN_NUMBER='(0,0,0,0,0,0,0,0,0,0,0,EL62,0,0,0,0,0,0,0,0,0,0,0,0,0,0,0,0,0,~
0,0,0,0,0,0,0,0,0,0,0,0,0)';
      BIDIRECTIONAL='TRUE';
      INPUT_LOAD='(-0.01,0.01)';
      OUTPUT_LOAD='(1.0,-1.0)';
      PINUSE='BI';
    'DDR4_SA_DQ24':
      PIN_NUMBER='(0,0,0,0,0,0,0,0,0,0,0,EM63,0,0,0,0,0,0,0,0,0,0,0,0,0,0,0,0,0,~
0,0,0,0,0,0,0,0,0,0,0,0,0)';
      BIDIRECTIONAL='TRUE';
      INPUT_LOAD='(-0.01,0.01)';
      OUTPUT_LOAD='(1.0,-1.0)';
      PINUSE='BI';
    'DDR4_SA_DQ23':
      PIN_NUMBER='(0,0,0,0,0,0,0,0,0,0,0,EP65,0,0,0,0,0,0,0,0,0,0,0,0,0,0,0,0,0,~
0,0,0,0,0,0,0,0,0,0,0,0,0)';
      BIDIRECTIONAL='TRUE';
      INPUT_LOAD='(-0.01,0.01)';
      OUTPUT_LOAD='(1.0,-1.0)';
      PINUSE='BI';
    'DDR4_SA_DQ22':
      PIN_NUMBER='(0,0,0,0,0,0,0,0,0,0,0,EL66,0,0,0,0,0,0,0,0,0,0,0,0,0,0,0,0,0,~
0,0,0,0,0,0,0,0,0,0,0,0,0)';
      BIDIRECTIONAL='TRUE';
      INPUT_LOAD='(-0.01,0.01)';
      OUTPUT_LOAD='(1.0,-1.0)';
      PINUSE='BI';
    'DDR4_SA_DQ21':
      PIN_NUMBER='(0,0,0,0,0,0,0,0,0,0,0,EM65,0,0,0,0,0,0,0,0,0,0,0,0,0,0,0,0,0,~
0,0,0,0,0,0,0,0,0,0,0,0,0)';
      BIDIRECTIONAL='TRUE';
      INPUT_LOAD='(-0.01,0.01)';
      OUTPUT_LOAD='(1.0,-1.0)';
      PINUSE='BI';
    'DDR4_SA_DQ20':
      PIN_NUMBER='(0,0,0,0,0,0,0,0,0,0,0,ER66,0,0,0,0,0,0,0,0,0,0,0,0,0,0,0,0,0,~
0,0,0,0,0,0,0,0,0,0,0,0,0)';
      BIDIRECTIONAL='TRUE';
      INPUT_LOAD='(-0.01,0.01)';
      OUTPUT_LOAD='(1.0,-1.0)';
      PINUSE='BI';
    'DDR4_SA_DQ19':
      PIN_NUMBER='(0,0,0,0,0,0,0,0,0,0,0,ER68,0,0,0,0,0,0,0,0,0,0,0,0,0,0,0,0,0,~
0,0,0,0,0,0,0,0,0,0,0,0,0)';
      BIDIRECTIONAL='TRUE';
      INPUT_LOAD='(-0.01,0.01)';
      OUTPUT_LOAD='(1.0,-1.0)';
      PINUSE='BI';
    'DDR4_SA_DQ18':
      PIN_NUMBER='(0,0,0,0,0,0,0,0,0,0,0,EN70,0,0,0,0,0,0,0,0,0,0,0,0,0,0,0,0,0,~
0,0,0,0,0,0,0,0,0,0,0,0,0)';
      BIDIRECTIONAL='TRUE';
      INPUT_LOAD='(-0.01,0.01)';
      OUTPUT_LOAD='(1.0,-1.0)';
      PINUSE='BI';
    'DDR4_SA_DQ17':
      PIN_NUMBER='(0,0,0,0,0,0,0,0,0,0,0,EM69,0,0,0,0,0,0,0,0,0,0,0,0,0,0,0,0,0,~
0,0,0,0,0,0,0,0,0,0,0,0,0)';
      BIDIRECTIONAL='TRUE';
      INPUT_LOAD='(-0.01,0.01)';
      OUTPUT_LOAD='(1.0,-1.0)';
      PINUSE='BI';
    'DDR4_SA_DQ16':
      PIN_NUMBER='(0,0,0,0,0,0,0,0,0,0,0,EM71,0,0,0,0,0,0,0,0,0,0,0,0,0,0,0,0,0,~
0,0,0,0,0,0,0,0,0,0,0,0,0)';
      BIDIRECTIONAL='TRUE';
      INPUT_LOAD='(-0.01,0.01)';
      OUTPUT_LOAD='(1.0,-1.0)';
      PINUSE='BI';
    'DDR4_SA_DQ15':
      PIN_NUMBER='(0,0,0,0,0,0,0,0,0,0,0,EG68,0,0,0,0,0,0,0,0,0,0,0,0,0,0,0,0,0,~
0,0,0,0,0,0,0,0,0,0,0,0,0)';
      BIDIRECTIONAL='TRUE';
      INPUT_LOAD='(-0.01,0.01)';
      OUTPUT_LOAD='(1.0,-1.0)';
      PINUSE='BI';
    'DDR4_SA_DQ14':
      PIN_NUMBER='(0,0,0,0,0,0,0,0,0,0,0,EH69,0,0,0,0,0,0,0,0,0,0,0,0,0,0,0,0,0,~
0,0,0,0,0,0,0,0,0,0,0,0,0)';
      BIDIRECTIONAL='TRUE';
      INPUT_LOAD='(-0.01,0.01)';
      OUTPUT_LOAD='(1.0,-1.0)';
      PINUSE='BI';
    'DDR4_SA_DQ13':
      PIN_NUMBER='(0,0,0,0,0,0,0,0,0,0,0,EE68,0,0,0,0,0,0,0,0,0,0,0,0,0,0,0,0,0,~
0,0,0,0,0,0,0,0,0,0,0,0,0)';
      BIDIRECTIONAL='TRUE';
      INPUT_LOAD='(-0.01,0.01)';
      OUTPUT_LOAD='(1.0,-1.0)';
      PINUSE='BI';
    'DDR4_SA_DQ12':
      PIN_NUMBER='(0,0,0,0,0,0,0,0,0,0,0,ED69,0,0,0,0,0,0,0,0,0,0,0,0,0,0,0,0,0,~
0,0,0,0,0,0,0,0,0,0,0,0,0)';
      BIDIRECTIONAL='TRUE';
      INPUT_LOAD='(-0.01,0.01)';
      OUTPUT_LOAD='(1.0,-1.0)';
      PINUSE='BI';
    'DDR4_SA_DQ11':
      PIN_NUMBER='(0,0,0,0,0,0,0,0,0,0,0,EH71,0,0,0,0,0,0,0,0,0,0,0,0,0,0,0,0,0,~
0,0,0,0,0,0,0,0,0,0,0,0,0)';
      BIDIRECTIONAL='TRUE';
      INPUT_LOAD='(-0.01,0.01)';
      OUTPUT_LOAD='(1.0,-1.0)';
      PINUSE='BI';
    'DDR4_SA_DQ10':
      PIN_NUMBER='(0,0,0,0,0,0,0,0,0,0,0,EG72,0,0,0,0,0,0,0,0,0,0,0,0,0,0,0,0,0,~
0,0,0,0,0,0,0,0,0,0,0,0,0)';
      BIDIRECTIONAL='TRUE';
      INPUT_LOAD='(-0.01,0.01)';
      OUTPUT_LOAD='(1.0,-1.0)';
      PINUSE='BI';
    'DDR4_SA_DQ9':
      PIN_NUMBER='(0,0,0,0,0,0,0,0,0,0,0,ED71,0,0,0,0,0,0,0,0,0,0,0,0,0,0,0,0,0,~
0,0,0,0,0,0,0,0,0,0,0,0,0)';
      BIDIRECTIONAL='TRUE';
      INPUT_LOAD='(-0.01,0.01)';
      OUTPUT_LOAD='(1.0,-1.0)';
      PINUSE='BI';
    'DDR4_SA_DQ8':
      PIN_NUMBER='(0,0,0,0,0,0,0,0,0,0,0,EE72,0,0,0,0,0,0,0,0,0,0,0,0,0,0,0,0,0,~
0,0,0,0,0,0,0,0,0,0,0,0,0)';
      BIDIRECTIONAL='TRUE';
      INPUT_LOAD='(-0.01,0.01)';
      OUTPUT_LOAD='(1.0,-1.0)';
      PINUSE='BI';
    'DDR4_SA_DQ7':
      PIN_NUMBER='(0,0,0,0,0,0,0,0,0,0,0,ER72,0,0,0,0,0,0,0,0,0,0,0,0,0,0,0,0,0,~
0,0,0,0,0,0,0,0,0,0,0,0,0)';
      BIDIRECTIONAL='TRUE';
      INPUT_LOAD='(-0.01,0.01)';
      OUTPUT_LOAD='(1.0,-1.0)';
      PINUSE='BI';
    'DDR4_SA_DQ6':
      PIN_NUMBER='(0,0,0,0,0,0,0,0,0,0,0,EP73,0,0,0,0,0,0,0,0,0,0,0,0,0,0,0,0,0,~
0,0,0,0,0,0,0,0,0,0,0,0,0)';
      BIDIRECTIONAL='TRUE';
      INPUT_LOAD='(-0.01,0.01)';
      OUTPUT_LOAD='(1.0,-1.0)';
      PINUSE='BI';
    'DDR4_SA_DQ5':
      PIN_NUMBER='(0,0,0,0,0,0,0,0,0,0,0,EK73,0,0,0,0,0,0,0,0,0,0,0,0,0,0,0,0,0,~
0,0,0,0,0,0,0,0,0,0,0,0,0)';
      BIDIRECTIONAL='TRUE';
      INPUT_LOAD='(-0.01,0.01)';
      OUTPUT_LOAD='(1.0,-1.0)';
      PINUSE='BI';
    'DDR4_SA_DQ4':
      PIN_NUMBER='(0,0,0,0,0,0,0,0,0,0,0,EL74,0,0,0,0,0,0,0,0,0,0,0,0,0,0,0,0,0,~
0,0,0,0,0,0,0,0,0,0,0,0,0)';
      BIDIRECTIONAL='TRUE';
      INPUT_LOAD='(-0.01,0.01)';
      OUTPUT_LOAD='(1.0,-1.0)';
      PINUSE='BI';
    'DDR4_SA_DQ3':
      PIN_NUMBER='(0,0,0,0,0,0,0,0,0,0,0,ER76,0,0,0,0,0,0,0,0,0,0,0,0,0,0,0,0,0,~
0,0,0,0,0,0,0,0,0,0,0,0,0)';
      BIDIRECTIONAL='TRUE';
      INPUT_LOAD='(-0.01,0.01)';
      OUTPUT_LOAD='(1.0,-1.0)';
      PINUSE='BI';
    'DDR4_SA_DQ2':
      PIN_NUMBER='(0,0,0,0,0,0,0,0,0,0,0,EP79,0,0,0,0,0,0,0,0,0,0,0,0,0,0,0,0,0,~
0,0,0,0,0,0,0,0,0,0,0,0,0)';
      BIDIRECTIONAL='TRUE';
      INPUT_LOAD='(-0.01,0.01)';
      OUTPUT_LOAD='(1.0,-1.0)';
      PINUSE='BI';
    'DDR4_SA_DQ1':
      PIN_NUMBER='(0,0,0,0,0,0,0,0,0,0,0,EM77,0,0,0,0,0,0,0,0,0,0,0,0,0,0,0,0,0,~
0,0,0,0,0,0,0,0,0,0,0,0,0)';
      BIDIRECTIONAL='TRUE';
      INPUT_LOAD='(-0.01,0.01)';
      OUTPUT_LOAD='(1.0,-1.0)';
      PINUSE='BI';
    'DDR4_SA_DQ0':
      PIN_NUMBER='(0,0,0,0,0,0,0,0,0,0,0,EL78,0,0,0,0,0,0,0,0,0,0,0,0,0,0,0,0,0,~
0,0,0,0,0,0,0,0,0,0,0,0,0)';
      BIDIRECTIONAL='TRUE';
      INPUT_LOAD='(-0.01,0.01)';
      OUTPUT_LOAD='(1.0,-1.0)';
      PINUSE='BI';
    'DDR4_SA_DQS_DN9':
      PIN_NUMBER='(0,0,0,0,0,0,0,0,0,0,0,ET55,0,0,0,0,0,0,0,0,0,0,0,0,0,0,0,0,0,~
0,0,0,0,0,0,0,0,0,0,0,0,0)';
      BIDIRECTIONAL='TRUE';
      INPUT_LOAD='(-0.01,0.01)';
      OUTPUT_LOAD='(1.0,-1.0)';
      PINUSE='BI';
    'DDR4_SA_DQS_DN8':
      PIN_NUMBER='(0,0,0,0,0,0,0,0,0,0,0,ET61,0,0,0,0,0,0,0,0,0,0,0,0,0,0,0,0,0,~
0,0,0,0,0,0,0,0,0,0,0,0,0)';
      BIDIRECTIONAL='TRUE';
      INPUT_LOAD='(-0.01,0.01)';
      OUTPUT_LOAD='(1.0,-1.0)';
      PINUSE='BI';
    'DDR4_SA_DQS_DN7':
      PIN_NUMBER='(0,0,0,0,0,0,0,0,0,0,0,EN68,0,0,0,0,0,0,0,0,0,0,0,0,0,0,0,0,0,~
0,0,0,0,0,0,0,0,0,0,0,0,0)';
      BIDIRECTIONAL='TRUE';
      INPUT_LOAD='(-0.01,0.01)';
      OUTPUT_LOAD='(1.0,-1.0)';
      PINUSE='BI';
    'DDR4_SA_DQS_DN6':
      PIN_NUMBER='(0,0,0,0,0,0,0,0,0,0,0,EJ70,0,0,0,0,0,0,0,0,0,0,0,0,0,0,0,0,0,~
0,0,0,0,0,0,0,0,0,0,0,0,0)';
      BIDIRECTIONAL='TRUE';
      INPUT_LOAD='(-0.01,0.01)';
      OUTPUT_LOAD='(1.0,-1.0)';
      PINUSE='BI';
    'DDR4_SA_DQS_DN5':
      PIN_NUMBER='(0,0,0,0,0,0,0,0,0,0,0,EM75,0,0,0,0,0,0,0,0,0,0,0,0,0,0,0,0,0,~
0,0,0,0,0,0,0,0,0,0,0,0,0)';
      BIDIRECTIONAL='TRUE';
      INPUT_LOAD='(-0.01,0.01)';
      OUTPUT_LOAD='(1.0,-1.0)';
      PINUSE='BI';
    'DDR4_SA_DQS_DN4':
      PIN_NUMBER='(0,0,0,0,0,0,0,0,0,0,0,EM55,0,0,0,0,0,0,0,0,0,0,0,0,0,0,0,0,0,~
0,0,0,0,0,0,0,0,0,0,0,0,0)';
      BIDIRECTIONAL='TRUE';
      INPUT_LOAD='(-0.01,0.01)';
      OUTPUT_LOAD='(1.0,-1.0)';
      PINUSE='BI';
    'DDR4_SA_DQS_DN3':
      PIN_NUMBER='(0,0,0,0,0,0,0,0,0,0,0,EK61,0,0,0,0,0,0,0,0,0,0,0,0,0,0,0,0,0,~
0,0,0,0,0,0,0,0,0,0,0,0,0)';
      BIDIRECTIONAL='TRUE';
      INPUT_LOAD='(-0.01,0.01)';
      OUTPUT_LOAD='(1.0,-1.0)';
      PINUSE='BI';
    'DDR4_SA_DQS_DN2':
      PIN_NUMBER='(0,0,0,0,0,0,0,0,0,0,0,EK67,0,0,0,0,0,0,0,0,0,0,0,0,0,0,0,0,0,~
0,0,0,0,0,0,0,0,0,0,0,0,0)';
      BIDIRECTIONAL='TRUE';
      INPUT_LOAD='(-0.01,0.01)';
      OUTPUT_LOAD='(1.0,-1.0)';
      PINUSE='BI';
    'DDR4_SA_DQS_DN1':
      PIN_NUMBER='(0,0,0,0,0,0,0,0,0,0,0,EC70,0,0,0,0,0,0,0,0,0,0,0,0,0,0,0,0,0,~
0,0,0,0,0,0,0,0,0,0,0,0,0)';
      BIDIRECTIONAL='TRUE';
      INPUT_LOAD='(-0.01,0.01)';
      OUTPUT_LOAD='(1.0,-1.0)';
      PINUSE='BI';
    'DDR4_SA_DQS_DN0':
      PIN_NUMBER='(0,0,0,0,0,0,0,0,0,0,0,EP75,0,0,0,0,0,0,0,0,0,0,0,0,0,0,0,0,0,~
0,0,0,0,0,0,0,0,0,0,0,0,0)';
      BIDIRECTIONAL='TRUE';
      INPUT_LOAD='(-0.01,0.01)';
      OUTPUT_LOAD='(1.0,-1.0)';
      PINUSE='BI';
    'DDR4_SA_DQS_DP9':
      PIN_NUMBER='(0,0,0,0,0,0,0,0,0,0,0,EP55,0,0,0,0,0,0,0,0,0,0,0,0,0,0,0,0,0,~
0,0,0,0,0,0,0,0,0,0,0,0,0)';
      BIDIRECTIONAL='TRUE';
      INPUT_LOAD='(-0.01,0.01)';
      OUTPUT_LOAD='(1.0,-1.0)';
      PINUSE='BI';
    'DDR4_SA_DQS_DP8':
      PIN_NUMBER='(0,0,0,0,0,0,0,0,0,0,0,EP61,0,0,0,0,0,0,0,0,0,0,0,0,0,0,0,0,0,~
0,0,0,0,0,0,0,0,0,0,0,0,0)';
      BIDIRECTIONAL='TRUE';
      INPUT_LOAD='(-0.01,0.01)';
      OUTPUT_LOAD='(1.0,-1.0)';
      PINUSE='BI';
    'DDR4_SA_DQS_DP7':
      PIN_NUMBER='(0,0,0,0,0,0,0,0,0,0,0,EM67,0,0,0,0,0,0,0,0,0,0,0,0,0,0,0,0,0,~
0,0,0,0,0,0,0,0,0,0,0,0,0)';
      BIDIRECTIONAL='TRUE';
      INPUT_LOAD='(-0.01,0.01)';
      OUTPUT_LOAD='(1.0,-1.0)';
      PINUSE='BI';
    'DDR4_SA_DQS_DP6':
      PIN_NUMBER='(0,0,0,0,0,0,0,0,0,0,0,EG70,0,0,0,0,0,0,0,0,0,0,0,0,0,0,0,0,0,~
0,0,0,0,0,0,0,0,0,0,0,0,0)';
      BIDIRECTIONAL='TRUE';
      INPUT_LOAD='(-0.01,0.01)';
      OUTPUT_LOAD='(1.0,-1.0)';
      PINUSE='BI';
    'DDR4_SA_DQS_DP5':
      PIN_NUMBER='(0,0,0,0,0,0,0,0,0,0,0,EN74,0,0,0,0,0,0,0,0,0,0,0,0,0,0,0,0,0,~
0,0,0,0,0,0,0,0,0,0,0,0,0)';
      BIDIRECTIONAL='TRUE';
      INPUT_LOAD='(-0.01,0.01)';
      OUTPUT_LOAD='(1.0,-1.0)';
      PINUSE='BI';
    'DDR4_SA_DQS_DP4':
      PIN_NUMBER='(0,0,0,0,0,0,0,0,0,0,0,EK55,0,0,0,0,0,0,0,0,0,0,0,0,0,0,0,0,0,~
0,0,0,0,0,0,0,0,0,0,0,0,0)';
      BIDIRECTIONAL='TRUE';
      INPUT_LOAD='(-0.01,0.01)';
      OUTPUT_LOAD='(1.0,-1.0)';
      PINUSE='BI';
    'DDR4_SA_DQS_DP3':
      PIN_NUMBER='(0,0,0,0,0,0,0,0,0,0,0,EM61,0,0,0,0,0,0,0,0,0,0,0,0,0,0,0,0,0,~
0,0,0,0,0,0,0,0,0,0,0,0,0)';
      BIDIRECTIONAL='TRUE';
      INPUT_LOAD='(-0.01,0.01)';
      OUTPUT_LOAD='(1.0,-1.0)';
      PINUSE='BI';
    'DDR4_SA_DQS_DP2':
      PIN_NUMBER='(0,0,0,0,0,0,0,0,0,0,0,EL68,0,0,0,0,0,0,0,0,0,0,0,0,0,0,0,0,0,~
0,0,0,0,0,0,0,0,0,0,0,0,0)';
      BIDIRECTIONAL='TRUE';
      INPUT_LOAD='(-0.01,0.01)';
      OUTPUT_LOAD='(1.0,-1.0)';
      PINUSE='BI';
    'DDR4_SA_DQS_DP1':
      PIN_NUMBER='(0,0,0,0,0,0,0,0,0,0,0,EE70,0,0,0,0,0,0,0,0,0,0,0,0,0,0,0,0,0,~
0,0,0,0,0,0,0,0,0,0,0,0,0)';
      BIDIRECTIONAL='TRUE';
      INPUT_LOAD='(-0.01,0.01)';
      OUTPUT_LOAD='(1.0,-1.0)';
      PINUSE='BI';
    'DDR4_SA_DQS_DP0':
      PIN_NUMBER='(0,0,0,0,0,0,0,0,0,0,0,EN76,0,0,0,0,0,0,0,0,0,0,0,0,0,0,0,0,0,~
0,0,0,0,0,0,0,0,0,0,0,0,0)';
      BIDIRECTIONAL='TRUE';
      INPUT_LOAD='(-0.01,0.01)';
      OUTPUT_LOAD='(1.0,-1.0)';
      PINUSE='BI';
    'DDR4_SA_ECC7':
      PIN_NUMBER='(0,0,0,0,0,0,0,0,0,0,0,EP53,0,0,0,0,0,0,0,0,0,0,0,0,0,0,0,0,0,~
0,0,0,0,0,0,0,0,0,0,0,0,0)';
      BIDIRECTIONAL='TRUE';
      INPUT_LOAD='(-0.01,0.01)';
      OUTPUT_LOAD='(1.0,-1.0)';
      PINUSE='BI';
    'DDR4_SA_ECC6':
      PIN_NUMBER='(0,0,0,0,0,0,0,0,0,0,0,ER54,0,0,0,0,0,0,0,0,0,0,0,0,0,0,0,0,0,~
0,0,0,0,0,0,0,0,0,0,0,0,0)';
      BIDIRECTIONAL='TRUE';
      INPUT_LOAD='(-0.01,0.01)';
      OUTPUT_LOAD='(1.0,-1.0)';
      PINUSE='BI';
    'DDR4_SA_ECC5':
      PIN_NUMBER='(0,0,0,0,0,0,0,0,0,0,0,EM53,0,0,0,0,0,0,0,0,0,0,0,0,0,0,0,0,0,~
0,0,0,0,0,0,0,0,0,0,0,0,0)';
      BIDIRECTIONAL='TRUE';
      INPUT_LOAD='(-0.01,0.01)';
      OUTPUT_LOAD='(1.0,-1.0)';
      PINUSE='BI';
    'DDR4_SA_ECC4':
      PIN_NUMBER='(0,0,0,0,0,0,0,0,0,0,0,EL54,0,0,0,0,0,0,0,0,0,0,0,0,0,0,0,0,0,~
0,0,0,0,0,0,0,0,0,0,0,0,0)';
      BIDIRECTIONAL='TRUE';
      INPUT_LOAD='(-0.01,0.01)';
      OUTPUT_LOAD='(1.0,-1.0)';
      PINUSE='BI';
    'DDR4_SA_ECC3':
      PIN_NUMBER='(0,0,0,0,0,0,0,0,0,0,0,ER56,0,0,0,0,0,0,0,0,0,0,0,0,0,0,0,0,0,~
0,0,0,0,0,0,0,0,0,0,0,0,0)';
      BIDIRECTIONAL='TRUE';
      INPUT_LOAD='(-0.01,0.01)';
      OUTPUT_LOAD='(1.0,-1.0)';
      PINUSE='BI';
    'DDR4_SA_ECC2':
      PIN_NUMBER='(0,0,0,0,0,0,0,0,0,0,0,EP57,0,0,0,0,0,0,0,0,0,0,0,0,0,0,0,0,0,~
0,0,0,0,0,0,0,0,0,0,0,0,0)';
      BIDIRECTIONAL='TRUE';
      INPUT_LOAD='(-0.01,0.01)';
      OUTPUT_LOAD='(1.0,-1.0)';
      PINUSE='BI';
    'DDR4_SA_ECC1':
      PIN_NUMBER='(0,0,0,0,0,0,0,0,0,0,0,EL56,0,0,0,0,0,0,0,0,0,0,0,0,0,0,0,0,0,~
0,0,0,0,0,0,0,0,0,0,0,0,0)';
      BIDIRECTIONAL='TRUE';
      INPUT_LOAD='(-0.01,0.01)';
      OUTPUT_LOAD='(1.0,-1.0)';
      PINUSE='BI';
    'DDR4_SA_ECC0':
      PIN_NUMBER='(0,0,0,0,0,0,0,0,0,0,0,EM57,0,0,0,0,0,0,0,0,0,0,0,0,0,0,0,0,0,~
0,0,0,0,0,0,0,0,0,0,0,0,0)';
      BIDIRECTIONAL='TRUE';
      INPUT_LOAD='(-0.01,0.01)';
      OUTPUT_LOAD='(1.0,-1.0)';
      PINUSE='BI';
    'DDR4_SA_PAR':
      PIN_NUMBER='(0,0,0,0,0,0,0,0,0,0,0,EE43,0,0,0,0,0,0,0,0,0,0,0,0,0,0,0,0,0,~
0,0,0,0,0,0,0,0,0,0,0,0,0)';
      OUTPUT_LOAD='(1.0,-1.0)';
      PINUSE='OUT';
    'DDR4_SB_CA6':
      PIN_NUMBER='(0,0,0,0,0,0,0,0,0,0,0,EK42,0,0,0,0,0,0,0,0,0,0,0,0,0,0,0,0,0,~
0,0,0,0,0,0,0,0,0,0,0,0,0)';
      OUTPUT_LOAD='(1.0,-1.0)';
      PINUSE='OUT';
    'DDR4_SB_CA5':
      PIN_NUMBER='(0,0,0,0,0,0,0,0,0,0,0,ET42,0,0,0,0,0,0,0,0,0,0,0,0,0,0,0,0,0,~
0,0,0,0,0,0,0,0,0,0,0,0,0)';
      OUTPUT_LOAD='(1.0,-1.0)';
      PINUSE='OUT';
    'DDR4_SB_CA4':
      PIN_NUMBER='(0,0,0,0,0,0,0,0,0,0,0,EL43,0,0,0,0,0,0,0,0,0,0,0,0,0,0,0,0,0,~
0,0,0,0,0,0,0,0,0,0,0,0,0)';
      OUTPUT_LOAD='(1.0,-1.0)';
      PINUSE='OUT';
    'DDR4_SB_CA3':
      PIN_NUMBER='(0,0,0,0,0,0,0,0,0,0,0,EP44,0,0,0,0,0,0,0,0,0,0,0,0,0,0,0,0,0,~
0,0,0,0,0,0,0,0,0,0,0,0,0)';
      OUTPUT_LOAD='(1.0,-1.0)';
      PINUSE='OUT';
    'DDR4_SB_CA2':
      PIN_NUMBER='(0,0,0,0,0,0,0,0,0,0,0,EM44,0,0,0,0,0,0,0,0,0,0,0,0,0,0,0,0,0,~
0,0,0,0,0,0,0,0,0,0,0,0,0)';
      OUTPUT_LOAD='(1.0,-1.0)';
      PINUSE='OUT';
    'DDR4_SB_CA1':
      PIN_NUMBER='(0,0,0,0,0,0,0,0,0,0,0,EH44,0,0,0,0,0,0,0,0,0,0,0,0,0,0,0,0,0,~
0,0,0,0,0,0,0,0,0,0,0,0,0)';
      OUTPUT_LOAD='(1.0,-1.0)';
      PINUSE='OUT';
    'DDR4_SB_CA0':
      PIN_NUMBER='(0,0,0,0,0,0,0,0,0,0,0,EG43,0,0,0,0,0,0,0,0,0,0,0,0,0,0,0,0,0,~
0,0,0,0,0,0,0,0,0,0,0,0,0)';
      OUTPUT_LOAD='(1.0,-1.0)';
      PINUSE='OUT';
    'DDR4_SB_CS_N3':
      PIN_NUMBER='(0,0,0,0,0,0,0,0,0,0,0,EL41,0,0,0,0,0,0,0,0,0,0,0,0,0,0,0,0,0,~
0,0,0,0,0,0,0,0,0,0,0,0,0)';
      OUTPUT_LOAD='(1.0,-1.0)';
      PINUSE='OUT';
    'DDR4_SB_CS_N2':
      PIN_NUMBER='(0,0,0,0,0,0,0,0,0,0,0,EM40,0,0,0,0,0,0,0,0,0,0,0,0,0,0,0,0,0,~
0,0,0,0,0,0,0,0,0,0,0,0,0)';
      OUTPUT_LOAD='(1.0,-1.0)';
      PINUSE='OUT';
    'DDR4_SB_CS_N1':
      PIN_NUMBER='(0,0,0,0,0,0,0,0,0,0,0,ET40,0,0,0,0,0,0,0,0,0,0,0,0,0,0,0,0,0,~
0,0,0,0,0,0,0,0,0,0,0,0,0)';
      OUTPUT_LOAD='(1.0,-1.0)';
      PINUSE='OUT';
    'DDR4_SB_CS_N0':
      PIN_NUMBER='(0,0,0,0,0,0,0,0,0,0,0,EP40,0,0,0,0,0,0,0,0,0,0,0,0,0,0,0,0,0,~
0,0,0,0,0,0,0,0,0,0,0,0,0)';
      OUTPUT_LOAD='(1.0,-1.0)';
      PINUSE='OUT';
    'DDR4_SB_DQ31':
      PIN_NUMBER='(0,0,0,0,0,0,0,0,0,0,0,EP16,0,0,0,0,0,0,0,0,0,0,0,0,0,0,0,0,0,~
0,0,0,0,0,0,0,0,0,0,0,0,0)';
      BIDIRECTIONAL='TRUE';
      INPUT_LOAD='(-0.01,0.01)';
      OUTPUT_LOAD='(1.0,-1.0)';
      PINUSE='BI';
    'DDR4_SB_DQ30':
      PIN_NUMBER='(0,0,0,0,0,0,0,0,0,0,0,ER17,0,0,0,0,0,0,0,0,0,0,0,0,0,0,0,0,0,~
0,0,0,0,0,0,0,0,0,0,0,0,0)';
      BIDIRECTIONAL='TRUE';
      INPUT_LOAD='(-0.01,0.01)';
      OUTPUT_LOAD='(1.0,-1.0)';
      PINUSE='BI';
    'DDR4_SB_DQ29':
      PIN_NUMBER='(0,0,0,0,0,0,0,0,0,0,0,EM16,0,0,0,0,0,0,0,0,0,0,0,0,0,0,0,0,0,~
0,0,0,0,0,0,0,0,0,0,0,0,0)';
      BIDIRECTIONAL='TRUE';
      INPUT_LOAD='(-0.01,0.01)';
      OUTPUT_LOAD='(1.0,-1.0)';
      PINUSE='BI';
    'DDR4_SB_DQ28':
      PIN_NUMBER='(0,0,0,0,0,0,0,0,0,0,0,EL17,0,0,0,0,0,0,0,0,0,0,0,0,0,0,0,0,0,~
0,0,0,0,0,0,0,0,0,0,0,0,0)';
      BIDIRECTIONAL='TRUE';
      INPUT_LOAD='(-0.01,0.01)';
      OUTPUT_LOAD='(1.0,-1.0)';
      PINUSE='BI';
    'DDR4_SB_DQ27':
      PIN_NUMBER='(0,0,0,0,0,0,0,0,0,0,0,ER19,0,0,0,0,0,0,0,0,0,0,0,0,0,0,0,0,0,~
0,0,0,0,0,0,0,0,0,0,0,0,0)';
      BIDIRECTIONAL='TRUE';
      INPUT_LOAD='(-0.01,0.01)';
      OUTPUT_LOAD='(1.0,-1.0)';
      PINUSE='BI';
    'DDR4_SB_DQ26':
      PIN_NUMBER='(0,0,0,0,0,0,0,0,0,0,0,EP20,0,0,0,0,0,0,0,0,0,0,0,0,0,0,0,0,0,~
0,0,0,0,0,0,0,0,0,0,0,0,0)';
      BIDIRECTIONAL='TRUE';
      INPUT_LOAD='(-0.01,0.01)';
      OUTPUT_LOAD='(1.0,-1.0)';
      PINUSE='BI';
    'DDR4_SB_DQ25':
      PIN_NUMBER='(0,0,0,0,0,0,0,0,0,0,0,EL19,0,0,0,0,0,0,0,0,0,0,0,0,0,0,0,0,0,~
0,0,0,0,0,0,0,0,0,0,0,0,0)';
      BIDIRECTIONAL='TRUE';
      INPUT_LOAD='(-0.01,0.01)';
      OUTPUT_LOAD='(1.0,-1.0)';
      PINUSE='BI';
    'DDR4_SB_DQ24':
      PIN_NUMBER='(0,0,0,0,0,0,0,0,0,0,0,EM20,0,0,0,0,0,0,0,0,0,0,0,0,0,0,0,0,0,~
0,0,0,0,0,0,0,0,0,0,0,0,0)';
      BIDIRECTIONAL='TRUE';
      INPUT_LOAD='(-0.01,0.01)';
      OUTPUT_LOAD='(1.0,-1.0)';
      PINUSE='BI';
    'DDR4_SB_DQ23':
      PIN_NUMBER='(0,0,0,0,0,0,0,0,0,0,0,EP22,0,0,0,0,0,0,0,0,0,0,0,0,0,0,0,0,0,~
0,0,0,0,0,0,0,0,0,0,0,0,0)';
      BIDIRECTIONAL='TRUE';
      INPUT_LOAD='(-0.01,0.01)';
      OUTPUT_LOAD='(1.0,-1.0)';
      PINUSE='BI';
    'DDR4_SB_DQ22':
      PIN_NUMBER='(0,0,0,0,0,0,0,0,0,0,0,ER23,0,0,0,0,0,0,0,0,0,0,0,0,0,0,0,0,0,~
0,0,0,0,0,0,0,0,0,0,0,0,0)';
      BIDIRECTIONAL='TRUE';
      INPUT_LOAD='(-0.01,0.01)';
      OUTPUT_LOAD='(1.0,-1.0)';
      PINUSE='BI';
    'DDR4_SB_DQ21':
      PIN_NUMBER='(0,0,0,0,0,0,0,0,0,0,0,EM22,0,0,0,0,0,0,0,0,0,0,0,0,0,0,0,0,0,~
0,0,0,0,0,0,0,0,0,0,0,0,0)';
      BIDIRECTIONAL='TRUE';
      INPUT_LOAD='(-0.01,0.01)';
      OUTPUT_LOAD='(1.0,-1.0)';
      PINUSE='BI';
    'DDR4_SB_DQ20':
      PIN_NUMBER='(0,0,0,0,0,0,0,0,0,0,0,EL23,0,0,0,0,0,0,0,0,0,0,0,0,0,0,0,0,0,~
0,0,0,0,0,0,0,0,0,0,0,0,0)';
      BIDIRECTIONAL='TRUE';
      INPUT_LOAD='(-0.01,0.01)';
      OUTPUT_LOAD='(1.0,-1.0)';
      PINUSE='BI';
    'DDR4_SB_DQ19':
      PIN_NUMBER='(0,0,0,0,0,0,0,0,0,0,0,ER25,0,0,0,0,0,0,0,0,0,0,0,0,0,0,0,0,0,~
0,0,0,0,0,0,0,0,0,0,0,0,0)';
      BIDIRECTIONAL='TRUE';
      INPUT_LOAD='(-0.01,0.01)';
      OUTPUT_LOAD='(1.0,-1.0)';
      PINUSE='BI';
    'DDR4_SB_DQ18':
      PIN_NUMBER='(0,0,0,0,0,0,0,0,0,0,0,EP26,0,0,0,0,0,0,0,0,0,0,0,0,0,0,0,0,0,~
0,0,0,0,0,0,0,0,0,0,0,0,0)';
      BIDIRECTIONAL='TRUE';
      INPUT_LOAD='(-0.01,0.01)';
      OUTPUT_LOAD='(1.0,-1.0)';
      PINUSE='BI';
    'DDR4_SB_DQ17':
      PIN_NUMBER='(0,0,0,0,0,0,0,0,0,0,0,EL25,0,0,0,0,0,0,0,0,0,0,0,0,0,0,0,0,0,~
0,0,0,0,0,0,0,0,0,0,0,0,0)';
      BIDIRECTIONAL='TRUE';
      INPUT_LOAD='(-0.01,0.01)';
      OUTPUT_LOAD='(1.0,-1.0)';
      PINUSE='BI';
    'DDR4_SB_DQ16':
      PIN_NUMBER='(0,0,0,0,0,0,0,0,0,0,0,EM26,0,0,0,0,0,0,0,0,0,0,0,0,0,0,0,0,0,~
0,0,0,0,0,0,0,0,0,0,0,0,0)';
      BIDIRECTIONAL='TRUE';
      INPUT_LOAD='(-0.01,0.01)';
      OUTPUT_LOAD='(1.0,-1.0)';
      PINUSE='BI';
    'DDR4_SB_DQ15':
      PIN_NUMBER='(0,0,0,0,0,0,0,0,0,0,0,EP28,0,0,0,0,0,0,0,0,0,0,0,0,0,0,0,0,0,~
0,0,0,0,0,0,0,0,0,0,0,0,0)';
      BIDIRECTIONAL='TRUE';
      INPUT_LOAD='(-0.01,0.01)';
      OUTPUT_LOAD='(1.0,-1.0)';
      PINUSE='BI';
    'DDR4_SB_DQ14':
      PIN_NUMBER='(0,0,0,0,0,0,0,0,0,0,0,ER29,0,0,0,0,0,0,0,0,0,0,0,0,0,0,0,0,0,~
0,0,0,0,0,0,0,0,0,0,0,0,0)';
      BIDIRECTIONAL='TRUE';
      INPUT_LOAD='(-0.01,0.01)';
      OUTPUT_LOAD='(1.0,-1.0)';
      PINUSE='BI';
    'DDR4_SB_DQ13':
      PIN_NUMBER='(0,0,0,0,0,0,0,0,0,0,0,EM28,0,0,0,0,0,0,0,0,0,0,0,0,0,0,0,0,0,~
0,0,0,0,0,0,0,0,0,0,0,0,0)';
      BIDIRECTIONAL='TRUE';
      INPUT_LOAD='(-0.01,0.01)';
      OUTPUT_LOAD='(1.0,-1.0)';
      PINUSE='BI';
    'DDR4_SB_DQ12':
      PIN_NUMBER='(0,0,0,0,0,0,0,0,0,0,0,EL29,0,0,0,0,0,0,0,0,0,0,0,0,0,0,0,0,0,~
0,0,0,0,0,0,0,0,0,0,0,0,0)';
      BIDIRECTIONAL='TRUE';
      INPUT_LOAD='(-0.01,0.01)';
      OUTPUT_LOAD='(1.0,-1.0)';
      PINUSE='BI';
    'DDR4_SB_DQ11':
      PIN_NUMBER='(0,0,0,0,0,0,0,0,0,0,0,ER31,0,0,0,0,0,0,0,0,0,0,0,0,0,0,0,0,0,~
0,0,0,0,0,0,0,0,0,0,0,0,0)';
      BIDIRECTIONAL='TRUE';
      INPUT_LOAD='(-0.01,0.01)';
      OUTPUT_LOAD='(1.0,-1.0)';
      PINUSE='BI';
    'DDR4_SB_DQ10':
      PIN_NUMBER='(0,0,0,0,0,0,0,0,0,0,0,EP32,0,0,0,0,0,0,0,0,0,0,0,0,0,0,0,0,0,~
0,0,0,0,0,0,0,0,0,0,0,0,0)';
      BIDIRECTIONAL='TRUE';
      INPUT_LOAD='(-0.01,0.01)';
      OUTPUT_LOAD='(1.0,-1.0)';
      PINUSE='BI';
    'DDR4_SB_DQ9':
      PIN_NUMBER='(0,0,0,0,0,0,0,0,0,0,0,EL31,0,0,0,0,0,0,0,0,0,0,0,0,0,0,0,0,0,~
0,0,0,0,0,0,0,0,0,0,0,0,0)';
      BIDIRECTIONAL='TRUE';
      INPUT_LOAD='(-0.01,0.01)';
      OUTPUT_LOAD='(1.0,-1.0)';
      PINUSE='BI';
    'DDR4_SB_DQ8':
      PIN_NUMBER='(0,0,0,0,0,0,0,0,0,0,0,EM32,0,0,0,0,0,0,0,0,0,0,0,0,0,0,0,0,0,~
0,0,0,0,0,0,0,0,0,0,0,0,0)';
      BIDIRECTIONAL='TRUE';
      INPUT_LOAD='(-0.01,0.01)';
      OUTPUT_LOAD='(1.0,-1.0)';
      PINUSE='BI';
    'DDR4_SB_DQ7':
      PIN_NUMBER='(0,0,0,0,0,0,0,0,0,0,0,EG25,0,0,0,0,0,0,0,0,0,0,0,0,0,0,0,0,0,~
0,0,0,0,0,0,0,0,0,0,0,0,0)';
      BIDIRECTIONAL='TRUE';
      INPUT_LOAD='(-0.01,0.01)';
      OUTPUT_LOAD='(1.0,-1.0)';
      PINUSE='BI';
    'DDR4_SB_DQ6':
      PIN_NUMBER='(0,0,0,0,0,0,0,0,0,0,0,EH26,0,0,0,0,0,0,0,0,0,0,0,0,0,0,0,0,0,~
0,0,0,0,0,0,0,0,0,0,0,0,0)';
      BIDIRECTIONAL='TRUE';
      INPUT_LOAD='(-0.01,0.01)';
      OUTPUT_LOAD='(1.0,-1.0)';
      PINUSE='BI';
    'DDR4_SB_DQ5':
      PIN_NUMBER='(0,0,0,0,0,0,0,0,0,0,0,EE25,0,0,0,0,0,0,0,0,0,0,0,0,0,0,0,0,0,~
0,0,0,0,0,0,0,0,0,0,0,0,0)';
      BIDIRECTIONAL='TRUE';
      INPUT_LOAD='(-0.01,0.01)';
      OUTPUT_LOAD='(1.0,-1.0)';
      PINUSE='BI';
    'DDR4_SB_DQ4':
      PIN_NUMBER='(0,0,0,0,0,0,0,0,0,0,0,ED26,0,0,0,0,0,0,0,0,0,0,0,0,0,0,0,0,0,~
0,0,0,0,0,0,0,0,0,0,0,0,0)';
      BIDIRECTIONAL='TRUE';
      INPUT_LOAD='(-0.01,0.01)';
      OUTPUT_LOAD='(1.0,-1.0)';
      PINUSE='BI';
    'DDR4_SB_DQ3':
      PIN_NUMBER='(0,0,0,0,0,0,0,0,0,0,0,EH28,0,0,0,0,0,0,0,0,0,0,0,0,0,0,0,0,0,~
0,0,0,0,0,0,0,0,0,0,0,0,0)';
      BIDIRECTIONAL='TRUE';
      INPUT_LOAD='(-0.01,0.01)';
      OUTPUT_LOAD='(1.0,-1.0)';
      PINUSE='BI';
    'DDR4_SB_DQ2':
      PIN_NUMBER='(0,0,0,0,0,0,0,0,0,0,0,EG29,0,0,0,0,0,0,0,0,0,0,0,0,0,0,0,0,0,~
0,0,0,0,0,0,0,0,0,0,0,0,0)';
      BIDIRECTIONAL='TRUE';
      INPUT_LOAD='(-0.01,0.01)';
      OUTPUT_LOAD='(1.0,-1.0)';
      PINUSE='BI';
    'DDR4_SB_DQ1':
      PIN_NUMBER='(0,0,0,0,0,0,0,0,0,0,0,ED28,0,0,0,0,0,0,0,0,0,0,0,0,0,0,0,0,0,~
0,0,0,0,0,0,0,0,0,0,0,0,0)';
      BIDIRECTIONAL='TRUE';
      INPUT_LOAD='(-0.01,0.01)';
      OUTPUT_LOAD='(1.0,-1.0)';
      PINUSE='BI';
    'DDR4_SB_DQ0':
      PIN_NUMBER='(0,0,0,0,0,0,0,0,0,0,0,EE29,0,0,0,0,0,0,0,0,0,0,0,0,0,0,0,0,0,~
0,0,0,0,0,0,0,0,0,0,0,0,0)';
      BIDIRECTIONAL='TRUE';
      INPUT_LOAD='(-0.01,0.01)';
      OUTPUT_LOAD='(1.0,-1.0)';
      PINUSE='BI';
    'DDR4_SB_DQS_DN9':
      PIN_NUMBER='(0,0,0,0,0,0,0,0,0,0,0,EK36,0,0,0,0,0,0,0,0,0,0,0,0,0,0,0,0,0,~
0,0,0,0,0,0,0,0,0,0,0,0,0)';
      BIDIRECTIONAL='TRUE';
      INPUT_LOAD='(-0.01,0.01)';
      OUTPUT_LOAD='(1.0,-1.0)';
      PINUSE='BI';
    'DDR4_SB_DQS_DN8':
      PIN_NUMBER='(0,0,0,0,0,0,0,0,0,0,0,ET18,0,0,0,0,0,0,0,0,0,0,0,0,0,0,0,0,0,~
0,0,0,0,0,0,0,0,0,0,0,0,0)';
      BIDIRECTIONAL='TRUE';
      INPUT_LOAD='(-0.01,0.01)';
      OUTPUT_LOAD='(1.0,-1.0)';
      PINUSE='BI';
    'DDR4_SB_DQS_DN7':
      PIN_NUMBER='(0,0,0,0,0,0,0,0,0,0,0,ET24,0,0,0,0,0,0,0,0,0,0,0,0,0,0,0,0,0,~
0,0,0,0,0,0,0,0,0,0,0,0,0)';
      BIDIRECTIONAL='TRUE';
      INPUT_LOAD='(-0.01,0.01)';
      OUTPUT_LOAD='(1.0,-1.0)';
      PINUSE='BI';
    'DDR4_SB_DQS_DN6':
      PIN_NUMBER='(0,0,0,0,0,0,0,0,0,0,0,ET30,0,0,0,0,0,0,0,0,0,0,0,0,0,0,0,0,0,~
0,0,0,0,0,0,0,0,0,0,0,0,0)';
      BIDIRECTIONAL='TRUE';
      INPUT_LOAD='(-0.01,0.01)';
      OUTPUT_LOAD='(1.0,-1.0)';
      PINUSE='BI';
    'DDR4_SB_DQS_DN5':
      PIN_NUMBER='(0,0,0,0,0,0,0,0,0,0,0,EJ27,0,0,0,0,0,0,0,0,0,0,0,0,0,0,0,0,0,~
0,0,0,0,0,0,0,0,0,0,0,0,0)';
      BIDIRECTIONAL='TRUE';
      INPUT_LOAD='(-0.01,0.01)';
      OUTPUT_LOAD='(1.0,-1.0)';
      PINUSE='BI';
    'DDR4_SB_DQS_DN4':
      PIN_NUMBER='(0,0,0,0,0,0,0,0,0,0,0,ET36,0,0,0,0,0,0,0,0,0,0,0,0,0,0,0,0,0,~
0,0,0,0,0,0,0,0,0,0,0,0,0)';
      BIDIRECTIONAL='TRUE';
      INPUT_LOAD='(-0.01,0.01)';
      OUTPUT_LOAD='(1.0,-1.0)';
      PINUSE='BI';
    'DDR4_SB_DQS_DN3':
      PIN_NUMBER='(0,0,0,0,0,0,0,0,0,0,0,EK18,0,0,0,0,0,0,0,0,0,0,0,0,0,0,0,0,0,~
0,0,0,0,0,0,0,0,0,0,0,0,0)';
      BIDIRECTIONAL='TRUE';
      INPUT_LOAD='(-0.01,0.01)';
      OUTPUT_LOAD='(1.0,-1.0)';
      PINUSE='BI';
    'DDR4_SB_DQS_DN2':
      PIN_NUMBER='(0,0,0,0,0,0,0,0,0,0,0,EK24,0,0,0,0,0,0,0,0,0,0,0,0,0,0,0,0,0,~
0,0,0,0,0,0,0,0,0,0,0,0,0)';
      BIDIRECTIONAL='TRUE';
      INPUT_LOAD='(-0.01,0.01)';
      OUTPUT_LOAD='(1.0,-1.0)';
      PINUSE='BI';
    'DDR4_SB_DQS_DN1':
      PIN_NUMBER='(0,0,0,0,0,0,0,0,0,0,0,EK30,0,0,0,0,0,0,0,0,0,0,0,0,0,0,0,0,0,~
0,0,0,0,0,0,0,0,0,0,0,0,0)';
      BIDIRECTIONAL='TRUE';
      INPUT_LOAD='(-0.01,0.01)';
      OUTPUT_LOAD='(1.0,-1.0)';
      PINUSE='BI';
    'DDR4_SB_DQS_DN0':
      PIN_NUMBER='(0,0,0,0,0,0,0,0,0,0,0,EE27,0,0,0,0,0,0,0,0,0,0,0,0,0,0,0,0,0,~
0,0,0,0,0,0,0,0,0,0,0,0,0)';
      BIDIRECTIONAL='TRUE';
      INPUT_LOAD='(-0.01,0.01)';
      OUTPUT_LOAD='(1.0,-1.0)';
      PINUSE='BI';
    'DDR4_SB_DQS_DP9':
      PIN_NUMBER='(0,0,0,0,0,0,0,0,0,0,0,EM36,0,0,0,0,0,0,0,0,0,0,0,0,0,0,0,0,0,~
0,0,0,0,0,0,0,0,0,0,0,0,0)';
      BIDIRECTIONAL='TRUE';
      INPUT_LOAD='(-0.01,0.01)';
      OUTPUT_LOAD='(1.0,-1.0)';
      PINUSE='BI';
    'DDR4_SB_DQS_DP8':
      PIN_NUMBER='(0,0,0,0,0,0,0,0,0,0,0,EP18,0,0,0,0,0,0,0,0,0,0,0,0,0,0,0,0,0,~
0,0,0,0,0,0,0,0,0,0,0,0,0)';
      BIDIRECTIONAL='TRUE';
      INPUT_LOAD='(-0.01,0.01)';
      OUTPUT_LOAD='(1.0,-1.0)';
      PINUSE='BI';
    'DDR4_SB_DQS_DP7':
      PIN_NUMBER='(0,0,0,0,0,0,0,0,0,0,0,EP24,0,0,0,0,0,0,0,0,0,0,0,0,0,0,0,0,0,~
0,0,0,0,0,0,0,0,0,0,0,0,0)';
      BIDIRECTIONAL='TRUE';
      INPUT_LOAD='(-0.01,0.01)';
      OUTPUT_LOAD='(1.0,-1.0)';
      PINUSE='BI';
    'DDR4_SB_DQS_DP6':
      PIN_NUMBER='(0,0,0,0,0,0,0,0,0,0,0,EP30,0,0,0,0,0,0,0,0,0,0,0,0,0,0,0,0,0,~
0,0,0,0,0,0,0,0,0,0,0,0,0)';
      BIDIRECTIONAL='TRUE';
      INPUT_LOAD='(-0.01,0.01)';
      OUTPUT_LOAD='(1.0,-1.0)';
      PINUSE='BI';
    'DDR4_SB_DQS_DP5':
      PIN_NUMBER='(0,0,0,0,0,0,0,0,0,0,0,EG27,0,0,0,0,0,0,0,0,0,0,0,0,0,0,0,0,0,~
0,0,0,0,0,0,0,0,0,0,0,0,0)';
      BIDIRECTIONAL='TRUE';
      INPUT_LOAD='(-0.01,0.01)';
      OUTPUT_LOAD='(1.0,-1.0)';
      PINUSE='BI';
    'DDR4_SB_DQS_DP4':
      PIN_NUMBER='(0,0,0,0,0,0,0,0,0,0,0,EP36,0,0,0,0,0,0,0,0,0,0,0,0,0,0,0,0,0,~
0,0,0,0,0,0,0,0,0,0,0,0,0)';
      BIDIRECTIONAL='TRUE';
      INPUT_LOAD='(-0.01,0.01)';
      OUTPUT_LOAD='(1.0,-1.0)';
      PINUSE='BI';
    'DDR4_SB_DQS_DP3':
      PIN_NUMBER='(0,0,0,0,0,0,0,0,0,0,0,EM18,0,0,0,0,0,0,0,0,0,0,0,0,0,0,0,0,0,~
0,0,0,0,0,0,0,0,0,0,0,0,0)';
      BIDIRECTIONAL='TRUE';
      INPUT_LOAD='(-0.01,0.01)';
      OUTPUT_LOAD='(1.0,-1.0)';
      PINUSE='BI';
    'DDR4_SB_DQS_DP2':
      PIN_NUMBER='(0,0,0,0,0,0,0,0,0,0,0,EM24,0,0,0,0,0,0,0,0,0,0,0,0,0,0,0,0,0,~
0,0,0,0,0,0,0,0,0,0,0,0,0)';
      BIDIRECTIONAL='TRUE';
      INPUT_LOAD='(-0.01,0.01)';
      OUTPUT_LOAD='(1.0,-1.0)';
      PINUSE='BI';
    'DDR4_SB_DQS_DP1':
      PIN_NUMBER='(0,0,0,0,0,0,0,0,0,0,0,EM30,0,0,0,0,0,0,0,0,0,0,0,0,0,0,0,0,0,~
0,0,0,0,0,0,0,0,0,0,0,0,0)';
      BIDIRECTIONAL='TRUE';
      INPUT_LOAD='(-0.01,0.01)';
      OUTPUT_LOAD='(1.0,-1.0)';
      PINUSE='BI';
    'DDR4_SB_DQS_DP0':
      PIN_NUMBER='(0,0,0,0,0,0,0,0,0,0,0,EC27,0,0,0,0,0,0,0,0,0,0,0,0,0,0,0,0,0,~
0,0,0,0,0,0,0,0,0,0,0,0,0)';
      BIDIRECTIONAL='TRUE';
      INPUT_LOAD='(-0.01,0.01)';
      OUTPUT_LOAD='(1.0,-1.0)';
      PINUSE='BI';
    'DDR4_SB_ECC7':
      PIN_NUMBER='(0,0,0,0,0,0,0,0,0,0,0,ER37,0,0,0,0,0,0,0,0,0,0,0,0,0,0,0,0,0,~
0,0,0,0,0,0,0,0,0,0,0,0,0)';
      BIDIRECTIONAL='TRUE';
      INPUT_LOAD='(-0.01,0.01)';
      OUTPUT_LOAD='(1.0,-1.0)';
      PINUSE='BI';
    'DDR4_SB_ECC6':
      PIN_NUMBER='(0,0,0,0,0,0,0,0,0,0,0,EP38,0,0,0,0,0,0,0,0,0,0,0,0,0,0,0,0,0,~
0,0,0,0,0,0,0,0,0,0,0,0,0)';
      BIDIRECTIONAL='TRUE';
      INPUT_LOAD='(-0.01,0.01)';
      OUTPUT_LOAD='(1.0,-1.0)';
      PINUSE='BI';
    'DDR4_SB_ECC5':
      PIN_NUMBER='(0,0,0,0,0,0,0,0,0,0,0,EL37,0,0,0,0,0,0,0,0,0,0,0,0,0,0,0,0,0,~
0,0,0,0,0,0,0,0,0,0,0,0,0)';
      BIDIRECTIONAL='TRUE';
      INPUT_LOAD='(-0.01,0.01)';
      OUTPUT_LOAD='(1.0,-1.0)';
      PINUSE='BI';
    'DDR4_SB_ECC4':
      PIN_NUMBER='(0,0,0,0,0,0,0,0,0,0,0,EM38,0,0,0,0,0,0,0,0,0,0,0,0,0,0,0,0,0,~
0,0,0,0,0,0,0,0,0,0,0,0,0)';
      BIDIRECTIONAL='TRUE';
      INPUT_LOAD='(-0.01,0.01)';
      OUTPUT_LOAD='(1.0,-1.0)';
      PINUSE='BI';
    'DDR4_SB_ECC3':
      PIN_NUMBER='(0,0,0,0,0,0,0,0,0,0,0,EP34,0,0,0,0,0,0,0,0,0,0,0,0,0,0,0,0,0,~
0,0,0,0,0,0,0,0,0,0,0,0,0)';
      BIDIRECTIONAL='TRUE';
      INPUT_LOAD='(-0.01,0.01)';
      OUTPUT_LOAD='(1.0,-1.0)';
      PINUSE='BI';
    'DDR4_SB_ECC2':
      PIN_NUMBER='(0,0,0,0,0,0,0,0,0,0,0,ER35,0,0,0,0,0,0,0,0,0,0,0,0,0,0,0,0,0,~
0,0,0,0,0,0,0,0,0,0,0,0,0)';
      BIDIRECTIONAL='TRUE';
      INPUT_LOAD='(-0.01,0.01)';
      OUTPUT_LOAD='(1.0,-1.0)';
      PINUSE='BI';
    'DDR4_SB_ECC1':
      PIN_NUMBER='(0,0,0,0,0,0,0,0,0,0,0,EM34,0,0,0,0,0,0,0,0,0,0,0,0,0,0,0,0,0,~
0,0,0,0,0,0,0,0,0,0,0,0,0)';
      BIDIRECTIONAL='TRUE';
      INPUT_LOAD='(-0.01,0.01)';
      OUTPUT_LOAD='(1.0,-1.0)';
      PINUSE='BI';
    'DDR4_SB_ECC0':
      PIN_NUMBER='(0,0,0,0,0,0,0,0,0,0,0,EL35,0,0,0,0,0,0,0,0,0,0,0,0,0,0,0,0,0,~
0,0,0,0,0,0,0,0,0,0,0,0,0)';
      BIDIRECTIONAL='TRUE';
      INPUT_LOAD='(-0.01,0.01)';
      OUTPUT_LOAD='(1.0,-1.0)';
      PINUSE='BI';
    'DDR4_SB_PAR':
      PIN_NUMBER='(0,0,0,0,0,0,0,0,0,0,0,EP42,0,0,0,0,0,0,0,0,0,0,0,0,0,0,0,0,0,~
0,0,0,0,0,0,0,0,0,0,0,0,0)';
      OUTPUT_LOAD='(1.0,-1.0)';
      PINUSE='OUT';
    'DDR5_ALERT_N':
      PIN_NUMBER='(0,0,0,0,0,0,0,0,0,0,0,0,CW48,0,0,0,0,0,0,0,0,0,0,0,0,0,0,0,0,~
0,0,0,0,0,0,0,0,0,0,0,0,0)';
      INPUT_LOAD='(-0.01,0.01)';
      PINUSE='IN';
    'DDR5_A_RSP1':
      PIN_NUMBER='(0,0,0,0,0,0,0,0,0,0,0,0,DP47,0,0,0,0,0,0,0,0,0,0,0,0,0,0,0,0,~
0,0,0,0,0,0,0,0,0,0,0,0,0)';
      INPUT_LOAD='(-0.01,0.01)';
      PINUSE='IN';
    'DDR5_A_RSP0':
      PIN_NUMBER='(0,0,0,0,0,0,0,0,0,0,0,0,DN48,0,0,0,0,0,0,0,0,0,0,0,0,0,0,0,0,~
0,0,0,0,0,0,0,0,0,0,0,0,0)';
      INPUT_LOAD='(-0.01,0.01)';
      PINUSE='IN';
    'DDR5_B_RSP1':
      PIN_NUMBER='(0,0,0,0,0,0,0,0,0,0,0,0,DK47,0,0,0,0,0,0,0,0,0,0,0,0,0,0,0,0,~
0,0,0,0,0,0,0,0,0,0,0,0,0)';
      INPUT_LOAD='(-0.01,0.01)';
      PINUSE='IN';
    'DDR5_B_RSP0':
      PIN_NUMBER='(0,0,0,0,0,0,0,0,0,0,0,0,DL48,0,0,0,0,0,0,0,0,0,0,0,0,0,0,0,0,~
0,0,0,0,0,0,0,0,0,0,0,0,0)';
      INPUT_LOAD='(-0.01,0.01)';
      PINUSE='IN';
    'DDR5_CLK_DN1':
      PIN_NUMBER='(0,0,0,0,0,0,0,0,0,0,0,0,DV49,0,0,0,0,0,0,0,0,0,0,0,0,0,0,0,0,~
0,0,0,0,0,0,0,0,0,0,0,0,0)';
      OUTPUT_LOAD='(1.0,-1.0)';
      PINUSE='OUT';
    'DDR5_CLK_DN0':
      PIN_NUMBER='(0,0,0,0,0,0,0,0,0,0,0,0,DY49,0,0,0,0,0,0,0,0,0,0,0,0,0,0,0,0,~
0,0,0,0,0,0,0,0,0,0,0,0,0)';
      OUTPUT_LOAD='(1.0,-1.0)';
      PINUSE='OUT';
    'DDR5_CLK_DP1':
      PIN_NUMBER='(0,0,0,0,0,0,0,0,0,0,0,0,DT49,0,0,0,0,0,0,0,0,0,0,0,0,0,0,0,0,~
0,0,0,0,0,0,0,0,0,0,0,0,0)';
      OUTPUT_LOAD='(1.0,-1.0)';
      PINUSE='OUT';
    'DDR5_CLK_DP0':
      PIN_NUMBER='(0,0,0,0,0,0,0,0,0,0,0,0,EB49,0,0,0,0,0,0,0,0,0,0,0,0,0,0,0,0,~
0,0,0,0,0,0,0,0,0,0,0,0,0)';
      OUTPUT_LOAD='(1.0,-1.0)';
      PINUSE='OUT';
    'DDR5_SA_CA6':
      PIN_NUMBER='(0,0,0,0,0,0,0,0,0,0,0,0,DY51,0,0,0,0,0,0,0,0,0,0,0,0,0,0,0,0,~
0,0,0,0,0,0,0,0,0,0,0,0,0)';
      OUTPUT_LOAD='(1.0,-1.0)';
      PINUSE='OUT';
    'DDR5_SA_CA5':
      PIN_NUMBER='(0,0,0,0,0,0,0,0,0,0,0,0,EG50,0,0,0,0,0,0,0,0,0,0,0,0,0,0,0,0,~
0,0,0,0,0,0,0,0,0,0,0,0,0)';
      OUTPUT_LOAD='(1.0,-1.0)';
      PINUSE='OUT';
    'DDR5_SA_CA4':
      PIN_NUMBER='(0,0,0,0,0,0,0,0,0,0,0,0,EE50,0,0,0,0,0,0,0,0,0,0,0,0,0,0,0,0,~
0,0,0,0,0,0,0,0,0,0,0,0,0)';
      OUTPUT_LOAD='(1.0,-1.0)';
      PINUSE='OUT';
    'DDR5_SA_CA3':
      PIN_NUMBER='(0,0,0,0,0,0,0,0,0,0,0,0,EH51,0,0,0,0,0,0,0,0,0,0,0,0,0,0,0,0,~
0,0,0,0,0,0,0,0,0,0,0,0,0)';
      OUTPUT_LOAD='(1.0,-1.0)';
      PINUSE='OUT';
    'DDR5_SA_CA2':
      PIN_NUMBER='(0,0,0,0,0,0,0,0,0,0,0,0,ED51,0,0,0,0,0,0,0,0,0,0,0,0,0,0,0,0,~
0,0,0,0,0,0,0,0,0,0,0,0,0)';
      OUTPUT_LOAD='(1.0,-1.0)';
      PINUSE='OUT';
    'DDR5_SA_CA1':
      PIN_NUMBER='(0,0,0,0,0,0,0,0,0,0,0,0,EJ52,0,0,0,0,0,0,0,0,0,0,0,0,0,0,0,0,~
0,0,0,0,0,0,0,0,0,0,0,0,0)';
      OUTPUT_LOAD='(1.0,-1.0)';
      PINUSE='OUT';
    'DDR5_SA_CA0':
      PIN_NUMBER='(0,0,0,0,0,0,0,0,0,0,0,0,EC52,0,0,0,0,0,0,0,0,0,0,0,0,0,0,0,0,~
0,0,0,0,0,0,0,0,0,0,0,0,0)';
      OUTPUT_LOAD='(1.0,-1.0)';
      PINUSE='OUT';
    'DDR5_SA_CS_N3':
      PIN_NUMBER='(0,0,0,0,0,0,0,0,0,0,0,0,ED53,0,0,0,0,0,0,0,0,0,0,0,0,0,0,0,0,~
0,0,0,0,0,0,0,0,0,0,0,0,0)';
      OUTPUT_LOAD='(1.0,-1.0)';
      PINUSE='OUT';
    'DDR5_SA_CS_N2':
      PIN_NUMBER='(0,0,0,0,0,0,0,0,0,0,0,0,EE54,0,0,0,0,0,0,0,0,0,0,0,0,0,0,0,0,~
0,0,0,0,0,0,0,0,0,0,0,0,0)';
      OUTPUT_LOAD='(1.0,-1.0)';
      PINUSE='OUT';
    'DDR5_SA_CS_N1':
      PIN_NUMBER='(0,0,0,0,0,0,0,0,0,0,0,0,EH53,0,0,0,0,0,0,0,0,0,0,0,0,0,0,0,0,~
0,0,0,0,0,0,0,0,0,0,0,0,0)';
      OUTPUT_LOAD='(1.0,-1.0)';
      PINUSE='OUT';
    'DDR5_SA_CS_N0':
      PIN_NUMBER='(0,0,0,0,0,0,0,0,0,0,0,0,EG54,0,0,0,0,0,0,0,0,0,0,0,0,0,0,0,0,~
0,0,0,0,0,0,0,0,0,0,0,0,0)';
      OUTPUT_LOAD='(1.0,-1.0)';
      PINUSE='OUT';
    'DDR5_SA_DQ31':
      PIN_NUMBER='(0,0,0,0,0,0,0,0,0,0,0,0,DY53,0,0,0,0,0,0,0,0,0,0,0,0,0,0,0,0,~
0,0,0,0,0,0,0,0,0,0,0,0,0)';
      BIDIRECTIONAL='TRUE';
      INPUT_LOAD='(-0.01,0.01)';
      OUTPUT_LOAD='(1.0,-1.0)';
      PINUSE='BI';
    'DDR5_SA_DQ30':
      PIN_NUMBER='(0,0,0,0,0,0,0,0,0,0,0,0,EA54,0,0,0,0,0,0,0,0,0,0,0,0,0,0,0,0,~
0,0,0,0,0,0,0,0,0,0,0,0,0)';
      BIDIRECTIONAL='TRUE';
      INPUT_LOAD='(-0.01,0.01)';
      OUTPUT_LOAD='(1.0,-1.0)';
      PINUSE='BI';
    'DDR5_SA_DQ29':
      PIN_NUMBER='(0,0,0,0,0,0,0,0,0,0,0,0,DV53,0,0,0,0,0,0,0,0,0,0,0,0,0,0,0,0,~
0,0,0,0,0,0,0,0,0,0,0,0,0)';
      BIDIRECTIONAL='TRUE';
      INPUT_LOAD='(-0.01,0.01)';
      OUTPUT_LOAD='(1.0,-1.0)';
      PINUSE='BI';
    'DDR5_SA_DQ28':
      PIN_NUMBER='(0,0,0,0,0,0,0,0,0,0,0,0,DU54,0,0,0,0,0,0,0,0,0,0,0,0,0,0,0,0,~
0,0,0,0,0,0,0,0,0,0,0,0,0)';
      BIDIRECTIONAL='TRUE';
      INPUT_LOAD='(-0.01,0.01)';
      OUTPUT_LOAD='(1.0,-1.0)';
      PINUSE='BI';
    'DDR5_SA_DQ27':
      PIN_NUMBER='(0,0,0,0,0,0,0,0,0,0,0,0,EA56,0,0,0,0,0,0,0,0,0,0,0,0,0,0,0,0,~
0,0,0,0,0,0,0,0,0,0,0,0,0)';
      BIDIRECTIONAL='TRUE';
      INPUT_LOAD='(-0.01,0.01)';
      OUTPUT_LOAD='(1.0,-1.0)';
      PINUSE='BI';
    'DDR5_SA_DQ26':
      PIN_NUMBER='(0,0,0,0,0,0,0,0,0,0,0,0,DY57,0,0,0,0,0,0,0,0,0,0,0,0,0,0,0,0,~
0,0,0,0,0,0,0,0,0,0,0,0,0)';
      BIDIRECTIONAL='TRUE';
      INPUT_LOAD='(-0.01,0.01)';
      OUTPUT_LOAD='(1.0,-1.0)';
      PINUSE='BI';
    'DDR5_SA_DQ25':
      PIN_NUMBER='(0,0,0,0,0,0,0,0,0,0,0,0,DU56,0,0,0,0,0,0,0,0,0,0,0,0,0,0,0,0,~
0,0,0,0,0,0,0,0,0,0,0,0,0)';
      BIDIRECTIONAL='TRUE';
      INPUT_LOAD='(-0.01,0.01)';
      OUTPUT_LOAD='(1.0,-1.0)';
      PINUSE='BI';
    'DDR5_SA_DQ24':
      PIN_NUMBER='(0,0,0,0,0,0,0,0,0,0,0,0,DV57,0,0,0,0,0,0,0,0,0,0,0,0,0,0,0,0,~
0,0,0,0,0,0,0,0,0,0,0,0,0)';
      BIDIRECTIONAL='TRUE';
      INPUT_LOAD='(-0.01,0.01)';
      OUTPUT_LOAD='(1.0,-1.0)';
      PINUSE='BI';
    'DDR5_SA_DQ23':
      PIN_NUMBER='(0,0,0,0,0,0,0,0,0,0,0,0,EG62,0,0,0,0,0,0,0,0,0,0,0,0,0,0,0,0,~
0,0,0,0,0,0,0,0,0,0,0,0,0)';
      BIDIRECTIONAL='TRUE';
      INPUT_LOAD='(-0.01,0.01)';
      OUTPUT_LOAD='(1.0,-1.0)';
      PINUSE='BI';
    'DDR5_SA_DQ22':
      PIN_NUMBER='(0,0,0,0,0,0,0,0,0,0,0,0,EH63,0,0,0,0,0,0,0,0,0,0,0,0,0,0,0,0,~
0,0,0,0,0,0,0,0,0,0,0,0,0)';
      BIDIRECTIONAL='TRUE';
      INPUT_LOAD='(-0.01,0.01)';
      OUTPUT_LOAD='(1.0,-1.0)';
      PINUSE='BI';
    'DDR5_SA_DQ21':
      PIN_NUMBER='(0,0,0,0,0,0,0,0,0,0,0,0,EE62,0,0,0,0,0,0,0,0,0,0,0,0,0,0,0,0,~
0,0,0,0,0,0,0,0,0,0,0,0,0)';
      BIDIRECTIONAL='TRUE';
      INPUT_LOAD='(-0.01,0.01)';
      OUTPUT_LOAD='(1.0,-1.0)';
      PINUSE='BI';
    'DDR5_SA_DQ20':
      PIN_NUMBER='(0,0,0,0,0,0,0,0,0,0,0,0,ED63,0,0,0,0,0,0,0,0,0,0,0,0,0,0,0,0,~
0,0,0,0,0,0,0,0,0,0,0,0,0)';
      BIDIRECTIONAL='TRUE';
      INPUT_LOAD='(-0.01,0.01)';
      OUTPUT_LOAD='(1.0,-1.0)';
      PINUSE='BI';
    'DDR5_SA_DQ19':
      PIN_NUMBER='(0,0,0,0,0,0,0,0,0,0,0,0,EH65,0,0,0,0,0,0,0,0,0,0,0,0,0,0,0,0,~
0,0,0,0,0,0,0,0,0,0,0,0,0)';
      BIDIRECTIONAL='TRUE';
      INPUT_LOAD='(-0.01,0.01)';
      OUTPUT_LOAD='(1.0,-1.0)';
      PINUSE='BI';
    'DDR5_SA_DQ18':
      PIN_NUMBER='(0,0,0,0,0,0,0,0,0,0,0,0,EG66,0,0,0,0,0,0,0,0,0,0,0,0,0,0,0,0,~
0,0,0,0,0,0,0,0,0,0,0,0,0)';
      BIDIRECTIONAL='TRUE';
      INPUT_LOAD='(-0.01,0.01)';
      OUTPUT_LOAD='(1.0,-1.0)';
      PINUSE='BI';
    'DDR5_SA_DQ17':
      PIN_NUMBER='(0,0,0,0,0,0,0,0,0,0,0,0,ED65,0,0,0,0,0,0,0,0,0,0,0,0,0,0,0,0,~
0,0,0,0,0,0,0,0,0,0,0,0,0)';
      BIDIRECTIONAL='TRUE';
      INPUT_LOAD='(-0.01,0.01)';
      OUTPUT_LOAD='(1.0,-1.0)';
      PINUSE='BI';
    'DDR5_SA_DQ16':
      PIN_NUMBER='(0,0,0,0,0,0,0,0,0,0,0,0,EE66,0,0,0,0,0,0,0,0,0,0,0,0,0,0,0,0,~
0,0,0,0,0,0,0,0,0,0,0,0,0)';
      BIDIRECTIONAL='TRUE';
      INPUT_LOAD='(-0.01,0.01)';
      OUTPUT_LOAD='(1.0,-1.0)';
      PINUSE='BI';
    'DDR5_SA_DQ15':
      PIN_NUMBER='(0,0,0,0,0,0,0,0,0,0,0,0,DY65,0,0,0,0,0,0,0,0,0,0,0,0,0,0,0,0,~
0,0,0,0,0,0,0,0,0,0,0,0,0)';
      BIDIRECTIONAL='TRUE';
      INPUT_LOAD='(-0.01,0.01)';
      OUTPUT_LOAD='(1.0,-1.0)';
      PINUSE='BI';
    'DDR5_SA_DQ14':
      PIN_NUMBER='(0,0,0,0,0,0,0,0,0,0,0,0,EA66,0,0,0,0,0,0,0,0,0,0,0,0,0,0,0,0,~
0,0,0,0,0,0,0,0,0,0,0,0,0)';
      BIDIRECTIONAL='TRUE';
      INPUT_LOAD='(-0.01,0.01)';
      OUTPUT_LOAD='(1.0,-1.0)';
      PINUSE='BI';
    'DDR5_SA_DQ13':
      PIN_NUMBER='(0,0,0,0,0,0,0,0,0,0,0,0,DV65,0,0,0,0,0,0,0,0,0,0,0,0,0,0,0,0,~
0,0,0,0,0,0,0,0,0,0,0,0,0)';
      BIDIRECTIONAL='TRUE';
      INPUT_LOAD='(-0.01,0.01)';
      OUTPUT_LOAD='(1.0,-1.0)';
      PINUSE='BI';
    'DDR5_SA_DQ12':
      PIN_NUMBER='(0,0,0,0,0,0,0,0,0,0,0,0,DU66,0,0,0,0,0,0,0,0,0,0,0,0,0,0,0,0,~
0,0,0,0,0,0,0,0,0,0,0,0,0)';
      BIDIRECTIONAL='TRUE';
      INPUT_LOAD='(-0.01,0.01)';
      OUTPUT_LOAD='(1.0,-1.0)';
      PINUSE='BI';
    'DDR5_SA_DQ11':
      PIN_NUMBER='(0,0,0,0,0,0,0,0,0,0,0,0,EA68,0,0,0,0,0,0,0,0,0,0,0,0,0,0,0,0,~
0,0,0,0,0,0,0,0,0,0,0,0,0)';
      BIDIRECTIONAL='TRUE';
      INPUT_LOAD='(-0.01,0.01)';
      OUTPUT_LOAD='(1.0,-1.0)';
      PINUSE='BI';
    'DDR5_SA_DQ10':
      PIN_NUMBER='(0,0,0,0,0,0,0,0,0,0,0,0,DY69,0,0,0,0,0,0,0,0,0,0,0,0,0,0,0,0,~
0,0,0,0,0,0,0,0,0,0,0,0,0)';
      BIDIRECTIONAL='TRUE';
      INPUT_LOAD='(-0.01,0.01)';
      OUTPUT_LOAD='(1.0,-1.0)';
      PINUSE='BI';
    'DDR5_SA_DQ9':
      PIN_NUMBER='(0,0,0,0,0,0,0,0,0,0,0,0,DU68,0,0,0,0,0,0,0,0,0,0,0,0,0,0,0,0,~
0,0,0,0,0,0,0,0,0,0,0,0,0)';
      BIDIRECTIONAL='TRUE';
      INPUT_LOAD='(-0.01,0.01)';
      OUTPUT_LOAD='(1.0,-1.0)';
      PINUSE='BI';
    'DDR5_SA_DQ8':
      PIN_NUMBER='(0,0,0,0,0,0,0,0,0,0,0,0,DV69,0,0,0,0,0,0,0,0,0,0,0,0,0,0,0,0,~
0,0,0,0,0,0,0,0,0,0,0,0,0)';
      BIDIRECTIONAL='TRUE';
      INPUT_LOAD='(-0.01,0.01)';
      OUTPUT_LOAD='(1.0,-1.0)';
      PINUSE='BI';
    'DDR5_SA_DQ7':
      PIN_NUMBER='(0,0,0,0,0,0,0,0,0,0,0,0,EG74,0,0,0,0,0,0,0,0,0,0,0,0,0,0,0,0,~
0,0,0,0,0,0,0,0,0,0,0,0,0)';
      BIDIRECTIONAL='TRUE';
      INPUT_LOAD='(-0.01,0.01)';
      OUTPUT_LOAD='(1.0,-1.0)';
      PINUSE='BI';
    'DDR5_SA_DQ6':
      PIN_NUMBER='(0,0,0,0,0,0,0,0,0,0,0,0,EH75,0,0,0,0,0,0,0,0,0,0,0,0,0,0,0,0,~
0,0,0,0,0,0,0,0,0,0,0,0,0)';
      BIDIRECTIONAL='TRUE';
      INPUT_LOAD='(-0.01,0.01)';
      OUTPUT_LOAD='(1.0,-1.0)';
      PINUSE='BI';
    'DDR5_SA_DQ5':
      PIN_NUMBER='(0,0,0,0,0,0,0,0,0,0,0,0,EE74,0,0,0,0,0,0,0,0,0,0,0,0,0,0,0,0,~
0,0,0,0,0,0,0,0,0,0,0,0,0)';
      BIDIRECTIONAL='TRUE';
      INPUT_LOAD='(-0.01,0.01)';
      OUTPUT_LOAD='(1.0,-1.0)';
      PINUSE='BI';
    'DDR5_SA_DQ4':
      PIN_NUMBER='(0,0,0,0,0,0,0,0,0,0,0,0,ED75,0,0,0,0,0,0,0,0,0,0,0,0,0,0,0,0,~
0,0,0,0,0,0,0,0,0,0,0,0,0)';
      BIDIRECTIONAL='TRUE';
      INPUT_LOAD='(-0.01,0.01)';
      OUTPUT_LOAD='(1.0,-1.0)';
      PINUSE='BI';
    'DDR5_SA_DQ3':
      PIN_NUMBER='(0,0,0,0,0,0,0,0,0,0,0,0,EG78,0,0,0,0,0,0,0,0,0,0,0,0,0,0,0,0,~
0,0,0,0,0,0,0,0,0,0,0,0,0)';
      BIDIRECTIONAL='TRUE';
      INPUT_LOAD='(-0.01,0.01)';
      OUTPUT_LOAD='(1.0,-1.0)';
      PINUSE='BI';
    'DDR5_SA_DQ2':
      PIN_NUMBER='(0,0,0,0,0,0,0,0,0,0,0,0,ED77,0,0,0,0,0,0,0,0,0,0,0,0,0,0,0,0,~
0,0,0,0,0,0,0,0,0,0,0,0,0)';
      BIDIRECTIONAL='TRUE';
      INPUT_LOAD='(-0.01,0.01)';
      OUTPUT_LOAD='(1.0,-1.0)';
      PINUSE='BI';
    'DDR5_SA_DQ1':
      PIN_NUMBER='(0,0,0,0,0,0,0,0,0,0,0,0,EH77,0,0,0,0,0,0,0,0,0,0,0,0,0,0,0,0,~
0,0,0,0,0,0,0,0,0,0,0,0,0)';
      BIDIRECTIONAL='TRUE';
      INPUT_LOAD='(-0.01,0.01)';
      OUTPUT_LOAD='(1.0,-1.0)';
      PINUSE='BI';
    'DDR5_SA_DQ0':
      PIN_NUMBER='(0,0,0,0,0,0,0,0,0,0,0,0,EB77,0,0,0,0,0,0,0,0,0,0,0,0,0,0,0,0,~
0,0,0,0,0,0,0,0,0,0,0,0,0)';
      BIDIRECTIONAL='TRUE';
      INPUT_LOAD='(-0.01,0.01)';
      OUTPUT_LOAD='(1.0,-1.0)';
      PINUSE='BI';
    'DDR5_SA_DQS_DN9':
      PIN_NUMBER='(0,0,0,0,0,0,0,0,0,0,0,0,EJ58,0,0,0,0,0,0,0,0,0,0,0,0,0,0,0,0,~
0,0,0,0,0,0,0,0,0,0,0,0,0)';
      BIDIRECTIONAL='TRUE';
      INPUT_LOAD='(-0.01,0.01)';
      OUTPUT_LOAD='(1.0,-1.0)';
      PINUSE='BI';
    'DDR5_SA_DQS_DN8':
      PIN_NUMBER='(0,0,0,0,0,0,0,0,0,0,0,0,EB55,0,0,0,0,0,0,0,0,0,0,0,0,0,0,0,0,~
0,0,0,0,0,0,0,0,0,0,0,0,0)';
      BIDIRECTIONAL='TRUE';
      INPUT_LOAD='(-0.01,0.01)';
      OUTPUT_LOAD='(1.0,-1.0)';
      PINUSE='BI';
    'DDR5_SA_DQS_DN7':
      PIN_NUMBER='(0,0,0,0,0,0,0,0,0,0,0,0,EJ64,0,0,0,0,0,0,0,0,0,0,0,0,0,0,0,0,~
0,0,0,0,0,0,0,0,0,0,0,0,0)';
      BIDIRECTIONAL='TRUE';
      INPUT_LOAD='(-0.01,0.01)';
      OUTPUT_LOAD='(1.0,-1.0)';
      PINUSE='BI';
    'DDR5_SA_DQS_DN6':
      PIN_NUMBER='(0,0,0,0,0,0,0,0,0,0,0,0,EB67,0,0,0,0,0,0,0,0,0,0,0,0,0,0,0,0,~
0,0,0,0,0,0,0,0,0,0,0,0,0)';
      BIDIRECTIONAL='TRUE';
      INPUT_LOAD='(-0.01,0.01)';
      OUTPUT_LOAD='(1.0,-1.0)';
      PINUSE='BI';
    'DDR5_SA_DQS_DN5':
      PIN_NUMBER='(0,0,0,0,0,0,0,0,0,0,0,0,EJ76,0,0,0,0,0,0,0,0,0,0,0,0,0,0,0,0,~
0,0,0,0,0,0,0,0,0,0,0,0,0)';
      BIDIRECTIONAL='TRUE';
      INPUT_LOAD='(-0.01,0.01)';
      OUTPUT_LOAD='(1.0,-1.0)';
      PINUSE='BI';
    'DDR5_SA_DQS_DN4':
      PIN_NUMBER='(0,0,0,0,0,0,0,0,0,0,0,0,EE58,0,0,0,0,0,0,0,0,0,0,0,0,0,0,0,0,~
0,0,0,0,0,0,0,0,0,0,0,0,0)';
      BIDIRECTIONAL='TRUE';
      INPUT_LOAD='(-0.01,0.01)';
      OUTPUT_LOAD='(1.0,-1.0)';
      PINUSE='BI';
    'DDR5_SA_DQS_DN3':
      PIN_NUMBER='(0,0,0,0,0,0,0,0,0,0,0,0,DV55,0,0,0,0,0,0,0,0,0,0,0,0,0,0,0,0,~
0,0,0,0,0,0,0,0,0,0,0,0,0)';
      BIDIRECTIONAL='TRUE';
      INPUT_LOAD='(-0.01,0.01)';
      OUTPUT_LOAD='(1.0,-1.0)';
      PINUSE='BI';
    'DDR5_SA_DQS_DN2':
      PIN_NUMBER='(0,0,0,0,0,0,0,0,0,0,0,0,EC64,0,0,0,0,0,0,0,0,0,0,0,0,0,0,0,0,~
0,0,0,0,0,0,0,0,0,0,0,0,0)';
      BIDIRECTIONAL='TRUE';
      INPUT_LOAD='(-0.01,0.01)';
      OUTPUT_LOAD='(1.0,-1.0)';
      PINUSE='BI';
    'DDR5_SA_DQS_DN1':
      PIN_NUMBER='(0,0,0,0,0,0,0,0,0,0,0,0,DT67,0,0,0,0,0,0,0,0,0,0,0,0,0,0,0,0,~
0,0,0,0,0,0,0,0,0,0,0,0,0)';
      BIDIRECTIONAL='TRUE';
      INPUT_LOAD='(-0.01,0.01)';
      OUTPUT_LOAD='(1.0,-1.0)';
      PINUSE='BI';
    'DDR5_SA_DQS_DN0':
      PIN_NUMBER='(0,0,0,0,0,0,0,0,0,0,0,0,EE76,0,0,0,0,0,0,0,0,0,0,0,0,0,0,0,0,~
0,0,0,0,0,0,0,0,0,0,0,0,0)';
      BIDIRECTIONAL='TRUE';
      INPUT_LOAD='(-0.01,0.01)';
      OUTPUT_LOAD='(1.0,-1.0)';
      PINUSE='BI';
    'DDR5_SA_DQS_DP9':
      PIN_NUMBER='(0,0,0,0,0,0,0,0,0,0,0,0,EG58,0,0,0,0,0,0,0,0,0,0,0,0,0,0,0,0,~
0,0,0,0,0,0,0,0,0,0,0,0,0)';
      BIDIRECTIONAL='TRUE';
      INPUT_LOAD='(-0.01,0.01)';
      OUTPUT_LOAD='(1.0,-1.0)';
      PINUSE='BI';
    'DDR5_SA_DQS_DP8':
      PIN_NUMBER='(0,0,0,0,0,0,0,0,0,0,0,0,DY55,0,0,0,0,0,0,0,0,0,0,0,0,0,0,0,0,~
0,0,0,0,0,0,0,0,0,0,0,0,0)';
      BIDIRECTIONAL='TRUE';
      INPUT_LOAD='(-0.01,0.01)';
      OUTPUT_LOAD='(1.0,-1.0)';
      PINUSE='BI';
    'DDR5_SA_DQS_DP7':
      PIN_NUMBER='(0,0,0,0,0,0,0,0,0,0,0,0,EG64,0,0,0,0,0,0,0,0,0,0,0,0,0,0,0,0,~
0,0,0,0,0,0,0,0,0,0,0,0,0)';
      BIDIRECTIONAL='TRUE';
      INPUT_LOAD='(-0.01,0.01)';
      OUTPUT_LOAD='(1.0,-1.0)';
      PINUSE='BI';
    'DDR5_SA_DQS_DP6':
      PIN_NUMBER='(0,0,0,0,0,0,0,0,0,0,0,0,DY67,0,0,0,0,0,0,0,0,0,0,0,0,0,0,0,0,~
0,0,0,0,0,0,0,0,0,0,0,0,0)';
      BIDIRECTIONAL='TRUE';
      INPUT_LOAD='(-0.01,0.01)';
      OUTPUT_LOAD='(1.0,-1.0)';
      PINUSE='BI';
    'DDR5_SA_DQS_DP5':
      PIN_NUMBER='(0,0,0,0,0,0,0,0,0,0,0,0,EG76,0,0,0,0,0,0,0,0,0,0,0,0,0,0,0,0,~
0,0,0,0,0,0,0,0,0,0,0,0,0)';
      BIDIRECTIONAL='TRUE';
      INPUT_LOAD='(-0.01,0.01)';
      OUTPUT_LOAD='(1.0,-1.0)';
      PINUSE='BI';
    'DDR5_SA_DQS_DP4':
      PIN_NUMBER='(0,0,0,0,0,0,0,0,0,0,0,0,EC58,0,0,0,0,0,0,0,0,0,0,0,0,0,0,0,0,~
0,0,0,0,0,0,0,0,0,0,0,0,0)';
      BIDIRECTIONAL='TRUE';
      INPUT_LOAD='(-0.01,0.01)';
      OUTPUT_LOAD='(1.0,-1.0)';
      PINUSE='BI';
    'DDR5_SA_DQS_DP3':
      PIN_NUMBER='(0,0,0,0,0,0,0,0,0,0,0,0,DT55,0,0,0,0,0,0,0,0,0,0,0,0,0,0,0,0,~
0,0,0,0,0,0,0,0,0,0,0,0,0)';
      BIDIRECTIONAL='TRUE';
      INPUT_LOAD='(-0.01,0.01)';
      OUTPUT_LOAD='(1.0,-1.0)';
      PINUSE='BI';
    'DDR5_SA_DQS_DP2':
      PIN_NUMBER='(0,0,0,0,0,0,0,0,0,0,0,0,EE64,0,0,0,0,0,0,0,0,0,0,0,0,0,0,0,0,~
0,0,0,0,0,0,0,0,0,0,0,0,0)';
      BIDIRECTIONAL='TRUE';
      INPUT_LOAD='(-0.01,0.01)';
      OUTPUT_LOAD='(1.0,-1.0)';
      PINUSE='BI';
    'DDR5_SA_DQS_DP1':
      PIN_NUMBER='(0,0,0,0,0,0,0,0,0,0,0,0,DV67,0,0,0,0,0,0,0,0,0,0,0,0,0,0,0,0,~
0,0,0,0,0,0,0,0,0,0,0,0,0)';
      BIDIRECTIONAL='TRUE';
      INPUT_LOAD='(-0.01,0.01)';
      OUTPUT_LOAD='(1.0,-1.0)';
      PINUSE='BI';
    'DDR5_SA_DQS_DP0':
      PIN_NUMBER='(0,0,0,0,0,0,0,0,0,0,0,0,EC76,0,0,0,0,0,0,0,0,0,0,0,0,0,0,0,0,~
0,0,0,0,0,0,0,0,0,0,0,0,0)';
      BIDIRECTIONAL='TRUE';
      INPUT_LOAD='(-0.01,0.01)';
      OUTPUT_LOAD='(1.0,-1.0)';
      PINUSE='BI';
    'DDR5_SA_ECC7':
      PIN_NUMBER='(0,0,0,0,0,0,0,0,0,0,0,0,EG56,0,0,0,0,0,0,0,0,0,0,0,0,0,0,0,0,~
0,0,0,0,0,0,0,0,0,0,0,0,0)';
      BIDIRECTIONAL='TRUE';
      INPUT_LOAD='(-0.01,0.01)';
      OUTPUT_LOAD='(1.0,-1.0)';
      PINUSE='BI';
    'DDR5_SA_ECC6':
      PIN_NUMBER='(0,0,0,0,0,0,0,0,0,0,0,0,EH57,0,0,0,0,0,0,0,0,0,0,0,0,0,0,0,0,~
0,0,0,0,0,0,0,0,0,0,0,0,0)';
      BIDIRECTIONAL='TRUE';
      INPUT_LOAD='(-0.01,0.01)';
      OUTPUT_LOAD='(1.0,-1.0)';
      PINUSE='BI';
    'DDR5_SA_ECC5':
      PIN_NUMBER='(0,0,0,0,0,0,0,0,0,0,0,0,EE56,0,0,0,0,0,0,0,0,0,0,0,0,0,0,0,0,~
0,0,0,0,0,0,0,0,0,0,0,0,0)';
      BIDIRECTIONAL='TRUE';
      INPUT_LOAD='(-0.01,0.01)';
      OUTPUT_LOAD='(1.0,-1.0)';
      PINUSE='BI';
    'DDR5_SA_ECC4':
      PIN_NUMBER='(0,0,0,0,0,0,0,0,0,0,0,0,ED57,0,0,0,0,0,0,0,0,0,0,0,0,0,0,0,0,~
0,0,0,0,0,0,0,0,0,0,0,0,0)';
      BIDIRECTIONAL='TRUE';
      INPUT_LOAD='(-0.01,0.01)';
      OUTPUT_LOAD='(1.0,-1.0)';
      PINUSE='BI';
    'DDR5_SA_ECC3':
      PIN_NUMBER='(0,0,0,0,0,0,0,0,0,0,0,0,EH59,0,0,0,0,0,0,0,0,0,0,0,0,0,0,0,0,~
0,0,0,0,0,0,0,0,0,0,0,0,0)';
      BIDIRECTIONAL='TRUE';
      INPUT_LOAD='(-0.01,0.01)';
      OUTPUT_LOAD='(1.0,-1.0)';
      PINUSE='BI';
    'DDR5_SA_ECC2':
      PIN_NUMBER='(0,0,0,0,0,0,0,0,0,0,0,0,EG60,0,0,0,0,0,0,0,0,0,0,0,0,0,0,0,0,~
0,0,0,0,0,0,0,0,0,0,0,0,0)';
      BIDIRECTIONAL='TRUE';
      INPUT_LOAD='(-0.01,0.01)';
      OUTPUT_LOAD='(1.0,-1.0)';
      PINUSE='BI';
    'DDR5_SA_ECC1':
      PIN_NUMBER='(0,0,0,0,0,0,0,0,0,0,0,0,ED59,0,0,0,0,0,0,0,0,0,0,0,0,0,0,0,0,~
0,0,0,0,0,0,0,0,0,0,0,0,0)';
      BIDIRECTIONAL='TRUE';
      INPUT_LOAD='(-0.01,0.01)';
      OUTPUT_LOAD='(1.0,-1.0)';
      PINUSE='BI';
    'DDR5_SA_ECC0':
      PIN_NUMBER='(0,0,0,0,0,0,0,0,0,0,0,0,EE60,0,0,0,0,0,0,0,0,0,0,0,0,0,0,0,0,~
0,0,0,0,0,0,0,0,0,0,0,0,0)';
      BIDIRECTIONAL='TRUE';
      INPUT_LOAD='(-0.01,0.01)';
      OUTPUT_LOAD='(1.0,-1.0)';
      PINUSE='BI';
    'DDR5_SA_PAR':
      PIN_NUMBER='(0,0,0,0,0,0,0,0,0,0,0,0,EA50,0,0,0,0,0,0,0,0,0,0,0,0,0,0,0,0,~
0,0,0,0,0,0,0,0,0,0,0,0,0)';
      OUTPUT_LOAD='(1.0,-1.0)';
      PINUSE='OUT';
    'DDR5_SB_CA6':
      PIN_NUMBER='(0,0,0,0,0,0,0,0,0,0,0,0,EC39,0,0,0,0,0,0,0,0,0,0,0,0,0,0,0,0,~
0,0,0,0,0,0,0,0,0,0,0,0,0)';
      OUTPUT_LOAD='(1.0,-1.0)';
      PINUSE='OUT';
    'DDR5_SB_CA5':
      PIN_NUMBER='(0,0,0,0,0,0,0,0,0,0,0,0,EH40,0,0,0,0,0,0,0,0,0,0,0,0,0,0,0,0,~
0,0,0,0,0,0,0,0,0,0,0,0,0)';
      OUTPUT_LOAD='(1.0,-1.0)';
      PINUSE='OUT';
    'DDR5_SB_CA4':
      PIN_NUMBER='(0,0,0,0,0,0,0,0,0,0,0,0,ED40,0,0,0,0,0,0,0,0,0,0,0,0,0,0,0,0,~
0,0,0,0,0,0,0,0,0,0,0,0,0)';
      OUTPUT_LOAD='(1.0,-1.0)';
      PINUSE='OUT';
    'DDR5_SB_CA3':
      PIN_NUMBER='(0,0,0,0,0,0,0,0,0,0,0,0,EG41,0,0,0,0,0,0,0,0,0,0,0,0,0,0,0,0,~
0,0,0,0,0,0,0,0,0,0,0,0,0)';
      OUTPUT_LOAD='(1.0,-1.0)';
      PINUSE='OUT';
    'DDR5_SB_CA2':
      PIN_NUMBER='(0,0,0,0,0,0,0,0,0,0,0,0,EE41,0,0,0,0,0,0,0,0,0,0,0,0,0,0,0,0,~
0,0,0,0,0,0,0,0,0,0,0,0,0)';
      OUTPUT_LOAD='(1.0,-1.0)';
      PINUSE='OUT';
    'DDR5_SB_CA1':
      PIN_NUMBER='(0,0,0,0,0,0,0,0,0,0,0,0,DU50,0,0,0,0,0,0,0,0,0,0,0,0,0,0,0,0,~
0,0,0,0,0,0,0,0,0,0,0,0,0)';
      OUTPUT_LOAD='(1.0,-1.0)';
      PINUSE='OUT';
    'DDR5_SB_CA0':
      PIN_NUMBER='(0,0,0,0,0,0,0,0,0,0,0,0,DV51,0,0,0,0,0,0,0,0,0,0,0,0,0,0,0,0,~
0,0,0,0,0,0,0,0,0,0,0,0,0)';
      OUTPUT_LOAD='(1.0,-1.0)';
      PINUSE='OUT';
    'DDR5_SB_CS_N3':
      PIN_NUMBER='(0,0,0,0,0,0,0,0,0,0,0,0,EE37,0,0,0,0,0,0,0,0,0,0,0,0,0,0,0,0,~
0,0,0,0,0,0,0,0,0,0,0,0,0)';
      OUTPUT_LOAD='(1.0,-1.0)';
      PINUSE='OUT';
    'DDR5_SB_CS_N2':
      PIN_NUMBER='(0,0,0,0,0,0,0,0,0,0,0,0,ED38,0,0,0,0,0,0,0,0,0,0,0,0,0,0,0,0,~
0,0,0,0,0,0,0,0,0,0,0,0,0)';
      OUTPUT_LOAD='(1.0,-1.0)';
      PINUSE='OUT';
    'DDR5_SB_CS_N1':
      PIN_NUMBER='(0,0,0,0,0,0,0,0,0,0,0,0,EG37,0,0,0,0,0,0,0,0,0,0,0,0,0,0,0,0,~
0,0,0,0,0,0,0,0,0,0,0,0,0)';
      OUTPUT_LOAD='(1.0,-1.0)';
      PINUSE='OUT';
    'DDR5_SB_CS_N0':
      PIN_NUMBER='(0,0,0,0,0,0,0,0,0,0,0,0,EH38,0,0,0,0,0,0,0,0,0,0,0,0,0,0,0,0,~
0,0,0,0,0,0,0,0,0,0,0,0,0)';
      OUTPUT_LOAD='(1.0,-1.0)';
      PINUSE='OUT';
    'DDR5_SB_DQ31':
      PIN_NUMBER='(0,0,0,0,0,0,0,0,0,0,0,0,DR17,0,0,0,0,0,0,0,0,0,0,0,0,0,0,0,0,~
0,0,0,0,0,0,0,0,0,0,0,0,0)';
      BIDIRECTIONAL='TRUE';
      INPUT_LOAD='(-0.01,0.01)';
      OUTPUT_LOAD='(1.0,-1.0)';
      PINUSE='BI';
    'DDR5_SB_DQ30':
      PIN_NUMBER='(0,0,0,0,0,0,0,0,0,0,0,0,EC17,0,0,0,0,0,0,0,0,0,0,0,0,0,0,0,0,~
0,0,0,0,0,0,0,0,0,0,0,0,0)';
      BIDIRECTIONAL='TRUE';
      INPUT_LOAD='(-0.01,0.01)';
      OUTPUT_LOAD='(1.0,-1.0)';
      PINUSE='BI';
    'DDR5_SB_DQ29':
      PIN_NUMBER='(0,0,0,0,0,0,0,0,0,0,0,0,DU17,0,0,0,0,0,0,0,0,0,0,0,0,0,0,0,0,~
0,0,0,0,0,0,0,0,0,0,0,0,0)';
      BIDIRECTIONAL='TRUE';
      INPUT_LOAD='(-0.01,0.01)';
      OUTPUT_LOAD='(1.0,-1.0)';
      PINUSE='BI';
    'DDR5_SB_DQ28':
      PIN_NUMBER='(0,0,0,0,0,0,0,0,0,0,0,0,EA17,0,0,0,0,0,0,0,0,0,0,0,0,0,0,0,0,~
0,0,0,0,0,0,0,0,0,0,0,0,0)';
      BIDIRECTIONAL='TRUE';
      INPUT_LOAD='(-0.01,0.01)';
      OUTPUT_LOAD='(1.0,-1.0)';
      PINUSE='BI';
    'DDR5_SB_DQ27':
      PIN_NUMBER='(0,0,0,0,0,0,0,0,0,0,0,0,EA19,0,0,0,0,0,0,0,0,0,0,0,0,0,0,0,0,~
0,0,0,0,0,0,0,0,0,0,0,0,0)';
      BIDIRECTIONAL='TRUE';
      INPUT_LOAD='(-0.01,0.01)';
      OUTPUT_LOAD='(1.0,-1.0)';
      PINUSE='BI';
    'DDR5_SB_DQ26':
      PIN_NUMBER='(0,0,0,0,0,0,0,0,0,0,0,0,DY20,0,0,0,0,0,0,0,0,0,0,0,0,0,0,0,0,~
0,0,0,0,0,0,0,0,0,0,0,0,0)';
      BIDIRECTIONAL='TRUE';
      INPUT_LOAD='(-0.01,0.01)';
      OUTPUT_LOAD='(1.0,-1.0)';
      PINUSE='BI';
    'DDR5_SB_DQ25':
      PIN_NUMBER='(0,0,0,0,0,0,0,0,0,0,0,0,DU19,0,0,0,0,0,0,0,0,0,0,0,0,0,0,0,0,~
0,0,0,0,0,0,0,0,0,0,0,0,0)';
      BIDIRECTIONAL='TRUE';
      INPUT_LOAD='(-0.01,0.01)';
      OUTPUT_LOAD='(1.0,-1.0)';
      PINUSE='BI';
    'DDR5_SB_DQ24':
      PIN_NUMBER='(0,0,0,0,0,0,0,0,0,0,0,0,DV20,0,0,0,0,0,0,0,0,0,0,0,0,0,0,0,0,~
0,0,0,0,0,0,0,0,0,0,0,0,0)';
      BIDIRECTIONAL='TRUE';
      INPUT_LOAD='(-0.01,0.01)';
      OUTPUT_LOAD='(1.0,-1.0)';
      PINUSE='BI';
    'DDR5_SB_DQ23':
      PIN_NUMBER='(0,0,0,0,0,0,0,0,0,0,0,0,EP10,0,0,0,0,0,0,0,0,0,0,0,0,0,0,0,0,~
0,0,0,0,0,0,0,0,0,0,0,0,0)';
      BIDIRECTIONAL='TRUE';
      INPUT_LOAD='(-0.01,0.01)';
      OUTPUT_LOAD='(1.0,-1.0)';
      PINUSE='BI';
    'DDR5_SB_DQ22':
      PIN_NUMBER='(0,0,0,0,0,0,0,0,0,0,0,0,ER11,0,0,0,0,0,0,0,0,0,0,0,0,0,0,0,0,~
0,0,0,0,0,0,0,0,0,0,0,0,0)';
      BIDIRECTIONAL='TRUE';
      INPUT_LOAD='(-0.01,0.01)';
      OUTPUT_LOAD='(1.0,-1.0)';
      PINUSE='BI';
    'DDR5_SB_DQ21':
      PIN_NUMBER='(0,0,0,0,0,0,0,0,0,0,0,0,EM10,0,0,0,0,0,0,0,0,0,0,0,0,0,0,0,0,~
0,0,0,0,0,0,0,0,0,0,0,0,0)';
      BIDIRECTIONAL='TRUE';
      INPUT_LOAD='(-0.01,0.01)';
      OUTPUT_LOAD='(1.0,-1.0)';
      PINUSE='BI';
    'DDR5_SB_DQ20':
      PIN_NUMBER='(0,0,0,0,0,0,0,0,0,0,0,0,EL11,0,0,0,0,0,0,0,0,0,0,0,0,0,0,0,0,~
0,0,0,0,0,0,0,0,0,0,0,0,0)';
      BIDIRECTIONAL='TRUE';
      INPUT_LOAD='(-0.01,0.01)';
      OUTPUT_LOAD='(1.0,-1.0)';
      PINUSE='BI';
    'DDR5_SB_DQ19':
      PIN_NUMBER='(0,0,0,0,0,0,0,0,0,0,0,0,ER13,0,0,0,0,0,0,0,0,0,0,0,0,0,0,0,0,~
0,0,0,0,0,0,0,0,0,0,0,0,0)';
      BIDIRECTIONAL='TRUE';
      INPUT_LOAD='(-0.01,0.01)';
      OUTPUT_LOAD='(1.0,-1.0)';
      PINUSE='BI';
    'DDR5_SB_DQ18':
      PIN_NUMBER='(0,0,0,0,0,0,0,0,0,0,0,0,EP14,0,0,0,0,0,0,0,0,0,0,0,0,0,0,0,0,~
0,0,0,0,0,0,0,0,0,0,0,0,0)';
      BIDIRECTIONAL='TRUE';
      INPUT_LOAD='(-0.01,0.01)';
      OUTPUT_LOAD='(1.0,-1.0)';
      PINUSE='BI';
    'DDR5_SB_DQ17':
      PIN_NUMBER='(0,0,0,0,0,0,0,0,0,0,0,0,EL13,0,0,0,0,0,0,0,0,0,0,0,0,0,0,0,0,~
0,0,0,0,0,0,0,0,0,0,0,0,0)';
      BIDIRECTIONAL='TRUE';
      INPUT_LOAD='(-0.01,0.01)';
      OUTPUT_LOAD='(1.0,-1.0)';
      PINUSE='BI';
    'DDR5_SB_DQ16':
      PIN_NUMBER='(0,0,0,0,0,0,0,0,0,0,0,0,EM14,0,0,0,0,0,0,0,0,0,0,0,0,0,0,0,0,~
0,0,0,0,0,0,0,0,0,0,0,0,0)';
      BIDIRECTIONAL='TRUE';
      INPUT_LOAD='(-0.01,0.01)';
      OUTPUT_LOAD='(1.0,-1.0)';
      PINUSE='BI';
    'DDR5_SB_DQ15':
      PIN_NUMBER='(0,0,0,0,0,0,0,0,0,0,0,0,EG19,0,0,0,0,0,0,0,0,0,0,0,0,0,0,0,0,~
0,0,0,0,0,0,0,0,0,0,0,0,0)';
      BIDIRECTIONAL='TRUE';
      INPUT_LOAD='(-0.01,0.01)';
      OUTPUT_LOAD='(1.0,-1.0)';
      PINUSE='BI';
    'DDR5_SB_DQ14':
      PIN_NUMBER='(0,0,0,0,0,0,0,0,0,0,0,0,EH20,0,0,0,0,0,0,0,0,0,0,0,0,0,0,0,0,~
0,0,0,0,0,0,0,0,0,0,0,0,0)';
      BIDIRECTIONAL='TRUE';
      INPUT_LOAD='(-0.01,0.01)';
      OUTPUT_LOAD='(1.0,-1.0)';
      PINUSE='BI';
    'DDR5_SB_DQ13':
      PIN_NUMBER='(0,0,0,0,0,0,0,0,0,0,0,0,EE19,0,0,0,0,0,0,0,0,0,0,0,0,0,0,0,0,~
0,0,0,0,0,0,0,0,0,0,0,0,0)';
      BIDIRECTIONAL='TRUE';
      INPUT_LOAD='(-0.01,0.01)';
      OUTPUT_LOAD='(1.0,-1.0)';
      PINUSE='BI';
    'DDR5_SB_DQ12':
      PIN_NUMBER='(0,0,0,0,0,0,0,0,0,0,0,0,ED20,0,0,0,0,0,0,0,0,0,0,0,0,0,0,0,0,~
0,0,0,0,0,0,0,0,0,0,0,0,0)';
      BIDIRECTIONAL='TRUE';
      INPUT_LOAD='(-0.01,0.01)';
      OUTPUT_LOAD='(1.0,-1.0)';
      PINUSE='BI';
    'DDR5_SB_DQ11':
      PIN_NUMBER='(0,0,0,0,0,0,0,0,0,0,0,0,EH22,0,0,0,0,0,0,0,0,0,0,0,0,0,0,0,0,~
0,0,0,0,0,0,0,0,0,0,0,0,0)';
      BIDIRECTIONAL='TRUE';
      INPUT_LOAD='(-0.01,0.01)';
      OUTPUT_LOAD='(1.0,-1.0)';
      PINUSE='BI';
    'DDR5_SB_DQ10':
      PIN_NUMBER='(0,0,0,0,0,0,0,0,0,0,0,0,EG23,0,0,0,0,0,0,0,0,0,0,0,0,0,0,0,0,~
0,0,0,0,0,0,0,0,0,0,0,0,0)';
      BIDIRECTIONAL='TRUE';
      INPUT_LOAD='(-0.01,0.01)';
      OUTPUT_LOAD='(1.0,-1.0)';
      PINUSE='BI';
    'DDR5_SB_DQ9':
      PIN_NUMBER='(0,0,0,0,0,0,0,0,0,0,0,0,ED22,0,0,0,0,0,0,0,0,0,0,0,0,0,0,0,0,~
0,0,0,0,0,0,0,0,0,0,0,0,0)';
      BIDIRECTIONAL='TRUE';
      INPUT_LOAD='(-0.01,0.01)';
      OUTPUT_LOAD='(1.0,-1.0)';
      PINUSE='BI';
    'DDR5_SB_DQ8':
      PIN_NUMBER='(0,0,0,0,0,0,0,0,0,0,0,0,EE23,0,0,0,0,0,0,0,0,0,0,0,0,0,0,0,0,~
0,0,0,0,0,0,0,0,0,0,0,0,0)';
      BIDIRECTIONAL='TRUE';
      INPUT_LOAD='(-0.01,0.01)';
      OUTPUT_LOAD='(1.0,-1.0)';
      PINUSE='BI';
    'DDR5_SB_DQ7':
      PIN_NUMBER='(0,0,0,0,0,0,0,0,0,0,0,0,DY28,0,0,0,0,0,0,0,0,0,0,0,0,0,0,0,0,~
0,0,0,0,0,0,0,0,0,0,0,0,0)';
      BIDIRECTIONAL='TRUE';
      INPUT_LOAD='(-0.01,0.01)';
      OUTPUT_LOAD='(1.0,-1.0)';
      PINUSE='BI';
    'DDR5_SB_DQ6':
      PIN_NUMBER='(0,0,0,0,0,0,0,0,0,0,0,0,EA29,0,0,0,0,0,0,0,0,0,0,0,0,0,0,0,0,~
0,0,0,0,0,0,0,0,0,0,0,0,0)';
      BIDIRECTIONAL='TRUE';
      INPUT_LOAD='(-0.01,0.01)';
      OUTPUT_LOAD='(1.0,-1.0)';
      PINUSE='BI';
    'DDR5_SB_DQ5':
      PIN_NUMBER='(0,0,0,0,0,0,0,0,0,0,0,0,DV28,0,0,0,0,0,0,0,0,0,0,0,0,0,0,0,0,~
0,0,0,0,0,0,0,0,0,0,0,0,0)';
      BIDIRECTIONAL='TRUE';
      INPUT_LOAD='(-0.01,0.01)';
      OUTPUT_LOAD='(1.0,-1.0)';
      PINUSE='BI';
    'DDR5_SB_DQ4':
      PIN_NUMBER='(0,0,0,0,0,0,0,0,0,0,0,0,DU29,0,0,0,0,0,0,0,0,0,0,0,0,0,0,0,0,~
0,0,0,0,0,0,0,0,0,0,0,0,0)';
      BIDIRECTIONAL='TRUE';
      INPUT_LOAD='(-0.01,0.01)';
      OUTPUT_LOAD='(1.0,-1.0)';
      PINUSE='BI';
    'DDR5_SB_DQ3':
      PIN_NUMBER='(0,0,0,0,0,0,0,0,0,0,0,0,EA31,0,0,0,0,0,0,0,0,0,0,0,0,0,0,0,0,~
0,0,0,0,0,0,0,0,0,0,0,0,0)';
      BIDIRECTIONAL='TRUE';
      INPUT_LOAD='(-0.01,0.01)';
      OUTPUT_LOAD='(1.0,-1.0)';
      PINUSE='BI';
    'DDR5_SB_DQ2':
      PIN_NUMBER='(0,0,0,0,0,0,0,0,0,0,0,0,DY32,0,0,0,0,0,0,0,0,0,0,0,0,0,0,0,0,~
0,0,0,0,0,0,0,0,0,0,0,0,0)';
      BIDIRECTIONAL='TRUE';
      INPUT_LOAD='(-0.01,0.01)';
      OUTPUT_LOAD='(1.0,-1.0)';
      PINUSE='BI';
    'DDR5_SB_DQ1':
      PIN_NUMBER='(0,0,0,0,0,0,0,0,0,0,0,0,DU31,0,0,0,0,0,0,0,0,0,0,0,0,0,0,0,0,~
0,0,0,0,0,0,0,0,0,0,0,0,0)';
      BIDIRECTIONAL='TRUE';
      INPUT_LOAD='(-0.01,0.01)';
      OUTPUT_LOAD='(1.0,-1.0)';
      PINUSE='BI';
    'DDR5_SB_DQ0':
      PIN_NUMBER='(0,0,0,0,0,0,0,0,0,0,0,0,DV32,0,0,0,0,0,0,0,0,0,0,0,0,0,0,0,0,~
0,0,0,0,0,0,0,0,0,0,0,0,0)';
      BIDIRECTIONAL='TRUE';
      INPUT_LOAD='(-0.01,0.01)';
      OUTPUT_LOAD='(1.0,-1.0)';
      PINUSE='BI';
    'DDR5_SB_DQS_DN9':
      PIN_NUMBER='(0,0,0,0,0,0,0,0,0,0,0,0,EE33,0,0,0,0,0,0,0,0,0,0,0,0,0,0,0,0,~
0,0,0,0,0,0,0,0,0,0,0,0,0)';
      BIDIRECTIONAL='TRUE';
      INPUT_LOAD='(-0.01,0.01)';
      OUTPUT_LOAD='(1.0,-1.0)';
      PINUSE='BI';
    'DDR5_SB_DQS_DN8':
      PIN_NUMBER='(0,0,0,0,0,0,0,0,0,0,0,0,DY18,0,0,0,0,0,0,0,0,0,0,0,0,0,0,0,0,~
0,0,0,0,0,0,0,0,0,0,0,0,0)';
      BIDIRECTIONAL='TRUE';
      INPUT_LOAD='(-0.01,0.01)';
      OUTPUT_LOAD='(1.0,-1.0)';
      PINUSE='BI';
    'DDR5_SB_DQS_DN7':
      PIN_NUMBER='(0,0,0,0,0,0,0,0,0,0,0,0,ET12,0,0,0,0,0,0,0,0,0,0,0,0,0,0,0,0,~
0,0,0,0,0,0,0,0,0,0,0,0,0)';
      BIDIRECTIONAL='TRUE';
      INPUT_LOAD='(-0.01,0.01)';
      OUTPUT_LOAD='(1.0,-1.0)';
      PINUSE='BI';
    'DDR5_SB_DQS_DN6':
      PIN_NUMBER='(0,0,0,0,0,0,0,0,0,0,0,0,EJ21,0,0,0,0,0,0,0,0,0,0,0,0,0,0,0,0,~
0,0,0,0,0,0,0,0,0,0,0,0,0)';
      BIDIRECTIONAL='TRUE';
      INPUT_LOAD='(-0.01,0.01)';
      OUTPUT_LOAD='(1.0,-1.0)';
      PINUSE='BI';
    'DDR5_SB_DQS_DN5':
      PIN_NUMBER='(0,0,0,0,0,0,0,0,0,0,0,0,EB30,0,0,0,0,0,0,0,0,0,0,0,0,0,0,0,0,~
0,0,0,0,0,0,0,0,0,0,0,0,0)';
      BIDIRECTIONAL='TRUE';
      INPUT_LOAD='(-0.01,0.01)';
      OUTPUT_LOAD='(1.0,-1.0)';
      PINUSE='BI';
    'DDR5_SB_DQS_DN4':
      PIN_NUMBER='(0,0,0,0,0,0,0,0,0,0,0,0,EJ33,0,0,0,0,0,0,0,0,0,0,0,0,0,0,0,0,~
0,0,0,0,0,0,0,0,0,0,0,0,0)';
      BIDIRECTIONAL='TRUE';
      INPUT_LOAD='(-0.01,0.01)';
      OUTPUT_LOAD='(1.0,-1.0)';
      PINUSE='BI';
    'DDR5_SB_DQS_DN3':
      PIN_NUMBER='(0,0,0,0,0,0,0,0,0,0,0,0,DT18,0,0,0,0,0,0,0,0,0,0,0,0,0,0,0,0,~
0,0,0,0,0,0,0,0,0,0,0,0,0)';
      BIDIRECTIONAL='TRUE';
      INPUT_LOAD='(-0.01,0.01)';
      OUTPUT_LOAD='(1.0,-1.0)';
      PINUSE='BI';
    'DDR5_SB_DQS_DN2':
      PIN_NUMBER='(0,0,0,0,0,0,0,0,0,0,0,0,EM12,0,0,0,0,0,0,0,0,0,0,0,0,0,0,0,0,~
0,0,0,0,0,0,0,0,0,0,0,0,0)';
      BIDIRECTIONAL='TRUE';
      INPUT_LOAD='(-0.01,0.01)';
      OUTPUT_LOAD='(1.0,-1.0)';
      PINUSE='BI';
    'DDR5_SB_DQS_DN1':
      PIN_NUMBER='(0,0,0,0,0,0,0,0,0,0,0,0,EE21,0,0,0,0,0,0,0,0,0,0,0,0,0,0,0,0,~
0,0,0,0,0,0,0,0,0,0,0,0,0)';
      BIDIRECTIONAL='TRUE';
      INPUT_LOAD='(-0.01,0.01)';
      OUTPUT_LOAD='(1.0,-1.0)';
      PINUSE='BI';
    'DDR5_SB_DQS_DN0':
      PIN_NUMBER='(0,0,0,0,0,0,0,0,0,0,0,0,DV30,0,0,0,0,0,0,0,0,0,0,0,0,0,0,0,0,~
0,0,0,0,0,0,0,0,0,0,0,0,0)';
      BIDIRECTIONAL='TRUE';
      INPUT_LOAD='(-0.01,0.01)';
      OUTPUT_LOAD='(1.0,-1.0)';
      PINUSE='BI';
    'DDR5_SB_DQS_DP9':
      PIN_NUMBER='(0,0,0,0,0,0,0,0,0,0,0,0,EC33,0,0,0,0,0,0,0,0,0,0,0,0,0,0,0,0,~
0,0,0,0,0,0,0,0,0,0,0,0,0)';
      BIDIRECTIONAL='TRUE';
      INPUT_LOAD='(-0.01,0.01)';
      OUTPUT_LOAD='(1.0,-1.0)';
      PINUSE='BI';
    'DDR5_SB_DQS_DP8':
      PIN_NUMBER='(0,0,0,0,0,0,0,0,0,0,0,0,EB18,0,0,0,0,0,0,0,0,0,0,0,0,0,0,0,0,~
0,0,0,0,0,0,0,0,0,0,0,0,0)';
      BIDIRECTIONAL='TRUE';
      INPUT_LOAD='(-0.01,0.01)';
      OUTPUT_LOAD='(1.0,-1.0)';
      PINUSE='BI';
    'DDR5_SB_DQS_DP7':
      PIN_NUMBER='(0,0,0,0,0,0,0,0,0,0,0,0,EP12,0,0,0,0,0,0,0,0,0,0,0,0,0,0,0,0,~
0,0,0,0,0,0,0,0,0,0,0,0,0)';
      BIDIRECTIONAL='TRUE';
      INPUT_LOAD='(-0.01,0.01)';
      OUTPUT_LOAD='(1.0,-1.0)';
      PINUSE='BI';
    'DDR5_SB_DQS_DP6':
      PIN_NUMBER='(0,0,0,0,0,0,0,0,0,0,0,0,EG21,0,0,0,0,0,0,0,0,0,0,0,0,0,0,0,0,~
0,0,0,0,0,0,0,0,0,0,0,0,0)';
      BIDIRECTIONAL='TRUE';
      INPUT_LOAD='(-0.01,0.01)';
      OUTPUT_LOAD='(1.0,-1.0)';
      PINUSE='BI';
    'DDR5_SB_DQS_DP5':
      PIN_NUMBER='(0,0,0,0,0,0,0,0,0,0,0,0,DY30,0,0,0,0,0,0,0,0,0,0,0,0,0,0,0,0,~
0,0,0,0,0,0,0,0,0,0,0,0,0)';
      BIDIRECTIONAL='TRUE';
      INPUT_LOAD='(-0.01,0.01)';
      OUTPUT_LOAD='(1.0,-1.0)';
      PINUSE='BI';
    'DDR5_SB_DQS_DP4':
      PIN_NUMBER='(0,0,0,0,0,0,0,0,0,0,0,0,EG33,0,0,0,0,0,0,0,0,0,0,0,0,0,0,0,0,~
0,0,0,0,0,0,0,0,0,0,0,0,0)';
      BIDIRECTIONAL='TRUE';
      INPUT_LOAD='(-0.01,0.01)';
      OUTPUT_LOAD='(1.0,-1.0)';
      PINUSE='BI';
    'DDR5_SB_DQS_DP3':
      PIN_NUMBER='(0,0,0,0,0,0,0,0,0,0,0,0,DV18,0,0,0,0,0,0,0,0,0,0,0,0,0,0,0,0,~
0,0,0,0,0,0,0,0,0,0,0,0,0)';
      BIDIRECTIONAL='TRUE';
      INPUT_LOAD='(-0.01,0.01)';
      OUTPUT_LOAD='(1.0,-1.0)';
      PINUSE='BI';
    'DDR5_SB_DQS_DP2':
      PIN_NUMBER='(0,0,0,0,0,0,0,0,0,0,0,0,EK12,0,0,0,0,0,0,0,0,0,0,0,0,0,0,0,0,~
0,0,0,0,0,0,0,0,0,0,0,0,0)';
      BIDIRECTIONAL='TRUE';
      INPUT_LOAD='(-0.01,0.01)';
      OUTPUT_LOAD='(1.0,-1.0)';
      PINUSE='BI';
    'DDR5_SB_DQS_DP1':
      PIN_NUMBER='(0,0,0,0,0,0,0,0,0,0,0,0,EC21,0,0,0,0,0,0,0,0,0,0,0,0,0,0,0,0,~
0,0,0,0,0,0,0,0,0,0,0,0,0)';
      BIDIRECTIONAL='TRUE';
      INPUT_LOAD='(-0.01,0.01)';
      OUTPUT_LOAD='(1.0,-1.0)';
      PINUSE='BI';
    'DDR5_SB_DQS_DP0':
      PIN_NUMBER='(0,0,0,0,0,0,0,0,0,0,0,0,DT30,0,0,0,0,0,0,0,0,0,0,0,0,0,0,0,0,~
0,0,0,0,0,0,0,0,0,0,0,0,0)';
      BIDIRECTIONAL='TRUE';
      INPUT_LOAD='(-0.01,0.01)';
      OUTPUT_LOAD='(1.0,-1.0)';
      PINUSE='BI';
    'DDR5_SB_ECC7':
      PIN_NUMBER='(0,0,0,0,0,0,0,0,0,0,0,0,EH34,0,0,0,0,0,0,0,0,0,0,0,0,0,0,0,0,~
0,0,0,0,0,0,0,0,0,0,0,0,0)';
      BIDIRECTIONAL='TRUE';
      INPUT_LOAD='(-0.01,0.01)';
      OUTPUT_LOAD='(1.0,-1.0)';
      PINUSE='BI';
    'DDR5_SB_ECC6':
      PIN_NUMBER='(0,0,0,0,0,0,0,0,0,0,0,0,EG35,0,0,0,0,0,0,0,0,0,0,0,0,0,0,0,0,~
0,0,0,0,0,0,0,0,0,0,0,0,0)';
      BIDIRECTIONAL='TRUE';
      INPUT_LOAD='(-0.01,0.01)';
      OUTPUT_LOAD='(1.0,-1.0)';
      PINUSE='BI';
    'DDR5_SB_ECC5':
      PIN_NUMBER='(0,0,0,0,0,0,0,0,0,0,0,0,ED34,0,0,0,0,0,0,0,0,0,0,0,0,0,0,0,0,~
0,0,0,0,0,0,0,0,0,0,0,0,0)';
      BIDIRECTIONAL='TRUE';
      INPUT_LOAD='(-0.01,0.01)';
      OUTPUT_LOAD='(1.0,-1.0)';
      PINUSE='BI';
    'DDR5_SB_ECC4':
      PIN_NUMBER='(0,0,0,0,0,0,0,0,0,0,0,0,EE35,0,0,0,0,0,0,0,0,0,0,0,0,0,0,0,0,~
0,0,0,0,0,0,0,0,0,0,0,0,0)';
      BIDIRECTIONAL='TRUE';
      INPUT_LOAD='(-0.01,0.01)';
      OUTPUT_LOAD='(1.0,-1.0)';
      PINUSE='BI';
    'DDR5_SB_ECC3':
      PIN_NUMBER='(0,0,0,0,0,0,0,0,0,0,0,0,EG31,0,0,0,0,0,0,0,0,0,0,0,0,0,0,0,0,~
0,0,0,0,0,0,0,0,0,0,0,0,0)';
      BIDIRECTIONAL='TRUE';
      INPUT_LOAD='(-0.01,0.01)';
      OUTPUT_LOAD='(1.0,-1.0)';
      PINUSE='BI';
    'DDR5_SB_ECC2':
      PIN_NUMBER='(0,0,0,0,0,0,0,0,0,0,0,0,EH32,0,0,0,0,0,0,0,0,0,0,0,0,0,0,0,0,~
0,0,0,0,0,0,0,0,0,0,0,0,0)';
      BIDIRECTIONAL='TRUE';
      INPUT_LOAD='(-0.01,0.01)';
      OUTPUT_LOAD='(1.0,-1.0)';
      PINUSE='BI';
    'DDR5_SB_ECC1':
      PIN_NUMBER='(0,0,0,0,0,0,0,0,0,0,0,0,EE31,0,0,0,0,0,0,0,0,0,0,0,0,0,0,0,0,~
0,0,0,0,0,0,0,0,0,0,0,0,0)';
      BIDIRECTIONAL='TRUE';
      INPUT_LOAD='(-0.01,0.01)';
      OUTPUT_LOAD='(1.0,-1.0)';
      PINUSE='BI';
    'DDR5_SB_ECC0':
      PIN_NUMBER='(0,0,0,0,0,0,0,0,0,0,0,0,ED32,0,0,0,0,0,0,0,0,0,0,0,0,0,0,0,0,~
0,0,0,0,0,0,0,0,0,0,0,0,0)';
      BIDIRECTIONAL='TRUE';
      INPUT_LOAD='(-0.01,0.01)';
      OUTPUT_LOAD='(1.0,-1.0)';
      PINUSE='BI';
    'DDR5_SB_PAR':
      PIN_NUMBER='(0,0,0,0,0,0,0,0,0,0,0,0,EJ39,0,0,0,0,0,0,0,0,0,0,0,0,0,0,0,0,~
0,0,0,0,0,0,0,0,0,0,0,0,0)';
      OUTPUT_LOAD='(1.0,-1.0)';
      PINUSE='OUT';
    'DDR6_ALERT_N':
      PIN_NUMBER='(0,0,0,0,0,0,0,0,0,0,0,0,0,CW50,0,0,0,0,0,0,0,0,0,0,0,0,0,0,0,~
0,0,0,0,0,0,0,0,0,0,0,0,0)';
      INPUT_LOAD='(-0.01,0.01)';
      PINUSE='IN';
    'DDR6_A_RSP1':
      PIN_NUMBER='(0,0,0,0,0,0,0,0,0,0,0,0,0,DY47,0,0,0,0,0,0,0,0,0,0,0,0,0,0,0,~
0,0,0,0,0,0,0,0,0,0,0,0,0)';
      INPUT_LOAD='(-0.01,0.01)';
      PINUSE='IN';
    'DDR6_A_RSP0':
      PIN_NUMBER='(0,0,0,0,0,0,0,0,0,0,0,0,0,EA48,0,0,0,0,0,0,0,0,0,0,0,0,0,0,0,~
0,0,0,0,0,0,0,0,0,0,0,0,0)';
      INPUT_LOAD='(-0.01,0.01)';
      PINUSE='IN';
    'DDR6_B_RSP1':
      PIN_NUMBER='(0,0,0,0,0,0,0,0,0,0,0,0,0,DV47,0,0,0,0,0,0,0,0,0,0,0,0,0,0,0,~
0,0,0,0,0,0,0,0,0,0,0,0,0)';
      INPUT_LOAD='(-0.01,0.01)';
      PINUSE='IN';
    'DDR6_B_RSP0':
      PIN_NUMBER='(0,0,0,0,0,0,0,0,0,0,0,0,0,DU48,0,0,0,0,0,0,0,0,0,0,0,0,0,0,0,~
0,0,0,0,0,0,0,0,0,0,0,0,0)';
      INPUT_LOAD='(-0.01,0.01)';
      PINUSE='IN';
    'DDR6_CLK_DN1':
      PIN_NUMBER='(0,0,0,0,0,0,0,0,0,0,0,0,0,DL45,0,0,0,0,0,0,0,0,0,0,0,0,0,0,0,~
0,0,0,0,0,0,0,0,0,0,0,0,0)';
      OUTPUT_LOAD='(1.0,-1.0)';
      PINUSE='OUT';
    'DDR6_CLK_DN0':
      PIN_NUMBER='(0,0,0,0,0,0,0,0,0,0,0,0,0,DR45,0,0,0,0,0,0,0,0,0,0,0,0,0,0,0,~
0,0,0,0,0,0,0,0,0,0,0,0,0)';
      OUTPUT_LOAD='(1.0,-1.0)';
      PINUSE='OUT';
    'DDR6_CLK_DP1':
      PIN_NUMBER='(0,0,0,0,0,0,0,0,0,0,0,0,0,DJ45,0,0,0,0,0,0,0,0,0,0,0,0,0,0,0,~
0,0,0,0,0,0,0,0,0,0,0,0,0)';
      OUTPUT_LOAD='(1.0,-1.0)';
      PINUSE='OUT';
    'DDR6_CLK_DP0':
      PIN_NUMBER='(0,0,0,0,0,0,0,0,0,0,0,0,0,DN45,0,0,0,0,0,0,0,0,0,0,0,0,0,0,0,~
0,0,0,0,0,0,0,0,0,0,0,0,0)';
      OUTPUT_LOAD='(1.0,-1.0)';
      PINUSE='OUT';
    'DDR6_SA_CA6':
      PIN_NUMBER='(0,0,0,0,0,0,0,0,0,0,0,0,0,DK44,0,0,0,0,0,0,0,0,0,0,0,0,0,0,0,~
0,0,0,0,0,0,0,0,0,0,0,0,0)';
      OUTPUT_LOAD='(1.0,-1.0)';
      PINUSE='OUT';
    'DDR6_SA_CA5':
      PIN_NUMBER='(0,0,0,0,0,0,0,0,0,0,0,0,0,DN50,0,0,0,0,0,0,0,0,0,0,0,0,0,0,0,~
0,0,0,0,0,0,0,0,0,0,0,0,0)';
      OUTPUT_LOAD='(1.0,-1.0)';
      PINUSE='OUT';
    'DDR6_SA_CA4':
      PIN_NUMBER='(0,0,0,0,0,0,0,0,0,0,0,0,0,DL50,0,0,0,0,0,0,0,0,0,0,0,0,0,0,0,~
0,0,0,0,0,0,0,0,0,0,0,0,0)';
      OUTPUT_LOAD='(1.0,-1.0)';
      PINUSE='OUT';
    'DDR6_SA_CA3':
      PIN_NUMBER='(0,0,0,0,0,0,0,0,0,0,0,0,0,DP51,0,0,0,0,0,0,0,0,0,0,0,0,0,0,0,~
0,0,0,0,0,0,0,0,0,0,0,0,0)';
      OUTPUT_LOAD='(1.0,-1.0)';
      PINUSE='OUT';
    'DDR6_SA_CA2':
      PIN_NUMBER='(0,0,0,0,0,0,0,0,0,0,0,0,0,DK51,0,0,0,0,0,0,0,0,0,0,0,0,0,0,0,~
0,0,0,0,0,0,0,0,0,0,0,0,0)';
      OUTPUT_LOAD='(1.0,-1.0)';
      PINUSE='OUT';
    'DDR6_SA_CA1':
      PIN_NUMBER='(0,0,0,0,0,0,0,0,0,0,0,0,0,DR52,0,0,0,0,0,0,0,0,0,0,0,0,0,0,0,~
0,0,0,0,0,0,0,0,0,0,0,0,0)';
      OUTPUT_LOAD='(1.0,-1.0)';
      PINUSE='OUT';
    'DDR6_SA_CA0':
      PIN_NUMBER='(0,0,0,0,0,0,0,0,0,0,0,0,0,DJ52,0,0,0,0,0,0,0,0,0,0,0,0,0,0,0,~
0,0,0,0,0,0,0,0,0,0,0,0,0)';
      OUTPUT_LOAD='(1.0,-1.0)';
      PINUSE='OUT';
    'DDR6_SA_CS_N3':
      PIN_NUMBER='(0,0,0,0,0,0,0,0,0,0,0,0,0,DK53,0,0,0,0,0,0,0,0,0,0,0,0,0,0,0,~
0,0,0,0,0,0,0,0,0,0,0,0,0)';
      OUTPUT_LOAD='(1.0,-1.0)';
      PINUSE='OUT';
    'DDR6_SA_CS_N2':
      PIN_NUMBER='(0,0,0,0,0,0,0,0,0,0,0,0,0,DL54,0,0,0,0,0,0,0,0,0,0,0,0,0,0,0,~
0,0,0,0,0,0,0,0,0,0,0,0,0)';
      OUTPUT_LOAD='(1.0,-1.0)';
      PINUSE='OUT';
    'DDR6_SA_CS_N1':
      PIN_NUMBER='(0,0,0,0,0,0,0,0,0,0,0,0,0,DP53,0,0,0,0,0,0,0,0,0,0,0,0,0,0,0,~
0,0,0,0,0,0,0,0,0,0,0,0,0)';
      OUTPUT_LOAD='(1.0,-1.0)';
      PINUSE='OUT';
    'DDR6_SA_CS_N0':
      PIN_NUMBER='(0,0,0,0,0,0,0,0,0,0,0,0,0,DN54,0,0,0,0,0,0,0,0,0,0,0,0,0,0,0,~
0,0,0,0,0,0,0,0,0,0,0,0,0)';
      OUTPUT_LOAD='(1.0,-1.0)';
      PINUSE='OUT';
    'DDR6_SA_DQ31':
      PIN_NUMBER='(0,0,0,0,0,0,0,0,0,0,0,0,0,DN62,0,0,0,0,0,0,0,0,0,0,0,0,0,0,0,~
0,0,0,0,0,0,0,0,0,0,0,0,0)';
      BIDIRECTIONAL='TRUE';
      INPUT_LOAD='(-0.01,0.01)';
      OUTPUT_LOAD='(1.0,-1.0)';
      PINUSE='BI';
    'DDR6_SA_DQ30':
      PIN_NUMBER='(0,0,0,0,0,0,0,0,0,0,0,0,0,DP63,0,0,0,0,0,0,0,0,0,0,0,0,0,0,0,~
0,0,0,0,0,0,0,0,0,0,0,0,0)';
      BIDIRECTIONAL='TRUE';
      INPUT_LOAD='(-0.01,0.01)';
      OUTPUT_LOAD='(1.0,-1.0)';
      PINUSE='BI';
    'DDR6_SA_DQ29':
      PIN_NUMBER='(0,0,0,0,0,0,0,0,0,0,0,0,0,DL62,0,0,0,0,0,0,0,0,0,0,0,0,0,0,0,~
0,0,0,0,0,0,0,0,0,0,0,0,0)';
      BIDIRECTIONAL='TRUE';
      INPUT_LOAD='(-0.01,0.01)';
      OUTPUT_LOAD='(1.0,-1.0)';
      PINUSE='BI';
    'DDR6_SA_DQ28':
      PIN_NUMBER='(0,0,0,0,0,0,0,0,0,0,0,0,0,DK63,0,0,0,0,0,0,0,0,0,0,0,0,0,0,0,~
0,0,0,0,0,0,0,0,0,0,0,0,0)';
      BIDIRECTIONAL='TRUE';
      INPUT_LOAD='(-0.01,0.01)';
      OUTPUT_LOAD='(1.0,-1.0)';
      PINUSE='BI';
    'DDR6_SA_DQ27':
      PIN_NUMBER='(0,0,0,0,0,0,0,0,0,0,0,0,0,DP65,0,0,0,0,0,0,0,0,0,0,0,0,0,0,0,~
0,0,0,0,0,0,0,0,0,0,0,0,0)';
      BIDIRECTIONAL='TRUE';
      INPUT_LOAD='(-0.01,0.01)';
      OUTPUT_LOAD='(1.0,-1.0)';
      PINUSE='BI';
    'DDR6_SA_DQ26':
      PIN_NUMBER='(0,0,0,0,0,0,0,0,0,0,0,0,0,DN66,0,0,0,0,0,0,0,0,0,0,0,0,0,0,0,~
0,0,0,0,0,0,0,0,0,0,0,0,0)';
      BIDIRECTIONAL='TRUE';
      INPUT_LOAD='(-0.01,0.01)';
      OUTPUT_LOAD='(1.0,-1.0)';
      PINUSE='BI';
    'DDR6_SA_DQ25':
      PIN_NUMBER='(0,0,0,0,0,0,0,0,0,0,0,0,0,DK65,0,0,0,0,0,0,0,0,0,0,0,0,0,0,0,~
0,0,0,0,0,0,0,0,0,0,0,0,0)';
      BIDIRECTIONAL='TRUE';
      INPUT_LOAD='(-0.01,0.01)';
      OUTPUT_LOAD='(1.0,-1.0)';
      PINUSE='BI';
    'DDR6_SA_DQ24':
      PIN_NUMBER='(0,0,0,0,0,0,0,0,0,0,0,0,0,DL66,0,0,0,0,0,0,0,0,0,0,0,0,0,0,0,~
0,0,0,0,0,0,0,0,0,0,0,0,0)';
      BIDIRECTIONAL='TRUE';
      INPUT_LOAD='(-0.01,0.01)';
      OUTPUT_LOAD='(1.0,-1.0)';
      PINUSE='BI';
    'DDR6_SA_DQ23':
      PIN_NUMBER='(0,0,0,0,0,0,0,0,0,0,0,0,0,DY59,0,0,0,0,0,0,0,0,0,0,0,0,0,0,0,~
0,0,0,0,0,0,0,0,0,0,0,0,0)';
      BIDIRECTIONAL='TRUE';
      INPUT_LOAD='(-0.01,0.01)';
      OUTPUT_LOAD='(1.0,-1.0)';
      PINUSE='BI';
    'DDR6_SA_DQ22':
      PIN_NUMBER='(0,0,0,0,0,0,0,0,0,0,0,0,0,EA60,0,0,0,0,0,0,0,0,0,0,0,0,0,0,0,~
0,0,0,0,0,0,0,0,0,0,0,0,0)';
      BIDIRECTIONAL='TRUE';
      INPUT_LOAD='(-0.01,0.01)';
      OUTPUT_LOAD='(1.0,-1.0)';
      PINUSE='BI';
    'DDR6_SA_DQ21':
      PIN_NUMBER='(0,0,0,0,0,0,0,0,0,0,0,0,0,DV59,0,0,0,0,0,0,0,0,0,0,0,0,0,0,0,~
0,0,0,0,0,0,0,0,0,0,0,0,0)';
      BIDIRECTIONAL='TRUE';
      INPUT_LOAD='(-0.01,0.01)';
      OUTPUT_LOAD='(1.0,-1.0)';
      PINUSE='BI';
    'DDR6_SA_DQ20':
      PIN_NUMBER='(0,0,0,0,0,0,0,0,0,0,0,0,0,DU60,0,0,0,0,0,0,0,0,0,0,0,0,0,0,0,~
0,0,0,0,0,0,0,0,0,0,0,0,0)';
      BIDIRECTIONAL='TRUE';
      INPUT_LOAD='(-0.01,0.01)';
      OUTPUT_LOAD='(1.0,-1.0)';
      PINUSE='BI';
    'DDR6_SA_DQ19':
      PIN_NUMBER='(0,0,0,0,0,0,0,0,0,0,0,0,0,EA62,0,0,0,0,0,0,0,0,0,0,0,0,0,0,0,~
0,0,0,0,0,0,0,0,0,0,0,0,0)';
      BIDIRECTIONAL='TRUE';
      INPUT_LOAD='(-0.01,0.01)';
      OUTPUT_LOAD='(1.0,-1.0)';
      PINUSE='BI';
    'DDR6_SA_DQ18':
      PIN_NUMBER='(0,0,0,0,0,0,0,0,0,0,0,0,0,DY63,0,0,0,0,0,0,0,0,0,0,0,0,0,0,0,~
0,0,0,0,0,0,0,0,0,0,0,0,0)';
      BIDIRECTIONAL='TRUE';
      INPUT_LOAD='(-0.01,0.01)';
      OUTPUT_LOAD='(1.0,-1.0)';
      PINUSE='BI';
    'DDR6_SA_DQ17':
      PIN_NUMBER='(0,0,0,0,0,0,0,0,0,0,0,0,0,DU62,0,0,0,0,0,0,0,0,0,0,0,0,0,0,0,~
0,0,0,0,0,0,0,0,0,0,0,0,0)';
      BIDIRECTIONAL='TRUE';
      INPUT_LOAD='(-0.01,0.01)';
      OUTPUT_LOAD='(1.0,-1.0)';
      PINUSE='BI';
    'DDR6_SA_DQ16':
      PIN_NUMBER='(0,0,0,0,0,0,0,0,0,0,0,0,0,DV63,0,0,0,0,0,0,0,0,0,0,0,0,0,0,0,~
0,0,0,0,0,0,0,0,0,0,0,0,0)';
      BIDIRECTIONAL='TRUE';
      INPUT_LOAD='(-0.01,0.01)';
      OUTPUT_LOAD='(1.0,-1.0)';
      PINUSE='BI';
    'DDR6_SA_DQ15':
      PIN_NUMBER='(0,0,0,0,0,0,0,0,0,0,0,0,0,DN68,0,0,0,0,0,0,0,0,0,0,0,0,0,0,0,~
0,0,0,0,0,0,0,0,0,0,0,0,0)';
      BIDIRECTIONAL='TRUE';
      INPUT_LOAD='(-0.01,0.01)';
      OUTPUT_LOAD='(1.0,-1.0)';
      PINUSE='BI';
    'DDR6_SA_DQ14':
      PIN_NUMBER='(0,0,0,0,0,0,0,0,0,0,0,0,0,DP69,0,0,0,0,0,0,0,0,0,0,0,0,0,0,0,~
0,0,0,0,0,0,0,0,0,0,0,0,0)';
      BIDIRECTIONAL='TRUE';
      INPUT_LOAD='(-0.01,0.01)';
      OUTPUT_LOAD='(1.0,-1.0)';
      PINUSE='BI';
    'DDR6_SA_DQ13':
      PIN_NUMBER='(0,0,0,0,0,0,0,0,0,0,0,0,0,DL68,0,0,0,0,0,0,0,0,0,0,0,0,0,0,0,~
0,0,0,0,0,0,0,0,0,0,0,0,0)';
      BIDIRECTIONAL='TRUE';
      INPUT_LOAD='(-0.01,0.01)';
      OUTPUT_LOAD='(1.0,-1.0)';
      PINUSE='BI';
    'DDR6_SA_DQ12':
      PIN_NUMBER='(0,0,0,0,0,0,0,0,0,0,0,0,0,DK69,0,0,0,0,0,0,0,0,0,0,0,0,0,0,0,~
0,0,0,0,0,0,0,0,0,0,0,0,0)';
      BIDIRECTIONAL='TRUE';
      INPUT_LOAD='(-0.01,0.01)';
      OUTPUT_LOAD='(1.0,-1.0)';
      PINUSE='BI';
    'DDR6_SA_DQ11':
      PIN_NUMBER='(0,0,0,0,0,0,0,0,0,0,0,0,0,DP71,0,0,0,0,0,0,0,0,0,0,0,0,0,0,0,~
0,0,0,0,0,0,0,0,0,0,0,0,0)';
      BIDIRECTIONAL='TRUE';
      INPUT_LOAD='(-0.01,0.01)';
      OUTPUT_LOAD='(1.0,-1.0)';
      PINUSE='BI';
    'DDR6_SA_DQ10':
      PIN_NUMBER='(0,0,0,0,0,0,0,0,0,0,0,0,0,DN72,0,0,0,0,0,0,0,0,0,0,0,0,0,0,0,~
0,0,0,0,0,0,0,0,0,0,0,0,0)';
      BIDIRECTIONAL='TRUE';
      INPUT_LOAD='(-0.01,0.01)';
      OUTPUT_LOAD='(1.0,-1.0)';
      PINUSE='BI';
    'DDR6_SA_DQ9':
      PIN_NUMBER='(0,0,0,0,0,0,0,0,0,0,0,0,0,DK71,0,0,0,0,0,0,0,0,0,0,0,0,0,0,0,~
0,0,0,0,0,0,0,0,0,0,0,0,0)';
      BIDIRECTIONAL='TRUE';
      INPUT_LOAD='(-0.01,0.01)';
      OUTPUT_LOAD='(1.0,-1.0)';
      PINUSE='BI';
    'DDR6_SA_DQ8':
      PIN_NUMBER='(0,0,0,0,0,0,0,0,0,0,0,0,0,DL72,0,0,0,0,0,0,0,0,0,0,0,0,0,0,0,~
0,0,0,0,0,0,0,0,0,0,0,0,0)';
      BIDIRECTIONAL='TRUE';
      INPUT_LOAD='(-0.01,0.01)';
      OUTPUT_LOAD='(1.0,-1.0)';
      PINUSE='BI';
    'DDR6_SA_DQ7':
      PIN_NUMBER='(0,0,0,0,0,0,0,0,0,0,0,0,0,DY71,0,0,0,0,0,0,0,0,0,0,0,0,0,0,0,~
0,0,0,0,0,0,0,0,0,0,0,0,0)';
      BIDIRECTIONAL='TRUE';
      INPUT_LOAD='(-0.01,0.01)';
      OUTPUT_LOAD='(1.0,-1.0)';
      PINUSE='BI';
    'DDR6_SA_DQ6':
      PIN_NUMBER='(0,0,0,0,0,0,0,0,0,0,0,0,0,EA72,0,0,0,0,0,0,0,0,0,0,0,0,0,0,0,~
0,0,0,0,0,0,0,0,0,0,0,0,0)';
      BIDIRECTIONAL='TRUE';
      INPUT_LOAD='(-0.01,0.01)';
      OUTPUT_LOAD='(1.0,-1.0)';
      PINUSE='BI';
    'DDR6_SA_DQ5':
      PIN_NUMBER='(0,0,0,0,0,0,0,0,0,0,0,0,0,DV71,0,0,0,0,0,0,0,0,0,0,0,0,0,0,0,~
0,0,0,0,0,0,0,0,0,0,0,0,0)';
      BIDIRECTIONAL='TRUE';
      INPUT_LOAD='(-0.01,0.01)';
      OUTPUT_LOAD='(1.0,-1.0)';
      PINUSE='BI';
    'DDR6_SA_DQ4':
      PIN_NUMBER='(0,0,0,0,0,0,0,0,0,0,0,0,0,DU72,0,0,0,0,0,0,0,0,0,0,0,0,0,0,0,~
0,0,0,0,0,0,0,0,0,0,0,0,0)';
      BIDIRECTIONAL='TRUE';
      INPUT_LOAD='(-0.01,0.01)';
      OUTPUT_LOAD='(1.0,-1.0)';
      PINUSE='BI';
    'DDR6_SA_DQ3':
      PIN_NUMBER='(0,0,0,0,0,0,0,0,0,0,0,0,0,EA74,0,0,0,0,0,0,0,0,0,0,0,0,0,0,0,~
0,0,0,0,0,0,0,0,0,0,0,0,0)';
      BIDIRECTIONAL='TRUE';
      INPUT_LOAD='(-0.01,0.01)';
      OUTPUT_LOAD='(1.0,-1.0)';
      PINUSE='BI';
    'DDR6_SA_DQ2':
      PIN_NUMBER='(0,0,0,0,0,0,0,0,0,0,0,0,0,DY75,0,0,0,0,0,0,0,0,0,0,0,0,0,0,0,~
0,0,0,0,0,0,0,0,0,0,0,0,0)';
      BIDIRECTIONAL='TRUE';
      INPUT_LOAD='(-0.01,0.01)';
      OUTPUT_LOAD='(1.0,-1.0)';
      PINUSE='BI';
    'DDR6_SA_DQ1':
      PIN_NUMBER='(0,0,0,0,0,0,0,0,0,0,0,0,0,DU74,0,0,0,0,0,0,0,0,0,0,0,0,0,0,0,~
0,0,0,0,0,0,0,0,0,0,0,0,0)';
      BIDIRECTIONAL='TRUE';
      INPUT_LOAD='(-0.01,0.01)';
      OUTPUT_LOAD='(1.0,-1.0)';
      PINUSE='BI';
    'DDR6_SA_DQ0':
      PIN_NUMBER='(0,0,0,0,0,0,0,0,0,0,0,0,0,DV75,0,0,0,0,0,0,0,0,0,0,0,0,0,0,0,~
0,0,0,0,0,0,0,0,0,0,0,0,0)';
      BIDIRECTIONAL='TRUE';
      INPUT_LOAD='(-0.01,0.01)';
      OUTPUT_LOAD='(1.0,-1.0)';
      PINUSE='BI';
    'DDR6_SA_DQS_DN9':
      PIN_NUMBER='(0,0,0,0,0,0,0,0,0,0,0,0,0,DR58,0,0,0,0,0,0,0,0,0,0,0,0,0,0,0,~
0,0,0,0,0,0,0,0,0,0,0,0,0)';
      BIDIRECTIONAL='TRUE';
      INPUT_LOAD='(-0.01,0.01)';
      OUTPUT_LOAD='(1.0,-1.0)';
      PINUSE='BI';
    'DDR6_SA_DQS_DN8':
      PIN_NUMBER='(0,0,0,0,0,0,0,0,0,0,0,0,0,DR64,0,0,0,0,0,0,0,0,0,0,0,0,0,0,0,~
0,0,0,0,0,0,0,0,0,0,0,0,0)';
      BIDIRECTIONAL='TRUE';
      INPUT_LOAD='(-0.01,0.01)';
      OUTPUT_LOAD='(1.0,-1.0)';
      PINUSE='BI';
    'DDR6_SA_DQS_DN7':
      PIN_NUMBER='(0,0,0,0,0,0,0,0,0,0,0,0,0,EB61,0,0,0,0,0,0,0,0,0,0,0,0,0,0,0,~
0,0,0,0,0,0,0,0,0,0,0,0,0)';
      BIDIRECTIONAL='TRUE';
      INPUT_LOAD='(-0.01,0.01)';
      OUTPUT_LOAD='(1.0,-1.0)';
      PINUSE='BI';
    'DDR6_SA_DQS_DN6':
      PIN_NUMBER='(0,0,0,0,0,0,0,0,0,0,0,0,0,DR70,0,0,0,0,0,0,0,0,0,0,0,0,0,0,0,~
0,0,0,0,0,0,0,0,0,0,0,0,0)';
      BIDIRECTIONAL='TRUE';
      INPUT_LOAD='(-0.01,0.01)';
      OUTPUT_LOAD='(1.0,-1.0)';
      PINUSE='BI';
    'DDR6_SA_DQS_DN5':
      PIN_NUMBER='(0,0,0,0,0,0,0,0,0,0,0,0,0,EB73,0,0,0,0,0,0,0,0,0,0,0,0,0,0,0,~
0,0,0,0,0,0,0,0,0,0,0,0,0)';
      BIDIRECTIONAL='TRUE';
      INPUT_LOAD='(-0.01,0.01)';
      OUTPUT_LOAD='(1.0,-1.0)';
      PINUSE='BI';
    'DDR6_SA_DQS_DN4':
      PIN_NUMBER='(0,0,0,0,0,0,0,0,0,0,0,0,0,DL58,0,0,0,0,0,0,0,0,0,0,0,0,0,0,0,~
0,0,0,0,0,0,0,0,0,0,0,0,0)';
      BIDIRECTIONAL='TRUE';
      INPUT_LOAD='(-0.01,0.01)';
      OUTPUT_LOAD='(1.0,-1.0)';
      PINUSE='BI';
    'DDR6_SA_DQS_DN3':
      PIN_NUMBER='(0,0,0,0,0,0,0,0,0,0,0,0,0,DL64,0,0,0,0,0,0,0,0,0,0,0,0,0,0,0,~
0,0,0,0,0,0,0,0,0,0,0,0,0)';
      BIDIRECTIONAL='TRUE';
      INPUT_LOAD='(-0.01,0.01)';
      OUTPUT_LOAD='(1.0,-1.0)';
      PINUSE='BI';
    'DDR6_SA_DQS_DN2':
      PIN_NUMBER='(0,0,0,0,0,0,0,0,0,0,0,0,0,DT61,0,0,0,0,0,0,0,0,0,0,0,0,0,0,0,~
0,0,0,0,0,0,0,0,0,0,0,0,0)';
      BIDIRECTIONAL='TRUE';
      INPUT_LOAD='(-0.01,0.01)';
      OUTPUT_LOAD='(1.0,-1.0)';
      PINUSE='BI';
    'DDR6_SA_DQS_DN1':
      PIN_NUMBER='(0,0,0,0,0,0,0,0,0,0,0,0,0,DJ70,0,0,0,0,0,0,0,0,0,0,0,0,0,0,0,~
0,0,0,0,0,0,0,0,0,0,0,0,0)';
      BIDIRECTIONAL='TRUE';
      INPUT_LOAD='(-0.01,0.01)';
      OUTPUT_LOAD='(1.0,-1.0)';
      PINUSE='BI';
    'DDR6_SA_DQS_DN0':
      PIN_NUMBER='(0,0,0,0,0,0,0,0,0,0,0,0,0,DV73,0,0,0,0,0,0,0,0,0,0,0,0,0,0,0,~
0,0,0,0,0,0,0,0,0,0,0,0,0)';
      BIDIRECTIONAL='TRUE';
      INPUT_LOAD='(-0.01,0.01)';
      OUTPUT_LOAD='(1.0,-1.0)';
      PINUSE='BI';
    'DDR6_SA_DQS_DP9':
      PIN_NUMBER='(0,0,0,0,0,0,0,0,0,0,0,0,0,DN58,0,0,0,0,0,0,0,0,0,0,0,0,0,0,0,~
0,0,0,0,0,0,0,0,0,0,0,0,0)';
      BIDIRECTIONAL='TRUE';
      INPUT_LOAD='(-0.01,0.01)';
      OUTPUT_LOAD='(1.0,-1.0)';
      PINUSE='BI';
    'DDR6_SA_DQS_DP8':
      PIN_NUMBER='(0,0,0,0,0,0,0,0,0,0,0,0,0,DN64,0,0,0,0,0,0,0,0,0,0,0,0,0,0,0,~
0,0,0,0,0,0,0,0,0,0,0,0,0)';
      BIDIRECTIONAL='TRUE';
      INPUT_LOAD='(-0.01,0.01)';
      OUTPUT_LOAD='(1.0,-1.0)';
      PINUSE='BI';
    'DDR6_SA_DQS_DP7':
      PIN_NUMBER='(0,0,0,0,0,0,0,0,0,0,0,0,0,DY61,0,0,0,0,0,0,0,0,0,0,0,0,0,0,0,~
0,0,0,0,0,0,0,0,0,0,0,0,0)';
      BIDIRECTIONAL='TRUE';
      INPUT_LOAD='(-0.01,0.01)';
      OUTPUT_LOAD='(1.0,-1.0)';
      PINUSE='BI';
    'DDR6_SA_DQS_DP6':
      PIN_NUMBER='(0,0,0,0,0,0,0,0,0,0,0,0,0,DN70,0,0,0,0,0,0,0,0,0,0,0,0,0,0,0,~
0,0,0,0,0,0,0,0,0,0,0,0,0)';
      BIDIRECTIONAL='TRUE';
      INPUT_LOAD='(-0.01,0.01)';
      OUTPUT_LOAD='(1.0,-1.0)';
      PINUSE='BI';
    'DDR6_SA_DQS_DP5':
      PIN_NUMBER='(0,0,0,0,0,0,0,0,0,0,0,0,0,DY73,0,0,0,0,0,0,0,0,0,0,0,0,0,0,0,~
0,0,0,0,0,0,0,0,0,0,0,0,0)';
      BIDIRECTIONAL='TRUE';
      INPUT_LOAD='(-0.01,0.01)';
      OUTPUT_LOAD='(1.0,-1.0)';
      PINUSE='BI';
    'DDR6_SA_DQS_DP4':
      PIN_NUMBER='(0,0,0,0,0,0,0,0,0,0,0,0,0,DJ58,0,0,0,0,0,0,0,0,0,0,0,0,0,0,0,~
0,0,0,0,0,0,0,0,0,0,0,0,0)';
      BIDIRECTIONAL='TRUE';
      INPUT_LOAD='(-0.01,0.01)';
      OUTPUT_LOAD='(1.0,-1.0)';
      PINUSE='BI';
    'DDR6_SA_DQS_DP3':
      PIN_NUMBER='(0,0,0,0,0,0,0,0,0,0,0,0,0,DJ64,0,0,0,0,0,0,0,0,0,0,0,0,0,0,0,~
0,0,0,0,0,0,0,0,0,0,0,0,0)';
      BIDIRECTIONAL='TRUE';
      INPUT_LOAD='(-0.01,0.01)';
      OUTPUT_LOAD='(1.0,-1.0)';
      PINUSE='BI';
    'DDR6_SA_DQS_DP2':
      PIN_NUMBER='(0,0,0,0,0,0,0,0,0,0,0,0,0,DV61,0,0,0,0,0,0,0,0,0,0,0,0,0,0,0,~
0,0,0,0,0,0,0,0,0,0,0,0,0)';
      BIDIRECTIONAL='TRUE';
      INPUT_LOAD='(-0.01,0.01)';
      OUTPUT_LOAD='(1.0,-1.0)';
      PINUSE='BI';
    'DDR6_SA_DQS_DP1':
      PIN_NUMBER='(0,0,0,0,0,0,0,0,0,0,0,0,0,DL70,0,0,0,0,0,0,0,0,0,0,0,0,0,0,0,~
0,0,0,0,0,0,0,0,0,0,0,0,0)';
      BIDIRECTIONAL='TRUE';
      INPUT_LOAD='(-0.01,0.01)';
      OUTPUT_LOAD='(1.0,-1.0)';
      PINUSE='BI';
    'DDR6_SA_DQS_DP0':
      PIN_NUMBER='(0,0,0,0,0,0,0,0,0,0,0,0,0,DT73,0,0,0,0,0,0,0,0,0,0,0,0,0,0,0,~
0,0,0,0,0,0,0,0,0,0,0,0,0)';
      BIDIRECTIONAL='TRUE';
      INPUT_LOAD='(-0.01,0.01)';
      OUTPUT_LOAD='(1.0,-1.0)';
      PINUSE='BI';
    'DDR6_SA_ECC7':
      PIN_NUMBER='(0,0,0,0,0,0,0,0,0,0,0,0,0,DN56,0,0,0,0,0,0,0,0,0,0,0,0,0,0,0,~
0,0,0,0,0,0,0,0,0,0,0,0,0)';
      BIDIRECTIONAL='TRUE';
      INPUT_LOAD='(-0.01,0.01)';
      OUTPUT_LOAD='(1.0,-1.0)';
      PINUSE='BI';
    'DDR6_SA_ECC6':
      PIN_NUMBER='(0,0,0,0,0,0,0,0,0,0,0,0,0,DP57,0,0,0,0,0,0,0,0,0,0,0,0,0,0,0,~
0,0,0,0,0,0,0,0,0,0,0,0,0)';
      BIDIRECTIONAL='TRUE';
      INPUT_LOAD='(-0.01,0.01)';
      OUTPUT_LOAD='(1.0,-1.0)';
      PINUSE='BI';
    'DDR6_SA_ECC5':
      PIN_NUMBER='(0,0,0,0,0,0,0,0,0,0,0,0,0,DL56,0,0,0,0,0,0,0,0,0,0,0,0,0,0,0,~
0,0,0,0,0,0,0,0,0,0,0,0,0)';
      BIDIRECTIONAL='TRUE';
      INPUT_LOAD='(-0.01,0.01)';
      OUTPUT_LOAD='(1.0,-1.0)';
      PINUSE='BI';
    'DDR6_SA_ECC4':
      PIN_NUMBER='(0,0,0,0,0,0,0,0,0,0,0,0,0,DK57,0,0,0,0,0,0,0,0,0,0,0,0,0,0,0,~
0,0,0,0,0,0,0,0,0,0,0,0,0)';
      BIDIRECTIONAL='TRUE';
      INPUT_LOAD='(-0.01,0.01)';
      OUTPUT_LOAD='(1.0,-1.0)';
      PINUSE='BI';
    'DDR6_SA_ECC3':
      PIN_NUMBER='(0,0,0,0,0,0,0,0,0,0,0,0,0,DP59,0,0,0,0,0,0,0,0,0,0,0,0,0,0,0,~
0,0,0,0,0,0,0,0,0,0,0,0,0)';
      BIDIRECTIONAL='TRUE';
      INPUT_LOAD='(-0.01,0.01)';
      OUTPUT_LOAD='(1.0,-1.0)';
      PINUSE='BI';
    'DDR6_SA_ECC2':
      PIN_NUMBER='(0,0,0,0,0,0,0,0,0,0,0,0,0,DN60,0,0,0,0,0,0,0,0,0,0,0,0,0,0,0,~
0,0,0,0,0,0,0,0,0,0,0,0,0)';
      BIDIRECTIONAL='TRUE';
      INPUT_LOAD='(-0.01,0.01)';
      OUTPUT_LOAD='(1.0,-1.0)';
      PINUSE='BI';
    'DDR6_SA_ECC1':
      PIN_NUMBER='(0,0,0,0,0,0,0,0,0,0,0,0,0,DK59,0,0,0,0,0,0,0,0,0,0,0,0,0,0,0,~
0,0,0,0,0,0,0,0,0,0,0,0,0)';
      BIDIRECTIONAL='TRUE';
      INPUT_LOAD='(-0.01,0.01)';
      OUTPUT_LOAD='(1.0,-1.0)';
      PINUSE='BI';
    'DDR6_SA_ECC0':
      PIN_NUMBER='(0,0,0,0,0,0,0,0,0,0,0,0,0,DL60,0,0,0,0,0,0,0,0,0,0,0,0,0,0,0,~
0,0,0,0,0,0,0,0,0,0,0,0,0)';
      BIDIRECTIONAL='TRUE';
      INPUT_LOAD='(-0.01,0.01)';
      OUTPUT_LOAD='(1.0,-1.0)';
      PINUSE='BI';
    'DDR6_SA_PAR':
      PIN_NUMBER='(0,0,0,0,0,0,0,0,0,0,0,0,0,DL43,0,0,0,0,0,0,0,0,0,0,0,0,0,0,0,~
0,0,0,0,0,0,0,0,0,0,0,0,0)';
      OUTPUT_LOAD='(1.0,-1.0)';
      PINUSE='OUT';
    'DDR6_SB_CA6':
      PIN_NUMBER='(0,0,0,0,0,0,0,0,0,0,0,0,0,DT42,0,0,0,0,0,0,0,0,0,0,0,0,0,0,0,~
0,0,0,0,0,0,0,0,0,0,0,0,0)';
      OUTPUT_LOAD='(1.0,-1.0)';
      PINUSE='OUT';
    'DDR6_SB_CA5':
      PIN_NUMBER='(0,0,0,0,0,0,0,0,0,0,0,0,0,EA43,0,0,0,0,0,0,0,0,0,0,0,0,0,0,0,~
0,0,0,0,0,0,0,0,0,0,0,0,0)';
      OUTPUT_LOAD='(1.0,-1.0)';
      PINUSE='OUT';
    'DDR6_SB_CA4':
      PIN_NUMBER='(0,0,0,0,0,0,0,0,0,0,0,0,0,DU43,0,0,0,0,0,0,0,0,0,0,0,0,0,0,0,~
0,0,0,0,0,0,0,0,0,0,0,0,0)';
      OUTPUT_LOAD='(1.0,-1.0)';
      PINUSE='OUT';
    'DDR6_SB_CA3':
      PIN_NUMBER='(0,0,0,0,0,0,0,0,0,0,0,0,0,DY44,0,0,0,0,0,0,0,0,0,0,0,0,0,0,0,~
0,0,0,0,0,0,0,0,0,0,0,0,0)';
      OUTPUT_LOAD='(1.0,-1.0)';
      PINUSE='OUT';
    'DDR6_SB_CA2':
      PIN_NUMBER='(0,0,0,0,0,0,0,0,0,0,0,0,0,DV44,0,0,0,0,0,0,0,0,0,0,0,0,0,0,0,~
0,0,0,0,0,0,0,0,0,0,0,0,0)';
      OUTPUT_LOAD='(1.0,-1.0)';
      PINUSE='OUT';
    'DDR6_SB_CA1':
      PIN_NUMBER='(0,0,0,0,0,0,0,0,0,0,0,0,0,DP44,0,0,0,0,0,0,0,0,0,0,0,0,0,0,0,~
0,0,0,0,0,0,0,0,0,0,0,0,0)';
      OUTPUT_LOAD='(1.0,-1.0)';
      PINUSE='OUT';
    'DDR6_SB_CA0':
      PIN_NUMBER='(0,0,0,0,0,0,0,0,0,0,0,0,0,DN43,0,0,0,0,0,0,0,0,0,0,0,0,0,0,0,~
0,0,0,0,0,0,0,0,0,0,0,0,0)';
      OUTPUT_LOAD='(1.0,-1.0)';
      PINUSE='OUT';
    'DDR6_SB_CS_N3':
      PIN_NUMBER='(0,0,0,0,0,0,0,0,0,0,0,0,0,DV40,0,0,0,0,0,0,0,0,0,0,0,0,0,0,0,~
0,0,0,0,0,0,0,0,0,0,0,0,0)';
      OUTPUT_LOAD='(1.0,-1.0)';
      PINUSE='OUT';
    'DDR6_SB_CS_N2':
      PIN_NUMBER='(0,0,0,0,0,0,0,0,0,0,0,0,0,DU41,0,0,0,0,0,0,0,0,0,0,0,0,0,0,0,~
0,0,0,0,0,0,0,0,0,0,0,0,0)';
      OUTPUT_LOAD='(1.0,-1.0)';
      PINUSE='OUT';
    'DDR6_SB_CS_N1':
      PIN_NUMBER='(0,0,0,0,0,0,0,0,0,0,0,0,0,DY40,0,0,0,0,0,0,0,0,0,0,0,0,0,0,0,~
0,0,0,0,0,0,0,0,0,0,0,0,0)';
      OUTPUT_LOAD='(1.0,-1.0)';
      PINUSE='OUT';
    'DDR6_SB_CS_N0':
      PIN_NUMBER='(0,0,0,0,0,0,0,0,0,0,0,0,0,EA41,0,0,0,0,0,0,0,0,0,0,0,0,0,0,0,~
0,0,0,0,0,0,0,0,0,0,0,0,0)';
      OUTPUT_LOAD='(1.0,-1.0)';
      PINUSE='OUT';
    'DDR6_SB_DQ31':
      PIN_NUMBER='(0,0,0,0,0,0,0,0,0,0,0,0,0,EM4,0,0,0,0,0,0,0,0,0,0,0,0,0,0,0,0~
,0,0,0,0,0,0,0,0,0,0,0,0)';
      BIDIRECTIONAL='TRUE';
      INPUT_LOAD='(-0.01,0.01)';
      OUTPUT_LOAD='(1.0,-1.0)';
      PINUSE='BI';
    'DDR6_SB_DQ30':
      PIN_NUMBER='(0,0,0,0,0,0,0,0,0,0,0,0,0,EP4,0,0,0,0,0,0,0,0,0,0,0,0,0,0,0,0~
,0,0,0,0,0,0,0,0,0,0,0,0)';
      BIDIRECTIONAL='TRUE';
      INPUT_LOAD='(-0.01,0.01)';
      OUTPUT_LOAD='(1.0,-1.0)';
      PINUSE='BI';
    'DDR6_SB_DQ29':
      PIN_NUMBER='(0,0,0,0,0,0,0,0,0,0,0,0,0,EJ5,0,0,0,0,0,0,0,0,0,0,0,0,0,0,0,0~
,0,0,0,0,0,0,0,0,0,0,0,0)';
      BIDIRECTIONAL='TRUE';
      INPUT_LOAD='(-0.01,0.01)';
      OUTPUT_LOAD='(1.0,-1.0)';
      PINUSE='BI';
    'DDR6_SB_DQ28':
      PIN_NUMBER='(0,0,0,0,0,0,0,0,0,0,0,0,0,EK6,0,0,0,0,0,0,0,0,0,0,0,0,0,0,0,0~
,0,0,0,0,0,0,0,0,0,0,0,0)';
      BIDIRECTIONAL='TRUE';
      INPUT_LOAD='(-0.01,0.01)';
      OUTPUT_LOAD='(1.0,-1.0)';
      PINUSE='BI';
    'DDR6_SB_DQ27':
      PIN_NUMBER='(0,0,0,0,0,0,0,0,0,0,0,0,0,ET8,0,0,0,0,0,0,0,0,0,0,0,0,0,0,0,0~
,0,0,0,0,0,0,0,0,0,0,0,0)';
      BIDIRECTIONAL='TRUE';
      INPUT_LOAD='(-0.01,0.01)';
      OUTPUT_LOAD='(1.0,-1.0)';
      PINUSE='BI';
    'DDR6_SB_DQ26':
      PIN_NUMBER='(0,0,0,0,0,0,0,0,0,0,0,0,0,EP8,0,0,0,0,0,0,0,0,0,0,0,0,0,0,0,0~
,0,0,0,0,0,0,0,0,0,0,0,0)';
      BIDIRECTIONAL='TRUE';
      INPUT_LOAD='(-0.01,0.01)';
      OUTPUT_LOAD='(1.0,-1.0)';
      PINUSE='BI';
    'DDR6_SB_DQ25':
      PIN_NUMBER='(0,0,0,0,0,0,0,0,0,0,0,0,0,EH8,0,0,0,0,0,0,0,0,0,0,0,0,0,0,0,0~
,0,0,0,0,0,0,0,0,0,0,0,0)';
      BIDIRECTIONAL='TRUE';
      INPUT_LOAD='(-0.01,0.01)';
      OUTPUT_LOAD='(1.0,-1.0)';
      PINUSE='BI';
    'DDR6_SB_DQ24':
      PIN_NUMBER='(0,0,0,0,0,0,0,0,0,0,0,0,0,EK8,0,0,0,0,0,0,0,0,0,0,0,0,0,0,0,0~
,0,0,0,0,0,0,0,0,0,0,0,0)';
      BIDIRECTIONAL='TRUE';
      INPUT_LOAD='(-0.01,0.01)';
      OUTPUT_LOAD='(1.0,-1.0)';
      PINUSE='BI';
    'DDR6_SB_DQ23':
      PIN_NUMBER='(0,0,0,0,0,0,0,0,0,0,0,0,0,DY22,0,0,0,0,0,0,0,0,0,0,0,0,0,0,0,~
0,0,0,0,0,0,0,0,0,0,0,0,0)';
      BIDIRECTIONAL='TRUE';
      INPUT_LOAD='(-0.01,0.01)';
      OUTPUT_LOAD='(1.0,-1.0)';
      PINUSE='BI';
    'DDR6_SB_DQ22':
      PIN_NUMBER='(0,0,0,0,0,0,0,0,0,0,0,0,0,EA23,0,0,0,0,0,0,0,0,0,0,0,0,0,0,0,~
0,0,0,0,0,0,0,0,0,0,0,0,0)';
      BIDIRECTIONAL='TRUE';
      INPUT_LOAD='(-0.01,0.01)';
      OUTPUT_LOAD='(1.0,-1.0)';
      PINUSE='BI';
    'DDR6_SB_DQ21':
      PIN_NUMBER='(0,0,0,0,0,0,0,0,0,0,0,0,0,DV22,0,0,0,0,0,0,0,0,0,0,0,0,0,0,0,~
0,0,0,0,0,0,0,0,0,0,0,0,0)';
      BIDIRECTIONAL='TRUE';
      INPUT_LOAD='(-0.01,0.01)';
      OUTPUT_LOAD='(1.0,-1.0)';
      PINUSE='BI';
    'DDR6_SB_DQ20':
      PIN_NUMBER='(0,0,0,0,0,0,0,0,0,0,0,0,0,DU23,0,0,0,0,0,0,0,0,0,0,0,0,0,0,0,~
0,0,0,0,0,0,0,0,0,0,0,0,0)';
      BIDIRECTIONAL='TRUE';
      INPUT_LOAD='(-0.01,0.01)';
      OUTPUT_LOAD='(1.0,-1.0)';
      PINUSE='BI';
    'DDR6_SB_DQ19':
      PIN_NUMBER='(0,0,0,0,0,0,0,0,0,0,0,0,0,EA25,0,0,0,0,0,0,0,0,0,0,0,0,0,0,0,~
0,0,0,0,0,0,0,0,0,0,0,0,0)';
      BIDIRECTIONAL='TRUE';
      INPUT_LOAD='(-0.01,0.01)';
      OUTPUT_LOAD='(1.0,-1.0)';
      PINUSE='BI';
    'DDR6_SB_DQ18':
      PIN_NUMBER='(0,0,0,0,0,0,0,0,0,0,0,0,0,DY26,0,0,0,0,0,0,0,0,0,0,0,0,0,0,0,~
0,0,0,0,0,0,0,0,0,0,0,0,0)';
      BIDIRECTIONAL='TRUE';
      INPUT_LOAD='(-0.01,0.01)';
      OUTPUT_LOAD='(1.0,-1.0)';
      PINUSE='BI';
    'DDR6_SB_DQ17':
      PIN_NUMBER='(0,0,0,0,0,0,0,0,0,0,0,0,0,DU25,0,0,0,0,0,0,0,0,0,0,0,0,0,0,0,~
0,0,0,0,0,0,0,0,0,0,0,0,0)';
      BIDIRECTIONAL='TRUE';
      INPUT_LOAD='(-0.01,0.01)';
      OUTPUT_LOAD='(1.0,-1.0)';
      PINUSE='BI';
    'DDR6_SB_DQ16':
      PIN_NUMBER='(0,0,0,0,0,0,0,0,0,0,0,0,0,DV26,0,0,0,0,0,0,0,0,0,0,0,0,0,0,0,~
0,0,0,0,0,0,0,0,0,0,0,0,0)';
      BIDIRECTIONAL='TRUE';
      INPUT_LOAD='(-0.01,0.01)';
      OUTPUT_LOAD='(1.0,-1.0)';
      PINUSE='BI';
    'DDR6_SB_DQ15':
      PIN_NUMBER='(0,0,0,0,0,0,0,0,0,0,0,0,0,DN25,0,0,0,0,0,0,0,0,0,0,0,0,0,0,0,~
0,0,0,0,0,0,0,0,0,0,0,0,0)';
      BIDIRECTIONAL='TRUE';
      INPUT_LOAD='(-0.01,0.01)';
      OUTPUT_LOAD='(1.0,-1.0)';
      PINUSE='BI';
    'DDR6_SB_DQ14':
      PIN_NUMBER='(0,0,0,0,0,0,0,0,0,0,0,0,0,DP26,0,0,0,0,0,0,0,0,0,0,0,0,0,0,0,~
0,0,0,0,0,0,0,0,0,0,0,0,0)';
      BIDIRECTIONAL='TRUE';
      INPUT_LOAD='(-0.01,0.01)';
      OUTPUT_LOAD='(1.0,-1.0)';
      PINUSE='BI';
    'DDR6_SB_DQ13':
      PIN_NUMBER='(0,0,0,0,0,0,0,0,0,0,0,0,0,DL25,0,0,0,0,0,0,0,0,0,0,0,0,0,0,0,~
0,0,0,0,0,0,0,0,0,0,0,0,0)';
      BIDIRECTIONAL='TRUE';
      INPUT_LOAD='(-0.01,0.01)';
      OUTPUT_LOAD='(1.0,-1.0)';
      PINUSE='BI';
    'DDR6_SB_DQ12':
      PIN_NUMBER='(0,0,0,0,0,0,0,0,0,0,0,0,0,DK26,0,0,0,0,0,0,0,0,0,0,0,0,0,0,0,~
0,0,0,0,0,0,0,0,0,0,0,0,0)';
      BIDIRECTIONAL='TRUE';
      INPUT_LOAD='(-0.01,0.01)';
      OUTPUT_LOAD='(1.0,-1.0)';
      PINUSE='BI';
    'DDR6_SB_DQ11':
      PIN_NUMBER='(0,0,0,0,0,0,0,0,0,0,0,0,0,DP28,0,0,0,0,0,0,0,0,0,0,0,0,0,0,0,~
0,0,0,0,0,0,0,0,0,0,0,0,0)';
      BIDIRECTIONAL='TRUE';
      INPUT_LOAD='(-0.01,0.01)';
      OUTPUT_LOAD='(1.0,-1.0)';
      PINUSE='BI';
    'DDR6_SB_DQ10':
      PIN_NUMBER='(0,0,0,0,0,0,0,0,0,0,0,0,0,DL29,0,0,0,0,0,0,0,0,0,0,0,0,0,0,0,~
0,0,0,0,0,0,0,0,0,0,0,0,0)';
      BIDIRECTIONAL='TRUE';
      INPUT_LOAD='(-0.01,0.01)';
      OUTPUT_LOAD='(1.0,-1.0)';
      PINUSE='BI';
    'DDR6_SB_DQ9':
      PIN_NUMBER='(0,0,0,0,0,0,0,0,0,0,0,0,0,DK28,0,0,0,0,0,0,0,0,0,0,0,0,0,0,0,~
0,0,0,0,0,0,0,0,0,0,0,0,0)';
      BIDIRECTIONAL='TRUE';
      INPUT_LOAD='(-0.01,0.01)';
      OUTPUT_LOAD='(1.0,-1.0)';
      PINUSE='BI';
    'DDR6_SB_DQ8':
      PIN_NUMBER='(0,0,0,0,0,0,0,0,0,0,0,0,0,DN29,0,0,0,0,0,0,0,0,0,0,0,0,0,0,0,~
0,0,0,0,0,0,0,0,0,0,0,0,0)';
      BIDIRECTIONAL='TRUE';
      INPUT_LOAD='(-0.01,0.01)';
      OUTPUT_LOAD='(1.0,-1.0)';
      PINUSE='BI';
    'DDR6_SB_DQ7':
      PIN_NUMBER='(0,0,0,0,0,0,0,0,0,0,0,0,0,DN31,0,0,0,0,0,0,0,0,0,0,0,0,0,0,0,~
0,0,0,0,0,0,0,0,0,0,0,0,0)';
      BIDIRECTIONAL='TRUE';
      INPUT_LOAD='(-0.01,0.01)';
      OUTPUT_LOAD='(1.0,-1.0)';
      PINUSE='BI';
    'DDR6_SB_DQ6':
      PIN_NUMBER='(0,0,0,0,0,0,0,0,0,0,0,0,0,DP32,0,0,0,0,0,0,0,0,0,0,0,0,0,0,0,~
0,0,0,0,0,0,0,0,0,0,0,0,0)';
      BIDIRECTIONAL='TRUE';
      INPUT_LOAD='(-0.01,0.01)';
      OUTPUT_LOAD='(1.0,-1.0)';
      PINUSE='BI';
    'DDR6_SB_DQ5':
      PIN_NUMBER='(0,0,0,0,0,0,0,0,0,0,0,0,0,DL31,0,0,0,0,0,0,0,0,0,0,0,0,0,0,0,~
0,0,0,0,0,0,0,0,0,0,0,0,0)';
      BIDIRECTIONAL='TRUE';
      INPUT_LOAD='(-0.01,0.01)';
      OUTPUT_LOAD='(1.0,-1.0)';
      PINUSE='BI';
    'DDR6_SB_DQ4':
      PIN_NUMBER='(0,0,0,0,0,0,0,0,0,0,0,0,0,DK32,0,0,0,0,0,0,0,0,0,0,0,0,0,0,0,~
0,0,0,0,0,0,0,0,0,0,0,0,0)';
      BIDIRECTIONAL='TRUE';
      INPUT_LOAD='(-0.01,0.01)';
      OUTPUT_LOAD='(1.0,-1.0)';
      PINUSE='BI';
    'DDR6_SB_DQ3':
      PIN_NUMBER='(0,0,0,0,0,0,0,0,0,0,0,0,0,DP34,0,0,0,0,0,0,0,0,0,0,0,0,0,0,0,~
0,0,0,0,0,0,0,0,0,0,0,0,0)';
      BIDIRECTIONAL='TRUE';
      INPUT_LOAD='(-0.01,0.01)';
      OUTPUT_LOAD='(1.0,-1.0)';
      PINUSE='BI';
    'DDR6_SB_DQ2':
      PIN_NUMBER='(0,0,0,0,0,0,0,0,0,0,0,0,0,DN35,0,0,0,0,0,0,0,0,0,0,0,0,0,0,0,~
0,0,0,0,0,0,0,0,0,0,0,0,0)';
      BIDIRECTIONAL='TRUE';
      INPUT_LOAD='(-0.01,0.01)';
      OUTPUT_LOAD='(1.0,-1.0)';
      PINUSE='BI';
    'DDR6_SB_DQ1':
      PIN_NUMBER='(0,0,0,0,0,0,0,0,0,0,0,0,0,DK34,0,0,0,0,0,0,0,0,0,0,0,0,0,0,0,~
0,0,0,0,0,0,0,0,0,0,0,0,0)';
      BIDIRECTIONAL='TRUE';
      INPUT_LOAD='(-0.01,0.01)';
      OUTPUT_LOAD='(1.0,-1.0)';
      PINUSE='BI';
    'DDR6_SB_DQ0':
      PIN_NUMBER='(0,0,0,0,0,0,0,0,0,0,0,0,0,DL35,0,0,0,0,0,0,0,0,0,0,0,0,0,0,0,~
0,0,0,0,0,0,0,0,0,0,0,0,0)';
      BIDIRECTIONAL='TRUE';
      INPUT_LOAD='(-0.01,0.01)';
      OUTPUT_LOAD='(1.0,-1.0)';
      PINUSE='BI';
    'DDR6_SB_DQS_DN9':
      PIN_NUMBER='(0,0,0,0,0,0,0,0,0,0,0,0,0,DV36,0,0,0,0,0,0,0,0,0,0,0,0,0,0,0,~
0,0,0,0,0,0,0,0,0,0,0,0,0)';
      BIDIRECTIONAL='TRUE';
      INPUT_LOAD='(-0.01,0.01)';
      OUTPUT_LOAD='(1.0,-1.0)';
      PINUSE='BI';
    'DDR6_SB_DQS_DN8':
      PIN_NUMBER='(0,0,0,0,0,0,0,0,0,0,0,0,0,EM6,0,0,0,0,0,0,0,0,0,0,0,0,0,0,0,0~
,0,0,0,0,0,0,0,0,0,0,0,0)';
      BIDIRECTIONAL='TRUE';
      INPUT_LOAD='(-0.01,0.01)';
      OUTPUT_LOAD='(1.0,-1.0)';
      PINUSE='BI';
    'DDR6_SB_DQS_DN7':
      PIN_NUMBER='(0,0,0,0,0,0,0,0,0,0,0,0,0,EB24,0,0,0,0,0,0,0,0,0,0,0,0,0,0,0,~
0,0,0,0,0,0,0,0,0,0,0,0,0)';
      BIDIRECTIONAL='TRUE';
      INPUT_LOAD='(-0.01,0.01)';
      OUTPUT_LOAD='(1.0,-1.0)';
      PINUSE='BI';
    'DDR6_SB_DQS_DN6':
      PIN_NUMBER='(0,0,0,0,0,0,0,0,0,0,0,0,0,DN27,0,0,0,0,0,0,0,0,0,0,0,0,0,0,0,~
0,0,0,0,0,0,0,0,0,0,0,0,0)';
      BIDIRECTIONAL='TRUE';
      INPUT_LOAD='(-0.01,0.01)';
      OUTPUT_LOAD='(1.0,-1.0)';
      PINUSE='BI';
    'DDR6_SB_DQS_DN5':
      PIN_NUMBER='(0,0,0,0,0,0,0,0,0,0,0,0,0,DR33,0,0,0,0,0,0,0,0,0,0,0,0,0,0,0,~
0,0,0,0,0,0,0,0,0,0,0,0,0)';
      BIDIRECTIONAL='TRUE';
      INPUT_LOAD='(-0.01,0.01)';
      OUTPUT_LOAD='(1.0,-1.0)';
      PINUSE='BI';
    'DDR6_SB_DQS_DN4':
      PIN_NUMBER='(0,0,0,0,0,0,0,0,0,0,0,0,0,EB36,0,0,0,0,0,0,0,0,0,0,0,0,0,0,0,~
0,0,0,0,0,0,0,0,0,0,0,0,0)';
      BIDIRECTIONAL='TRUE';
      INPUT_LOAD='(-0.01,0.01)';
      OUTPUT_LOAD='(1.0,-1.0)';
      PINUSE='BI';
    'DDR6_SB_DQS_DN3':
      PIN_NUMBER='(0,0,0,0,0,0,0,0,0,0,0,0,0,EP6,0,0,0,0,0,0,0,0,0,0,0,0,0,0,0,0~
,0,0,0,0,0,0,0,0,0,0,0,0)';
      BIDIRECTIONAL='TRUE';
      INPUT_LOAD='(-0.01,0.01)';
      OUTPUT_LOAD='(1.0,-1.0)';
      PINUSE='BI';
    'DDR6_SB_DQS_DN2':
      PIN_NUMBER='(0,0,0,0,0,0,0,0,0,0,0,0,0,DV24,0,0,0,0,0,0,0,0,0,0,0,0,0,0,0,~
0,0,0,0,0,0,0,0,0,0,0,0,0)';
      BIDIRECTIONAL='TRUE';
      INPUT_LOAD='(-0.01,0.01)';
      OUTPUT_LOAD='(1.0,-1.0)';
      PINUSE='BI';
    'DDR6_SB_DQS_DN1':
      PIN_NUMBER='(0,0,0,0,0,0,0,0,0,0,0,0,0,DJ27,0,0,0,0,0,0,0,0,0,0,0,0,0,0,0,~
0,0,0,0,0,0,0,0,0,0,0,0,0)';
      BIDIRECTIONAL='TRUE';
      INPUT_LOAD='(-0.01,0.01)';
      OUTPUT_LOAD='(1.0,-1.0)';
      PINUSE='BI';
    'DDR6_SB_DQS_DN0':
      PIN_NUMBER='(0,0,0,0,0,0,0,0,0,0,0,0,0,DJ33,0,0,0,0,0,0,0,0,0,0,0,0,0,0,0,~
0,0,0,0,0,0,0,0,0,0,0,0,0)';
      BIDIRECTIONAL='TRUE';
      INPUT_LOAD='(-0.01,0.01)';
      OUTPUT_LOAD='(1.0,-1.0)';
      PINUSE='BI';
    'DDR6_SB_DQS_DP9':
      PIN_NUMBER='(0,0,0,0,0,0,0,0,0,0,0,0,0,DT36,0,0,0,0,0,0,0,0,0,0,0,0,0,0,0,~
0,0,0,0,0,0,0,0,0,0,0,0,0)';
      BIDIRECTIONAL='TRUE';
      INPUT_LOAD='(-0.01,0.01)';
      OUTPUT_LOAD='(1.0,-1.0)';
      PINUSE='BI';
    'DDR6_SB_DQS_DP8':
      PIN_NUMBER='(0,0,0,0,0,0,0,0,0,0,0,0,0,EN5,0,0,0,0,0,0,0,0,0,0,0,0,0,0,0,0~
,0,0,0,0,0,0,0,0,0,0,0,0)';
      BIDIRECTIONAL='TRUE';
      INPUT_LOAD='(-0.01,0.01)';
      OUTPUT_LOAD='(1.0,-1.0)';
      PINUSE='BI';
    'DDR6_SB_DQS_DP7':
      PIN_NUMBER='(0,0,0,0,0,0,0,0,0,0,0,0,0,DY24,0,0,0,0,0,0,0,0,0,0,0,0,0,0,0,~
0,0,0,0,0,0,0,0,0,0,0,0,0)';
      BIDIRECTIONAL='TRUE';
      INPUT_LOAD='(-0.01,0.01)';
      OUTPUT_LOAD='(1.0,-1.0)';
      PINUSE='BI';
    'DDR6_SB_DQS_DP6':
      PIN_NUMBER='(0,0,0,0,0,0,0,0,0,0,0,0,0,DR27,0,0,0,0,0,0,0,0,0,0,0,0,0,0,0,~
0,0,0,0,0,0,0,0,0,0,0,0,0)';
      BIDIRECTIONAL='TRUE';
      INPUT_LOAD='(-0.01,0.01)';
      OUTPUT_LOAD='(1.0,-1.0)';
      PINUSE='BI';
    'DDR6_SB_DQS_DP5':
      PIN_NUMBER='(0,0,0,0,0,0,0,0,0,0,0,0,0,DN33,0,0,0,0,0,0,0,0,0,0,0,0,0,0,0,~
0,0,0,0,0,0,0,0,0,0,0,0,0)';
      BIDIRECTIONAL='TRUE';
      INPUT_LOAD='(-0.01,0.01)';
      OUTPUT_LOAD='(1.0,-1.0)';
      PINUSE='BI';
    'DDR6_SB_DQS_DP4':
      PIN_NUMBER='(0,0,0,0,0,0,0,0,0,0,0,0,0,DY36,0,0,0,0,0,0,0,0,0,0,0,0,0,0,0,~
0,0,0,0,0,0,0,0,0,0,0,0,0)';
      BIDIRECTIONAL='TRUE';
      INPUT_LOAD='(-0.01,0.01)';
      OUTPUT_LOAD='(1.0,-1.0)';
      PINUSE='BI';
    'DDR6_SB_DQS_DP3':
      PIN_NUMBER='(0,0,0,0,0,0,0,0,0,0,0,0,0,EN7,0,0,0,0,0,0,0,0,0,0,0,0,0,0,0,0~
,0,0,0,0,0,0,0,0,0,0,0,0)';
      BIDIRECTIONAL='TRUE';
      INPUT_LOAD='(-0.01,0.01)';
      OUTPUT_LOAD='(1.0,-1.0)';
      PINUSE='BI';
    'DDR6_SB_DQS_DP2':
      PIN_NUMBER='(0,0,0,0,0,0,0,0,0,0,0,0,0,DT24,0,0,0,0,0,0,0,0,0,0,0,0,0,0,0,~
0,0,0,0,0,0,0,0,0,0,0,0,0)';
      BIDIRECTIONAL='TRUE';
      INPUT_LOAD='(-0.01,0.01)';
      OUTPUT_LOAD='(1.0,-1.0)';
      PINUSE='BI';
    'DDR6_SB_DQS_DP1':
      PIN_NUMBER='(0,0,0,0,0,0,0,0,0,0,0,0,0,DL27,0,0,0,0,0,0,0,0,0,0,0,0,0,0,0,~
0,0,0,0,0,0,0,0,0,0,0,0,0)';
      BIDIRECTIONAL='TRUE';
      INPUT_LOAD='(-0.01,0.01)';
      OUTPUT_LOAD='(1.0,-1.0)';
      PINUSE='BI';
    'DDR6_SB_DQS_DP0':
      PIN_NUMBER='(0,0,0,0,0,0,0,0,0,0,0,0,0,DL33,0,0,0,0,0,0,0,0,0,0,0,0,0,0,0,~
0,0,0,0,0,0,0,0,0,0,0,0,0)';
      BIDIRECTIONAL='TRUE';
      INPUT_LOAD='(-0.01,0.01)';
      OUTPUT_LOAD='(1.0,-1.0)';
      PINUSE='BI';
    'DDR6_SB_ECC7':
      PIN_NUMBER='(0,0,0,0,0,0,0,0,0,0,0,0,0,EA37,0,0,0,0,0,0,0,0,0,0,0,0,0,0,0,~
0,0,0,0,0,0,0,0,0,0,0,0,0)';
      BIDIRECTIONAL='TRUE';
      INPUT_LOAD='(-0.01,0.01)';
      OUTPUT_LOAD='(1.0,-1.0)';
      PINUSE='BI';
    'DDR6_SB_ECC6':
      PIN_NUMBER='(0,0,0,0,0,0,0,0,0,0,0,0,0,DY38,0,0,0,0,0,0,0,0,0,0,0,0,0,0,0,~
0,0,0,0,0,0,0,0,0,0,0,0,0)';
      BIDIRECTIONAL='TRUE';
      INPUT_LOAD='(-0.01,0.01)';
      OUTPUT_LOAD='(1.0,-1.0)';
      PINUSE='BI';
    'DDR6_SB_ECC5':
      PIN_NUMBER='(0,0,0,0,0,0,0,0,0,0,0,0,0,DU37,0,0,0,0,0,0,0,0,0,0,0,0,0,0,0,~
0,0,0,0,0,0,0,0,0,0,0,0,0)';
      BIDIRECTIONAL='TRUE';
      INPUT_LOAD='(-0.01,0.01)';
      OUTPUT_LOAD='(1.0,-1.0)';
      PINUSE='BI';
    'DDR6_SB_ECC4':
      PIN_NUMBER='(0,0,0,0,0,0,0,0,0,0,0,0,0,DV38,0,0,0,0,0,0,0,0,0,0,0,0,0,0,0,~
0,0,0,0,0,0,0,0,0,0,0,0,0)';
      BIDIRECTIONAL='TRUE';
      INPUT_LOAD='(-0.01,0.01)';
      OUTPUT_LOAD='(1.0,-1.0)';
      PINUSE='BI';
    'DDR6_SB_ECC3':
      PIN_NUMBER='(0,0,0,0,0,0,0,0,0,0,0,0,0,DY34,0,0,0,0,0,0,0,0,0,0,0,0,0,0,0,~
0,0,0,0,0,0,0,0,0,0,0,0,0)';
      BIDIRECTIONAL='TRUE';
      INPUT_LOAD='(-0.01,0.01)';
      OUTPUT_LOAD='(1.0,-1.0)';
      PINUSE='BI';
    'DDR6_SB_ECC2':
      PIN_NUMBER='(0,0,0,0,0,0,0,0,0,0,0,0,0,EA35,0,0,0,0,0,0,0,0,0,0,0,0,0,0,0,~
0,0,0,0,0,0,0,0,0,0,0,0,0)';
      BIDIRECTIONAL='TRUE';
      INPUT_LOAD='(-0.01,0.01)';
      OUTPUT_LOAD='(1.0,-1.0)';
      PINUSE='BI';
    'DDR6_SB_ECC1':
      PIN_NUMBER='(0,0,0,0,0,0,0,0,0,0,0,0,0,DV34,0,0,0,0,0,0,0,0,0,0,0,0,0,0,0,~
0,0,0,0,0,0,0,0,0,0,0,0,0)';
      BIDIRECTIONAL='TRUE';
      INPUT_LOAD='(-0.01,0.01)';
      OUTPUT_LOAD='(1.0,-1.0)';
      PINUSE='BI';
    'DDR6_SB_ECC0':
      PIN_NUMBER='(0,0,0,0,0,0,0,0,0,0,0,0,0,DU35,0,0,0,0,0,0,0,0,0,0,0,0,0,0,0,~
0,0,0,0,0,0,0,0,0,0,0,0,0)';
      BIDIRECTIONAL='TRUE';
      INPUT_LOAD='(-0.01,0.01)';
      OUTPUT_LOAD='(1.0,-1.0)';
      PINUSE='BI';
    'DDR6_SB_PAR':
      PIN_NUMBER='(0,0,0,0,0,0,0,0,0,0,0,0,0,EB42,0,0,0,0,0,0,0,0,0,0,0,0,0,0,0,~
0,0,0,0,0,0,0,0,0,0,0,0,0)';
      OUTPUT_LOAD='(1.0,-1.0)';
      PINUSE='OUT';
    'DDR7_ALERT_N':
      PIN_NUMBER='(0,0,0,0,0,0,0,0,0,0,0,0,0,0,CY51,0,0,0,0,0,0,0,0,0,0,0,0,0,0,~
0,0,0,0,0,0,0,0,0,0,0,0,0)';
      INPUT_LOAD='(-0.01,0.01)';
      PINUSE='IN';
    'DDR7_A_RSP1':
      PIN_NUMBER='(0,0,0,0,0,0,0,0,0,0,0,0,0,0,EH47,0,0,0,0,0,0,0,0,0,0,0,0,0,0,~
0,0,0,0,0,0,0,0,0,0,0,0,0)';
      INPUT_LOAD='(-0.01,0.01)';
      PINUSE='IN';
    'DDR7_A_RSP0':
      PIN_NUMBER='(0,0,0,0,0,0,0,0,0,0,0,0,0,0,EG48,0,0,0,0,0,0,0,0,0,0,0,0,0,0,~
0,0,0,0,0,0,0,0,0,0,0,0,0)';
      INPUT_LOAD='(-0.01,0.01)';
      PINUSE='IN';
    'DDR7_B_RSP1':
      PIN_NUMBER='(0,0,0,0,0,0,0,0,0,0,0,0,0,0,ED47,0,0,0,0,0,0,0,0,0,0,0,0,0,0,~
0,0,0,0,0,0,0,0,0,0,0,0,0)';
      INPUT_LOAD='(-0.01,0.01)';
      PINUSE='IN';
    'DDR7_B_RSP0':
      PIN_NUMBER='(0,0,0,0,0,0,0,0,0,0,0,0,0,0,EE48,0,0,0,0,0,0,0,0,0,0,0,0,0,0,~
0,0,0,0,0,0,0,0,0,0,0,0,0)';
      INPUT_LOAD='(-0.01,0.01)';
      PINUSE='IN';
    'DDR7_CLK_DN1':
      PIN_NUMBER='(0,0,0,0,0,0,0,0,0,0,0,0,0,0,DD42,0,0,0,0,0,0,0,0,0,0,0,0,0,0,~
0,0,0,0,0,0,0,0,0,0,0,0,0)';
      OUTPUT_LOAD='(1.0,-1.0)';
      PINUSE='OUT';
    'DDR7_CLK_DN0':
      PIN_NUMBER='(0,0,0,0,0,0,0,0,0,0,0,0,0,0,DH42,0,0,0,0,0,0,0,0,0,0,0,0,0,0,~
0,0,0,0,0,0,0,0,0,0,0,0,0)';
      OUTPUT_LOAD='(1.0,-1.0)';
      PINUSE='OUT';
    'DDR7_CLK_DP1':
      PIN_NUMBER='(0,0,0,0,0,0,0,0,0,0,0,0,0,0,DB42,0,0,0,0,0,0,0,0,0,0,0,0,0,0,~
0,0,0,0,0,0,0,0,0,0,0,0,0)';
      OUTPUT_LOAD='(1.0,-1.0)';
      PINUSE='OUT';
    'DDR7_CLK_DP0':
      PIN_NUMBER='(0,0,0,0,0,0,0,0,0,0,0,0,0,0,DF42,0,0,0,0,0,0,0,0,0,0,0,0,0,0,~
0,0,0,0,0,0,0,0,0,0,0,0,0)';
      OUTPUT_LOAD='(1.0,-1.0)';
      PINUSE='OUT';
    'DDR7_SA_CA6':
      PIN_NUMBER='(0,0,0,0,0,0,0,0,0,0,0,0,0,0,DC41,0,0,0,0,0,0,0,0,0,0,0,0,0,0,~
0,0,0,0,0,0,0,0,0,0,0,0,0)';
      OUTPUT_LOAD='(1.0,-1.0)';
      PINUSE='OUT';
    'DDR7_SA_CA5':
      PIN_NUMBER='(0,0,0,0,0,0,0,0,0,0,0,0,0,0,DF47,0,0,0,0,0,0,0,0,0,0,0,0,0,0,~
0,0,0,0,0,0,0,0,0,0,0,0,0)';
      OUTPUT_LOAD='(1.0,-1.0)';
      PINUSE='OUT';
    'DDR7_SA_CA4':
      PIN_NUMBER='(0,0,0,0,0,0,0,0,0,0,0,0,0,0,DD47,0,0,0,0,0,0,0,0,0,0,0,0,0,0,~
0,0,0,0,0,0,0,0,0,0,0,0,0)';
      OUTPUT_LOAD='(1.0,-1.0)';
      PINUSE='OUT';
    'DDR7_SA_CA3':
      PIN_NUMBER='(0,0,0,0,0,0,0,0,0,0,0,0,0,0,DG48,0,0,0,0,0,0,0,0,0,0,0,0,0,0,~
0,0,0,0,0,0,0,0,0,0,0,0,0)';
      OUTPUT_LOAD='(1.0,-1.0)';
      PINUSE='OUT';
    'DDR7_SA_CA2':
      PIN_NUMBER='(0,0,0,0,0,0,0,0,0,0,0,0,0,0,DC48,0,0,0,0,0,0,0,0,0,0,0,0,0,0,~
0,0,0,0,0,0,0,0,0,0,0,0,0)';
      OUTPUT_LOAD='(1.0,-1.0)';
      PINUSE='OUT';
    'DDR7_SA_CA1':
      PIN_NUMBER='(0,0,0,0,0,0,0,0,0,0,0,0,0,0,DH49,0,0,0,0,0,0,0,0,0,0,0,0,0,0,~
0,0,0,0,0,0,0,0,0,0,0,0,0)';
      OUTPUT_LOAD='(1.0,-1.0)';
      PINUSE='OUT';
    'DDR7_SA_CA0':
      PIN_NUMBER='(0,0,0,0,0,0,0,0,0,0,0,0,0,0,DB49,0,0,0,0,0,0,0,0,0,0,0,0,0,0,~
0,0,0,0,0,0,0,0,0,0,0,0,0)';
      OUTPUT_LOAD='(1.0,-1.0)';
      PINUSE='OUT';
    'DDR7_SA_CS_N3':
      PIN_NUMBER='(0,0,0,0,0,0,0,0,0,0,0,0,0,0,DC50,0,0,0,0,0,0,0,0,0,0,0,0,0,0,~
0,0,0,0,0,0,0,0,0,0,0,0,0)';
      OUTPUT_LOAD='(1.0,-1.0)';
      PINUSE='OUT';
    'DDR7_SA_CS_N2':
      PIN_NUMBER='(0,0,0,0,0,0,0,0,0,0,0,0,0,0,DD51,0,0,0,0,0,0,0,0,0,0,0,0,0,0,~
0,0,0,0,0,0,0,0,0,0,0,0,0)';
      OUTPUT_LOAD='(1.0,-1.0)';
      PINUSE='OUT';
    'DDR7_SA_CS_N1':
      PIN_NUMBER='(0,0,0,0,0,0,0,0,0,0,0,0,0,0,DG50,0,0,0,0,0,0,0,0,0,0,0,0,0,0,~
0,0,0,0,0,0,0,0,0,0,0,0,0)';
      OUTPUT_LOAD='(1.0,-1.0)';
      PINUSE='OUT';
    'DDR7_SA_CS_N0':
      PIN_NUMBER='(0,0,0,0,0,0,0,0,0,0,0,0,0,0,DF51,0,0,0,0,0,0,0,0,0,0,0,0,0,0,~
0,0,0,0,0,0,0,0,0,0,0,0,0)';
      OUTPUT_LOAD='(1.0,-1.0)';
      PINUSE='OUT';
    'DDR7_SA_DQ31':
      PIN_NUMBER='(0,0,0,0,0,0,0,0,0,0,0,0,0,0,DF59,0,0,0,0,0,0,0,0,0,0,0,0,0,0,~
0,0,0,0,0,0,0,0,0,0,0,0,0)';
      BIDIRECTIONAL='TRUE';
      INPUT_LOAD='(-0.01,0.01)';
      OUTPUT_LOAD='(1.0,-1.0)';
      PINUSE='BI';
    'DDR7_SA_DQ30':
      PIN_NUMBER='(0,0,0,0,0,0,0,0,0,0,0,0,0,0,DG60,0,0,0,0,0,0,0,0,0,0,0,0,0,0,~
0,0,0,0,0,0,0,0,0,0,0,0,0)';
      BIDIRECTIONAL='TRUE';
      INPUT_LOAD='(-0.01,0.01)';
      OUTPUT_LOAD='(1.0,-1.0)';
      PINUSE='BI';
    'DDR7_SA_DQ29':
      PIN_NUMBER='(0,0,0,0,0,0,0,0,0,0,0,0,0,0,DD59,0,0,0,0,0,0,0,0,0,0,0,0,0,0,~
0,0,0,0,0,0,0,0,0,0,0,0,0)';
      BIDIRECTIONAL='TRUE';
      INPUT_LOAD='(-0.01,0.01)';
      OUTPUT_LOAD='(1.0,-1.0)';
      PINUSE='BI';
    'DDR7_SA_DQ28':
      PIN_NUMBER='(0,0,0,0,0,0,0,0,0,0,0,0,0,0,DC60,0,0,0,0,0,0,0,0,0,0,0,0,0,0,~
0,0,0,0,0,0,0,0,0,0,0,0,0)';
      BIDIRECTIONAL='TRUE';
      INPUT_LOAD='(-0.01,0.01)';
      OUTPUT_LOAD='(1.0,-1.0)';
      PINUSE='BI';
    'DDR7_SA_DQ27':
      PIN_NUMBER='(0,0,0,0,0,0,0,0,0,0,0,0,0,0,DG62,0,0,0,0,0,0,0,0,0,0,0,0,0,0,~
0,0,0,0,0,0,0,0,0,0,0,0,0)';
      BIDIRECTIONAL='TRUE';
      INPUT_LOAD='(-0.01,0.01)';
      OUTPUT_LOAD='(1.0,-1.0)';
      PINUSE='BI';
    'DDR7_SA_DQ26':
      PIN_NUMBER='(0,0,0,0,0,0,0,0,0,0,0,0,0,0,DF63,0,0,0,0,0,0,0,0,0,0,0,0,0,0,~
0,0,0,0,0,0,0,0,0,0,0,0,0)';
      BIDIRECTIONAL='TRUE';
      INPUT_LOAD='(-0.01,0.01)';
      OUTPUT_LOAD='(1.0,-1.0)';
      PINUSE='BI';
    'DDR7_SA_DQ25':
      PIN_NUMBER='(0,0,0,0,0,0,0,0,0,0,0,0,0,0,DC62,0,0,0,0,0,0,0,0,0,0,0,0,0,0,~
0,0,0,0,0,0,0,0,0,0,0,0,0)';
      BIDIRECTIONAL='TRUE';
      INPUT_LOAD='(-0.01,0.01)';
      OUTPUT_LOAD='(1.0,-1.0)';
      PINUSE='BI';
    'DDR7_SA_DQ24':
      PIN_NUMBER='(0,0,0,0,0,0,0,0,0,0,0,0,0,0,DD63,0,0,0,0,0,0,0,0,0,0,0,0,0,0,~
0,0,0,0,0,0,0,0,0,0,0,0,0)';
      BIDIRECTIONAL='TRUE';
      INPUT_LOAD='(-0.01,0.01)';
      OUTPUT_LOAD='(1.0,-1.0)';
      PINUSE='BI';
    'DDR7_SA_DQ23':
      PIN_NUMBER='(0,0,0,0,0,0,0,0,0,0,0,0,0,0,DF65,0,0,0,0,0,0,0,0,0,0,0,0,0,0,~
0,0,0,0,0,0,0,0,0,0,0,0,0)';
      BIDIRECTIONAL='TRUE';
      INPUT_LOAD='(-0.01,0.01)';
      OUTPUT_LOAD='(1.0,-1.0)';
      PINUSE='BI';
    'DDR7_SA_DQ22':
      PIN_NUMBER='(0,0,0,0,0,0,0,0,0,0,0,0,0,0,DG66,0,0,0,0,0,0,0,0,0,0,0,0,0,0,~
0,0,0,0,0,0,0,0,0,0,0,0,0)';
      BIDIRECTIONAL='TRUE';
      INPUT_LOAD='(-0.01,0.01)';
      OUTPUT_LOAD='(1.0,-1.0)';
      PINUSE='BI';
    'DDR7_SA_DQ21':
      PIN_NUMBER='(0,0,0,0,0,0,0,0,0,0,0,0,0,0,DD65,0,0,0,0,0,0,0,0,0,0,0,0,0,0,~
0,0,0,0,0,0,0,0,0,0,0,0,0)';
      BIDIRECTIONAL='TRUE';
      INPUT_LOAD='(-0.01,0.01)';
      OUTPUT_LOAD='(1.0,-1.0)';
      PINUSE='BI';
    'DDR7_SA_DQ20':
      PIN_NUMBER='(0,0,0,0,0,0,0,0,0,0,0,0,0,0,DC66,0,0,0,0,0,0,0,0,0,0,0,0,0,0,~
0,0,0,0,0,0,0,0,0,0,0,0,0)';
      BIDIRECTIONAL='TRUE';
      INPUT_LOAD='(-0.01,0.01)';
      OUTPUT_LOAD='(1.0,-1.0)';
      PINUSE='BI';
    'DDR7_SA_DQ19':
      PIN_NUMBER='(0,0,0,0,0,0,0,0,0,0,0,0,0,0,DG68,0,0,0,0,0,0,0,0,0,0,0,0,0,0,~
0,0,0,0,0,0,0,0,0,0,0,0,0)';
      BIDIRECTIONAL='TRUE';
      INPUT_LOAD='(-0.01,0.01)';
      OUTPUT_LOAD='(1.0,-1.0)';
      PINUSE='BI';
    'DDR7_SA_DQ18':
      PIN_NUMBER='(0,0,0,0,0,0,0,0,0,0,0,0,0,0,DF69,0,0,0,0,0,0,0,0,0,0,0,0,0,0,~
0,0,0,0,0,0,0,0,0,0,0,0,0)';
      BIDIRECTIONAL='TRUE';
      INPUT_LOAD='(-0.01,0.01)';
      OUTPUT_LOAD='(1.0,-1.0)';
      PINUSE='BI';
    'DDR7_SA_DQ17':
      PIN_NUMBER='(0,0,0,0,0,0,0,0,0,0,0,0,0,0,DC68,0,0,0,0,0,0,0,0,0,0,0,0,0,0,~
0,0,0,0,0,0,0,0,0,0,0,0,0)';
      BIDIRECTIONAL='TRUE';
      INPUT_LOAD='(-0.01,0.01)';
      OUTPUT_LOAD='(1.0,-1.0)';
      PINUSE='BI';
    'DDR7_SA_DQ16':
      PIN_NUMBER='(0,0,0,0,0,0,0,0,0,0,0,0,0,0,DD69,0,0,0,0,0,0,0,0,0,0,0,0,0,0,~
0,0,0,0,0,0,0,0,0,0,0,0,0)';
      BIDIRECTIONAL='TRUE';
      INPUT_LOAD='(-0.01,0.01)';
      OUTPUT_LOAD='(1.0,-1.0)';
      PINUSE='BI';
    'DDR7_SA_DQ15':
      PIN_NUMBER='(0,0,0,0,0,0,0,0,0,0,0,0,0,0,DF71,0,0,0,0,0,0,0,0,0,0,0,0,0,0,~
0,0,0,0,0,0,0,0,0,0,0,0,0)';
      BIDIRECTIONAL='TRUE';
      INPUT_LOAD='(-0.01,0.01)';
      OUTPUT_LOAD='(1.0,-1.0)';
      PINUSE='BI';
    'DDR7_SA_DQ14':
      PIN_NUMBER='(0,0,0,0,0,0,0,0,0,0,0,0,0,0,DG72,0,0,0,0,0,0,0,0,0,0,0,0,0,0,~
0,0,0,0,0,0,0,0,0,0,0,0,0)';
      BIDIRECTIONAL='TRUE';
      INPUT_LOAD='(-0.01,0.01)';
      OUTPUT_LOAD='(1.0,-1.0)';
      PINUSE='BI';
    'DDR7_SA_DQ13':
      PIN_NUMBER='(0,0,0,0,0,0,0,0,0,0,0,0,0,0,DD71,0,0,0,0,0,0,0,0,0,0,0,0,0,0,~
0,0,0,0,0,0,0,0,0,0,0,0,0)';
      BIDIRECTIONAL='TRUE';
      INPUT_LOAD='(-0.01,0.01)';
      OUTPUT_LOAD='(1.0,-1.0)';
      PINUSE='BI';
    'DDR7_SA_DQ12':
      PIN_NUMBER='(0,0,0,0,0,0,0,0,0,0,0,0,0,0,DC72,0,0,0,0,0,0,0,0,0,0,0,0,0,0,~
0,0,0,0,0,0,0,0,0,0,0,0,0)';
      BIDIRECTIONAL='TRUE';
      INPUT_LOAD='(-0.01,0.01)';
      OUTPUT_LOAD='(1.0,-1.0)';
      PINUSE='BI';
    'DDR7_SA_DQ11':
      PIN_NUMBER='(0,0,0,0,0,0,0,0,0,0,0,0,0,0,DG74,0,0,0,0,0,0,0,0,0,0,0,0,0,0,~
0,0,0,0,0,0,0,0,0,0,0,0,0)';
      BIDIRECTIONAL='TRUE';
      INPUT_LOAD='(-0.01,0.01)';
      OUTPUT_LOAD='(1.0,-1.0)';
      PINUSE='BI';
    'DDR7_SA_DQ10':
      PIN_NUMBER='(0,0,0,0,0,0,0,0,0,0,0,0,0,0,DF75,0,0,0,0,0,0,0,0,0,0,0,0,0,0,~
0,0,0,0,0,0,0,0,0,0,0,0,0)';
      BIDIRECTIONAL='TRUE';
      INPUT_LOAD='(-0.01,0.01)';
      OUTPUT_LOAD='(1.0,-1.0)';
      PINUSE='BI';
    'DDR7_SA_DQ9':
      PIN_NUMBER='(0,0,0,0,0,0,0,0,0,0,0,0,0,0,DC74,0,0,0,0,0,0,0,0,0,0,0,0,0,0,~
0,0,0,0,0,0,0,0,0,0,0,0,0)';
      BIDIRECTIONAL='TRUE';
      INPUT_LOAD='(-0.01,0.01)';
      OUTPUT_LOAD='(1.0,-1.0)';
      PINUSE='BI';
    'DDR7_SA_DQ8':
      PIN_NUMBER='(0,0,0,0,0,0,0,0,0,0,0,0,0,0,DD75,0,0,0,0,0,0,0,0,0,0,0,0,0,0,~
0,0,0,0,0,0,0,0,0,0,0,0,0)';
      BIDIRECTIONAL='TRUE';
      INPUT_LOAD='(-0.01,0.01)';
      OUTPUT_LOAD='(1.0,-1.0)';
      PINUSE='BI';
    'DDR7_SA_DQ7':
      PIN_NUMBER='(0,0,0,0,0,0,0,0,0,0,0,0,0,0,DN74,0,0,0,0,0,0,0,0,0,0,0,0,0,0,~
0,0,0,0,0,0,0,0,0,0,0,0,0)';
      BIDIRECTIONAL='TRUE';
      INPUT_LOAD='(-0.01,0.01)';
      OUTPUT_LOAD='(1.0,-1.0)';
      PINUSE='BI';
    'DDR7_SA_DQ6':
      PIN_NUMBER='(0,0,0,0,0,0,0,0,0,0,0,0,0,0,DP75,0,0,0,0,0,0,0,0,0,0,0,0,0,0,~
0,0,0,0,0,0,0,0,0,0,0,0,0)';
      BIDIRECTIONAL='TRUE';
      INPUT_LOAD='(-0.01,0.01)';
      OUTPUT_LOAD='(1.0,-1.0)';
      PINUSE='BI';
    'DDR7_SA_DQ5':
      PIN_NUMBER='(0,0,0,0,0,0,0,0,0,0,0,0,0,0,DL74,0,0,0,0,0,0,0,0,0,0,0,0,0,0,~
0,0,0,0,0,0,0,0,0,0,0,0,0)';
      BIDIRECTIONAL='TRUE';
      INPUT_LOAD='(-0.01,0.01)';
      OUTPUT_LOAD='(1.0,-1.0)';
      PINUSE='BI';
    'DDR7_SA_DQ4':
      PIN_NUMBER='(0,0,0,0,0,0,0,0,0,0,0,0,0,0,DK75,0,0,0,0,0,0,0,0,0,0,0,0,0,0,~
0,0,0,0,0,0,0,0,0,0,0,0,0)';
      BIDIRECTIONAL='TRUE';
      INPUT_LOAD='(-0.01,0.01)';
      OUTPUT_LOAD='(1.0,-1.0)';
      PINUSE='BI';
    'DDR7_SA_DQ3':
      PIN_NUMBER='(0,0,0,0,0,0,0,0,0,0,0,0,0,0,DP77,0,0,0,0,0,0,0,0,0,0,0,0,0,0,~
0,0,0,0,0,0,0,0,0,0,0,0,0)';
      BIDIRECTIONAL='TRUE';
      INPUT_LOAD='(-0.01,0.01)';
      OUTPUT_LOAD='(1.0,-1.0)';
      PINUSE='BI';
    'DDR7_SA_DQ2':
      PIN_NUMBER='(0,0,0,0,0,0,0,0,0,0,0,0,0,0,DW78,0,0,0,0,0,0,0,0,0,0,0,0,0,0,~
0,0,0,0,0,0,0,0,0,0,0,0,0)';
      BIDIRECTIONAL='TRUE';
      INPUT_LOAD='(-0.01,0.01)';
      OUTPUT_LOAD='(1.0,-1.0)';
      PINUSE='BI';
    'DDR7_SA_DQ1':
      PIN_NUMBER='(0,0,0,0,0,0,0,0,0,0,0,0,0,0,DT77,0,0,0,0,0,0,0,0,0,0,0,0,0,0,~
0,0,0,0,0,0,0,0,0,0,0,0,0)';
      BIDIRECTIONAL='TRUE';
      INPUT_LOAD='(-0.01,0.01)';
      OUTPUT_LOAD='(1.0,-1.0)';
      PINUSE='BI';
    'DDR7_SA_DQ0':
      PIN_NUMBER='(0,0,0,0,0,0,0,0,0,0,0,0,0,0,DY79,0,0,0,0,0,0,0,0,0,0,0,0,0,0,~
0,0,0,0,0,0,0,0,0,0,0,0,0)';
      BIDIRECTIONAL='TRUE';
      INPUT_LOAD='(-0.01,0.01)';
      OUTPUT_LOAD='(1.0,-1.0)';
      PINUSE='BI';
    'DDR7_SA_DQS_DN9':
      PIN_NUMBER='(0,0,0,0,0,0,0,0,0,0,0,0,0,0,DH55,0,0,0,0,0,0,0,0,0,0,0,0,0,0,~
0,0,0,0,0,0,0,0,0,0,0,0,0)';
      BIDIRECTIONAL='TRUE';
      INPUT_LOAD='(-0.01,0.01)';
      OUTPUT_LOAD='(1.0,-1.0)';
      PINUSE='BI';
    'DDR7_SA_DQS_DN8':
      PIN_NUMBER='(0,0,0,0,0,0,0,0,0,0,0,0,0,0,DH61,0,0,0,0,0,0,0,0,0,0,0,0,0,0,~
0,0,0,0,0,0,0,0,0,0,0,0,0)';
      BIDIRECTIONAL='TRUE';
      INPUT_LOAD='(-0.01,0.01)';
      OUTPUT_LOAD='(1.0,-1.0)';
      PINUSE='BI';
    'DDR7_SA_DQS_DN7':
      PIN_NUMBER='(0,0,0,0,0,0,0,0,0,0,0,0,0,0,DH67,0,0,0,0,0,0,0,0,0,0,0,0,0,0,~
0,0,0,0,0,0,0,0,0,0,0,0,0)';
      BIDIRECTIONAL='TRUE';
      INPUT_LOAD='(-0.01,0.01)';
      OUTPUT_LOAD='(1.0,-1.0)';
      PINUSE='BI';
    'DDR7_SA_DQS_DN6':
      PIN_NUMBER='(0,0,0,0,0,0,0,0,0,0,0,0,0,0,DH73,0,0,0,0,0,0,0,0,0,0,0,0,0,0,~
0,0,0,0,0,0,0,0,0,0,0,0,0)';
      BIDIRECTIONAL='TRUE';
      INPUT_LOAD='(-0.01,0.01)';
      OUTPUT_LOAD='(1.0,-1.0)';
      PINUSE='BI';
    'DDR7_SA_DQS_DN5':
      PIN_NUMBER='(0,0,0,0,0,0,0,0,0,0,0,0,0,0,DR76,0,0,0,0,0,0,0,0,0,0,0,0,0,0,~
0,0,0,0,0,0,0,0,0,0,0,0,0)';
      BIDIRECTIONAL='TRUE';
      INPUT_LOAD='(-0.01,0.01)';
      OUTPUT_LOAD='(1.0,-1.0)';
      PINUSE='BI';
    'DDR7_SA_DQS_DN4':
      PIN_NUMBER='(0,0,0,0,0,0,0,0,0,0,0,0,0,0,DD55,0,0,0,0,0,0,0,0,0,0,0,0,0,0,~
0,0,0,0,0,0,0,0,0,0,0,0,0)';
      BIDIRECTIONAL='TRUE';
      INPUT_LOAD='(-0.01,0.01)';
      OUTPUT_LOAD='(1.0,-1.0)';
      PINUSE='BI';
    'DDR7_SA_DQS_DN3':
      PIN_NUMBER='(0,0,0,0,0,0,0,0,0,0,0,0,0,0,DD61,0,0,0,0,0,0,0,0,0,0,0,0,0,0,~
0,0,0,0,0,0,0,0,0,0,0,0,0)';
      BIDIRECTIONAL='TRUE';
      INPUT_LOAD='(-0.01,0.01)';
      OUTPUT_LOAD='(1.0,-1.0)';
      PINUSE='BI';
    'DDR7_SA_DQS_DN2':
      PIN_NUMBER='(0,0,0,0,0,0,0,0,0,0,0,0,0,0,DD67,0,0,0,0,0,0,0,0,0,0,0,0,0,0,~
0,0,0,0,0,0,0,0,0,0,0,0,0)';
      BIDIRECTIONAL='TRUE';
      INPUT_LOAD='(-0.01,0.01)';
      OUTPUT_LOAD='(1.0,-1.0)';
      PINUSE='BI';
    'DDR7_SA_DQS_DN1':
      PIN_NUMBER='(0,0,0,0,0,0,0,0,0,0,0,0,0,0,DB73,0,0,0,0,0,0,0,0,0,0,0,0,0,0,~
0,0,0,0,0,0,0,0,0,0,0,0,0)';
      BIDIRECTIONAL='TRUE';
      INPUT_LOAD='(-0.01,0.01)';
      OUTPUT_LOAD='(1.0,-1.0)';
      PINUSE='BI';
    'DDR7_SA_DQS_DN0':
      PIN_NUMBER='(0,0,0,0,0,0,0,0,0,0,0,0,0,0,DJ76,0,0,0,0,0,0,0,0,0,0,0,0,0,0,~
0,0,0,0,0,0,0,0,0,0,0,0,0)';
      BIDIRECTIONAL='TRUE';
      INPUT_LOAD='(-0.01,0.01)';
      OUTPUT_LOAD='(1.0,-1.0)';
      PINUSE='BI';
    'DDR7_SA_DQS_DP9':
      PIN_NUMBER='(0,0,0,0,0,0,0,0,0,0,0,0,0,0,DF55,0,0,0,0,0,0,0,0,0,0,0,0,0,0,~
0,0,0,0,0,0,0,0,0,0,0,0,0)';
      BIDIRECTIONAL='TRUE';
      INPUT_LOAD='(-0.01,0.01)';
      OUTPUT_LOAD='(1.0,-1.0)';
      PINUSE='BI';
    'DDR7_SA_DQS_DP8':
      PIN_NUMBER='(0,0,0,0,0,0,0,0,0,0,0,0,0,0,DF61,0,0,0,0,0,0,0,0,0,0,0,0,0,0,~
0,0,0,0,0,0,0,0,0,0,0,0,0)';
      BIDIRECTIONAL='TRUE';
      INPUT_LOAD='(-0.01,0.01)';
      OUTPUT_LOAD='(1.0,-1.0)';
      PINUSE='BI';
    'DDR7_SA_DQS_DP7':
      PIN_NUMBER='(0,0,0,0,0,0,0,0,0,0,0,0,0,0,DF67,0,0,0,0,0,0,0,0,0,0,0,0,0,0,~
0,0,0,0,0,0,0,0,0,0,0,0,0)';
      BIDIRECTIONAL='TRUE';
      INPUT_LOAD='(-0.01,0.01)';
      OUTPUT_LOAD='(1.0,-1.0)';
      PINUSE='BI';
    'DDR7_SA_DQS_DP6':
      PIN_NUMBER='(0,0,0,0,0,0,0,0,0,0,0,0,0,0,DF73,0,0,0,0,0,0,0,0,0,0,0,0,0,0,~
0,0,0,0,0,0,0,0,0,0,0,0,0)';
      BIDIRECTIONAL='TRUE';
      INPUT_LOAD='(-0.01,0.01)';
      OUTPUT_LOAD='(1.0,-1.0)';
      PINUSE='BI';
    'DDR7_SA_DQS_DP5':
      PIN_NUMBER='(0,0,0,0,0,0,0,0,0,0,0,0,0,0,DN76,0,0,0,0,0,0,0,0,0,0,0,0,0,0,~
0,0,0,0,0,0,0,0,0,0,0,0,0)';
      BIDIRECTIONAL='TRUE';
      INPUT_LOAD='(-0.01,0.01)';
      OUTPUT_LOAD='(1.0,-1.0)';
      PINUSE='BI';
    'DDR7_SA_DQS_DP4':
      PIN_NUMBER='(0,0,0,0,0,0,0,0,0,0,0,0,0,0,DB55,0,0,0,0,0,0,0,0,0,0,0,0,0,0,~
0,0,0,0,0,0,0,0,0,0,0,0,0)';
      BIDIRECTIONAL='TRUE';
      INPUT_LOAD='(-0.01,0.01)';
      OUTPUT_LOAD='(1.0,-1.0)';
      PINUSE='BI';
    'DDR7_SA_DQS_DP3':
      PIN_NUMBER='(0,0,0,0,0,0,0,0,0,0,0,0,0,0,DB61,0,0,0,0,0,0,0,0,0,0,0,0,0,0,~
0,0,0,0,0,0,0,0,0,0,0,0,0)';
      BIDIRECTIONAL='TRUE';
      INPUT_LOAD='(-0.01,0.01)';
      OUTPUT_LOAD='(1.0,-1.0)';
      PINUSE='BI';
    'DDR7_SA_DQS_DP2':
      PIN_NUMBER='(0,0,0,0,0,0,0,0,0,0,0,0,0,0,DB67,0,0,0,0,0,0,0,0,0,0,0,0,0,0,~
0,0,0,0,0,0,0,0,0,0,0,0,0)';
      BIDIRECTIONAL='TRUE';
      INPUT_LOAD='(-0.01,0.01)';
      OUTPUT_LOAD='(1.0,-1.0)';
      PINUSE='BI';
    'DDR7_SA_DQS_DP1':
      PIN_NUMBER='(0,0,0,0,0,0,0,0,0,0,0,0,0,0,DD73,0,0,0,0,0,0,0,0,0,0,0,0,0,0,~
0,0,0,0,0,0,0,0,0,0,0,0,0)';
      BIDIRECTIONAL='TRUE';
      INPUT_LOAD='(-0.01,0.01)';
      OUTPUT_LOAD='(1.0,-1.0)';
      PINUSE='BI';
    'DDR7_SA_DQS_DP0':
      PIN_NUMBER='(0,0,0,0,0,0,0,0,0,0,0,0,0,0,DL76,0,0,0,0,0,0,0,0,0,0,0,0,0,0,~
0,0,0,0,0,0,0,0,0,0,0,0,0)';
      BIDIRECTIONAL='TRUE';
      INPUT_LOAD='(-0.01,0.01)';
      OUTPUT_LOAD='(1.0,-1.0)';
      PINUSE='BI';
    'DDR7_SA_ECC7':
      PIN_NUMBER='(0,0,0,0,0,0,0,0,0,0,0,0,0,0,DF53,0,0,0,0,0,0,0,0,0,0,0,0,0,0,~
0,0,0,0,0,0,0,0,0,0,0,0,0)';
      BIDIRECTIONAL='TRUE';
      INPUT_LOAD='(-0.01,0.01)';
      OUTPUT_LOAD='(1.0,-1.0)';
      PINUSE='BI';
    'DDR7_SA_ECC6':
      PIN_NUMBER='(0,0,0,0,0,0,0,0,0,0,0,0,0,0,DG54,0,0,0,0,0,0,0,0,0,0,0,0,0,0,~
0,0,0,0,0,0,0,0,0,0,0,0,0)';
      BIDIRECTIONAL='TRUE';
      INPUT_LOAD='(-0.01,0.01)';
      OUTPUT_LOAD='(1.0,-1.0)';
      PINUSE='BI';
    'DDR7_SA_ECC5':
      PIN_NUMBER='(0,0,0,0,0,0,0,0,0,0,0,0,0,0,DD53,0,0,0,0,0,0,0,0,0,0,0,0,0,0,~
0,0,0,0,0,0,0,0,0,0,0,0,0)';
      BIDIRECTIONAL='TRUE';
      INPUT_LOAD='(-0.01,0.01)';
      OUTPUT_LOAD='(1.0,-1.0)';
      PINUSE='BI';
    'DDR7_SA_ECC4':
      PIN_NUMBER='(0,0,0,0,0,0,0,0,0,0,0,0,0,0,DC54,0,0,0,0,0,0,0,0,0,0,0,0,0,0,~
0,0,0,0,0,0,0,0,0,0,0,0,0)';
      BIDIRECTIONAL='TRUE';
      INPUT_LOAD='(-0.01,0.01)';
      OUTPUT_LOAD='(1.0,-1.0)';
      PINUSE='BI';
    'DDR7_SA_ECC3':
      PIN_NUMBER='(0,0,0,0,0,0,0,0,0,0,0,0,0,0,DG56,0,0,0,0,0,0,0,0,0,0,0,0,0,0,~
0,0,0,0,0,0,0,0,0,0,0,0,0)';
      BIDIRECTIONAL='TRUE';
      INPUT_LOAD='(-0.01,0.01)';
      OUTPUT_LOAD='(1.0,-1.0)';
      PINUSE='BI';
    'DDR7_SA_ECC2':
      PIN_NUMBER='(0,0,0,0,0,0,0,0,0,0,0,0,0,0,DF57,0,0,0,0,0,0,0,0,0,0,0,0,0,0,~
0,0,0,0,0,0,0,0,0,0,0,0,0)';
      BIDIRECTIONAL='TRUE';
      INPUT_LOAD='(-0.01,0.01)';
      OUTPUT_LOAD='(1.0,-1.0)';
      PINUSE='BI';
    'DDR7_SA_ECC1':
      PIN_NUMBER='(0,0,0,0,0,0,0,0,0,0,0,0,0,0,DC56,0,0,0,0,0,0,0,0,0,0,0,0,0,0,~
0,0,0,0,0,0,0,0,0,0,0,0,0)';
      BIDIRECTIONAL='TRUE';
      INPUT_LOAD='(-0.01,0.01)';
      OUTPUT_LOAD='(1.0,-1.0)';
      PINUSE='BI';
    'DDR7_SA_ECC0':
      PIN_NUMBER='(0,0,0,0,0,0,0,0,0,0,0,0,0,0,DD57,0,0,0,0,0,0,0,0,0,0,0,0,0,0,~
0,0,0,0,0,0,0,0,0,0,0,0,0)';
      BIDIRECTIONAL='TRUE';
      INPUT_LOAD='(-0.01,0.01)';
      OUTPUT_LOAD='(1.0,-1.0)';
      PINUSE='BI';
    'DDR7_SA_PAR':
      PIN_NUMBER='(0,0,0,0,0,0,0,0,0,0,0,0,0,0,DD40,0,0,0,0,0,0,0,0,0,0,0,0,0,0,~
0,0,0,0,0,0,0,0,0,0,0,0,0)';
      OUTPUT_LOAD='(1.0,-1.0)';
      PINUSE='OUT';
    'DDR7_SB_CA6':
      PIN_NUMBER='(0,0,0,0,0,0,0,0,0,0,0,0,0,0,DJ39,0,0,0,0,0,0,0,0,0,0,0,0,0,0,~
0,0,0,0,0,0,0,0,0,0,0,0,0)';
      OUTPUT_LOAD='(1.0,-1.0)';
      PINUSE='OUT';
    'DDR7_SB_CA5':
      PIN_NUMBER='(0,0,0,0,0,0,0,0,0,0,0,0,0,0,DP40,0,0,0,0,0,0,0,0,0,0,0,0,0,0,~
0,0,0,0,0,0,0,0,0,0,0,0,0)';
      OUTPUT_LOAD='(1.0,-1.0)';
      PINUSE='OUT';
    'DDR7_SB_CA4':
      PIN_NUMBER='(0,0,0,0,0,0,0,0,0,0,0,0,0,0,DK40,0,0,0,0,0,0,0,0,0,0,0,0,0,0,~
0,0,0,0,0,0,0,0,0,0,0,0,0)';
      OUTPUT_LOAD='(1.0,-1.0)';
      PINUSE='OUT';
    'DDR7_SB_CA3':
      PIN_NUMBER='(0,0,0,0,0,0,0,0,0,0,0,0,0,0,DN41,0,0,0,0,0,0,0,0,0,0,0,0,0,0,~
0,0,0,0,0,0,0,0,0,0,0,0,0)';
      OUTPUT_LOAD='(1.0,-1.0)';
      PINUSE='OUT';
    'DDR7_SB_CA2':
      PIN_NUMBER='(0,0,0,0,0,0,0,0,0,0,0,0,0,0,DL41,0,0,0,0,0,0,0,0,0,0,0,0,0,0,~
0,0,0,0,0,0,0,0,0,0,0,0,0)';
      OUTPUT_LOAD='(1.0,-1.0)';
      PINUSE='OUT';
    'DDR7_SB_CA1':
      PIN_NUMBER='(0,0,0,0,0,0,0,0,0,0,0,0,0,0,DG41,0,0,0,0,0,0,0,0,0,0,0,0,0,0,~
0,0,0,0,0,0,0,0,0,0,0,0,0)';
      OUTPUT_LOAD='(1.0,-1.0)';
      PINUSE='OUT';
    'DDR7_SB_CA0':
      PIN_NUMBER='(0,0,0,0,0,0,0,0,0,0,0,0,0,0,DF40,0,0,0,0,0,0,0,0,0,0,0,0,0,0,~
0,0,0,0,0,0,0,0,0,0,0,0,0)';
      OUTPUT_LOAD='(1.0,-1.0)';
      PINUSE='OUT';
    'DDR7_SB_CS_N3':
      PIN_NUMBER='(0,0,0,0,0,0,0,0,0,0,0,0,0,0,DP38,0,0,0,0,0,0,0,0,0,0,0,0,0,0,~
0,0,0,0,0,0,0,0,0,0,0,0,0)';
      OUTPUT_LOAD='(1.0,-1.0)';
      PINUSE='OUT';
    'DDR7_SB_CS_N2':
      PIN_NUMBER='(0,0,0,0,0,0,0,0,0,0,0,0,0,0,DK38,0,0,0,0,0,0,0,0,0,0,0,0,0,0,~
0,0,0,0,0,0,0,0,0,0,0,0,0)';
      OUTPUT_LOAD='(1.0,-1.0)';
      PINUSE='OUT';
    'DDR7_SB_CS_N1':
      PIN_NUMBER='(0,0,0,0,0,0,0,0,0,0,0,0,0,0,DN37,0,0,0,0,0,0,0,0,0,0,0,0,0,0,~
0,0,0,0,0,0,0,0,0,0,0,0,0)';
      OUTPUT_LOAD='(1.0,-1.0)';
      PINUSE='OUT';
    'DDR7_SB_CS_N0':
      PIN_NUMBER='(0,0,0,0,0,0,0,0,0,0,0,0,0,0,DL37,0,0,0,0,0,0,0,0,0,0,0,0,0,0,~
0,0,0,0,0,0,0,0,0,0,0,0,0)';
      OUTPUT_LOAD='(1.0,-1.0)';
      PINUSE='OUT';
    'DDR7_SB_DQ31':
      PIN_NUMBER='(0,0,0,0,0,0,0,0,0,0,0,0,0,0,DC17,0,0,0,0,0,0,0,0,0,0,0,0,0,0,~
0,0,0,0,0,0,0,0,0,0,0,0,0)';
      BIDIRECTIONAL='TRUE';
      INPUT_LOAD='(-0.01,0.01)';
      OUTPUT_LOAD='(1.0,-1.0)';
      PINUSE='BI';
    'DDR7_SB_DQ30':
      PIN_NUMBER='(0,0,0,0,0,0,0,0,0,0,0,0,0,0,DJ17,0,0,0,0,0,0,0,0,0,0,0,0,0,0,~
0,0,0,0,0,0,0,0,0,0,0,0,0)';
      BIDIRECTIONAL='TRUE';
      INPUT_LOAD='(-0.01,0.01)';
      OUTPUT_LOAD='(1.0,-1.0)';
      PINUSE='BI';
    'DDR7_SB_DQ29':
      PIN_NUMBER='(0,0,0,0,0,0,0,0,0,0,0,0,0,0,DA17,0,0,0,0,0,0,0,0,0,0,0,0,0,0,~
0,0,0,0,0,0,0,0,0,0,0,0,0)';
      BIDIRECTIONAL='TRUE';
      INPUT_LOAD='(-0.01,0.01)';
      OUTPUT_LOAD='(1.0,-1.0)';
      PINUSE='BI';
    'DDR7_SB_DQ28':
      PIN_NUMBER='(0,0,0,0,0,0,0,0,0,0,0,0,0,0,DG17,0,0,0,0,0,0,0,0,0,0,0,0,0,0,~
0,0,0,0,0,0,0,0,0,0,0,0,0)';
      BIDIRECTIONAL='TRUE';
      INPUT_LOAD='(-0.01,0.01)';
      OUTPUT_LOAD='(1.0,-1.0)';
      PINUSE='BI';
    'DDR7_SB_DQ27':
      PIN_NUMBER='(0,0,0,0,0,0,0,0,0,0,0,0,0,0,DG19,0,0,0,0,0,0,0,0,0,0,0,0,0,0,~
0,0,0,0,0,0,0,0,0,0,0,0,0)';
      BIDIRECTIONAL='TRUE';
      INPUT_LOAD='(-0.01,0.01)';
      OUTPUT_LOAD='(1.0,-1.0)';
      PINUSE='BI';
    'DDR7_SB_DQ26':
      PIN_NUMBER='(0,0,0,0,0,0,0,0,0,0,0,0,0,0,DF20,0,0,0,0,0,0,0,0,0,0,0,0,0,0,~
0,0,0,0,0,0,0,0,0,0,0,0,0)';
      BIDIRECTIONAL='TRUE';
      INPUT_LOAD='(-0.01,0.01)';
      OUTPUT_LOAD='(1.0,-1.0)';
      PINUSE='BI';
    'DDR7_SB_DQ25':
      PIN_NUMBER='(0,0,0,0,0,0,0,0,0,0,0,0,0,0,DC19,0,0,0,0,0,0,0,0,0,0,0,0,0,0,~
0,0,0,0,0,0,0,0,0,0,0,0,0)';
      BIDIRECTIONAL='TRUE';
      INPUT_LOAD='(-0.01,0.01)';
      OUTPUT_LOAD='(1.0,-1.0)';
      PINUSE='BI';
    'DDR7_SB_DQ24':
      PIN_NUMBER='(0,0,0,0,0,0,0,0,0,0,0,0,0,0,DD20,0,0,0,0,0,0,0,0,0,0,0,0,0,0,~
0,0,0,0,0,0,0,0,0,0,0,0,0)';
      BIDIRECTIONAL='TRUE';
      INPUT_LOAD='(-0.01,0.01)';
      OUTPUT_LOAD='(1.0,-1.0)';
      PINUSE='BI';
    'DDR7_SB_DQ23':
      PIN_NUMBER='(0,0,0,0,0,0,0,0,0,0,0,0,0,0,DN19,0,0,0,0,0,0,0,0,0,0,0,0,0,0,~
0,0,0,0,0,0,0,0,0,0,0,0,0)';
      BIDIRECTIONAL='TRUE';
      INPUT_LOAD='(-0.01,0.01)';
      OUTPUT_LOAD='(1.0,-1.0)';
      PINUSE='BI';
    'DDR7_SB_DQ22':
      PIN_NUMBER='(0,0,0,0,0,0,0,0,0,0,0,0,0,0,DP20,0,0,0,0,0,0,0,0,0,0,0,0,0,0,~
0,0,0,0,0,0,0,0,0,0,0,0,0)';
      BIDIRECTIONAL='TRUE';
      INPUT_LOAD='(-0.01,0.01)';
      OUTPUT_LOAD='(1.0,-1.0)';
      PINUSE='BI';
    'DDR7_SB_DQ21':
      PIN_NUMBER='(0,0,0,0,0,0,0,0,0,0,0,0,0,0,DL19,0,0,0,0,0,0,0,0,0,0,0,0,0,0,~
0,0,0,0,0,0,0,0,0,0,0,0,0)';
      BIDIRECTIONAL='TRUE';
      INPUT_LOAD='(-0.01,0.01)';
      OUTPUT_LOAD='(1.0,-1.0)';
      PINUSE='BI';
    'DDR7_SB_DQ20':
      PIN_NUMBER='(0,0,0,0,0,0,0,0,0,0,0,0,0,0,DK20,0,0,0,0,0,0,0,0,0,0,0,0,0,0,~
0,0,0,0,0,0,0,0,0,0,0,0,0)';
      BIDIRECTIONAL='TRUE';
      INPUT_LOAD='(-0.01,0.01)';
      OUTPUT_LOAD='(1.0,-1.0)';
      PINUSE='BI';
    'DDR7_SB_DQ19':
      PIN_NUMBER='(0,0,0,0,0,0,0,0,0,0,0,0,0,0,DP22,0,0,0,0,0,0,0,0,0,0,0,0,0,0,~
0,0,0,0,0,0,0,0,0,0,0,0,0)';
      BIDIRECTIONAL='TRUE';
      INPUT_LOAD='(-0.01,0.01)';
      OUTPUT_LOAD='(1.0,-1.0)';
      PINUSE='BI';
    'DDR7_SB_DQ18':
      PIN_NUMBER='(0,0,0,0,0,0,0,0,0,0,0,0,0,0,DN23,0,0,0,0,0,0,0,0,0,0,0,0,0,0,~
0,0,0,0,0,0,0,0,0,0,0,0,0)';
      BIDIRECTIONAL='TRUE';
      INPUT_LOAD='(-0.01,0.01)';
      OUTPUT_LOAD='(1.0,-1.0)';
      PINUSE='BI';
    'DDR7_SB_DQ17':
      PIN_NUMBER='(0,0,0,0,0,0,0,0,0,0,0,0,0,0,DK22,0,0,0,0,0,0,0,0,0,0,0,0,0,0,~
0,0,0,0,0,0,0,0,0,0,0,0,0)';
      BIDIRECTIONAL='TRUE';
      INPUT_LOAD='(-0.01,0.01)';
      OUTPUT_LOAD='(1.0,-1.0)';
      PINUSE='BI';
    'DDR7_SB_DQ16':
      PIN_NUMBER='(0,0,0,0,0,0,0,0,0,0,0,0,0,0,DL23,0,0,0,0,0,0,0,0,0,0,0,0,0,0,~
0,0,0,0,0,0,0,0,0,0,0,0,0)';
      BIDIRECTIONAL='TRUE';
      INPUT_LOAD='(-0.01,0.01)';
      OUTPUT_LOAD='(1.0,-1.0)';
      PINUSE='BI';
    'DDR7_SB_DQ15':
      PIN_NUMBER='(0,0,0,0,0,0,0,0,0,0,0,0,0,0,DF22,0,0,0,0,0,0,0,0,0,0,0,0,0,0,~
0,0,0,0,0,0,0,0,0,0,0,0,0)';
      BIDIRECTIONAL='TRUE';
      INPUT_LOAD='(-0.01,0.01)';
      OUTPUT_LOAD='(1.0,-1.0)';
      PINUSE='BI';
    'DDR7_SB_DQ14':
      PIN_NUMBER='(0,0,0,0,0,0,0,0,0,0,0,0,0,0,DG23,0,0,0,0,0,0,0,0,0,0,0,0,0,0,~
0,0,0,0,0,0,0,0,0,0,0,0,0)';
      BIDIRECTIONAL='TRUE';
      INPUT_LOAD='(-0.01,0.01)';
      OUTPUT_LOAD='(1.0,-1.0)';
      PINUSE='BI';
    'DDR7_SB_DQ13':
      PIN_NUMBER='(0,0,0,0,0,0,0,0,0,0,0,0,0,0,DD22,0,0,0,0,0,0,0,0,0,0,0,0,0,0,~
0,0,0,0,0,0,0,0,0,0,0,0,0)';
      BIDIRECTIONAL='TRUE';
      INPUT_LOAD='(-0.01,0.01)';
      OUTPUT_LOAD='(1.0,-1.0)';
      PINUSE='BI';
    'DDR7_SB_DQ12':
      PIN_NUMBER='(0,0,0,0,0,0,0,0,0,0,0,0,0,0,DC23,0,0,0,0,0,0,0,0,0,0,0,0,0,0,~
0,0,0,0,0,0,0,0,0,0,0,0,0)';
      BIDIRECTIONAL='TRUE';
      INPUT_LOAD='(-0.01,0.01)';
      OUTPUT_LOAD='(1.0,-1.0)';
      PINUSE='BI';
    'DDR7_SB_DQ11':
      PIN_NUMBER='(0,0,0,0,0,0,0,0,0,0,0,0,0,0,DG25,0,0,0,0,0,0,0,0,0,0,0,0,0,0,~
0,0,0,0,0,0,0,0,0,0,0,0,0)';
      BIDIRECTIONAL='TRUE';
      INPUT_LOAD='(-0.01,0.01)';
      OUTPUT_LOAD='(1.0,-1.0)';
      PINUSE='BI';
    'DDR7_SB_DQ10':
      PIN_NUMBER='(0,0,0,0,0,0,0,0,0,0,0,0,0,0,DF26,0,0,0,0,0,0,0,0,0,0,0,0,0,0,~
0,0,0,0,0,0,0,0,0,0,0,0,0)';
      BIDIRECTIONAL='TRUE';
      INPUT_LOAD='(-0.01,0.01)';
      OUTPUT_LOAD='(1.0,-1.0)';
      PINUSE='BI';
    'DDR7_SB_DQ9':
      PIN_NUMBER='(0,0,0,0,0,0,0,0,0,0,0,0,0,0,DC25,0,0,0,0,0,0,0,0,0,0,0,0,0,0,~
0,0,0,0,0,0,0,0,0,0,0,0,0)';
      BIDIRECTIONAL='TRUE';
      INPUT_LOAD='(-0.01,0.01)';
      OUTPUT_LOAD='(1.0,-1.0)';
      PINUSE='BI';
    'DDR7_SB_DQ8':
      PIN_NUMBER='(0,0,0,0,0,0,0,0,0,0,0,0,0,0,DD26,0,0,0,0,0,0,0,0,0,0,0,0,0,0,~
0,0,0,0,0,0,0,0,0,0,0,0,0)';
      BIDIRECTIONAL='TRUE';
      INPUT_LOAD='(-0.01,0.01)';
      OUTPUT_LOAD='(1.0,-1.0)';
      PINUSE='BI';
    'DDR7_SB_DQ7':
      PIN_NUMBER='(0,0,0,0,0,0,0,0,0,0,0,0,0,0,DD28,0,0,0,0,0,0,0,0,0,0,0,0,0,0,~
0,0,0,0,0,0,0,0,0,0,0,0,0)';
      BIDIRECTIONAL='TRUE';
      INPUT_LOAD='(-0.01,0.01)';
      OUTPUT_LOAD='(1.0,-1.0)';
      PINUSE='BI';
    'DDR7_SB_DQ6':
      PIN_NUMBER='(0,0,0,0,0,0,0,0,0,0,0,0,0,0,DG29,0,0,0,0,0,0,0,0,0,0,0,0,0,0,~
0,0,0,0,0,0,0,0,0,0,0,0,0)';
      BIDIRECTIONAL='TRUE';
      INPUT_LOAD='(-0.01,0.01)';
      OUTPUT_LOAD='(1.0,-1.0)';
      PINUSE='BI';
    'DDR7_SB_DQ5':
      PIN_NUMBER='(0,0,0,0,0,0,0,0,0,0,0,0,0,0,DF28,0,0,0,0,0,0,0,0,0,0,0,0,0,0,~
0,0,0,0,0,0,0,0,0,0,0,0,0)';
      BIDIRECTIONAL='TRUE';
      INPUT_LOAD='(-0.01,0.01)';
      OUTPUT_LOAD='(1.0,-1.0)';
      PINUSE='BI';
    'DDR7_SB_DQ4':
      PIN_NUMBER='(0,0,0,0,0,0,0,0,0,0,0,0,0,0,DC29,0,0,0,0,0,0,0,0,0,0,0,0,0,0,~
0,0,0,0,0,0,0,0,0,0,0,0,0)';
      BIDIRECTIONAL='TRUE';
      INPUT_LOAD='(-0.01,0.01)';
      OUTPUT_LOAD='(1.0,-1.0)';
      PINUSE='BI';
    'DDR7_SB_DQ3':
      PIN_NUMBER='(0,0,0,0,0,0,0,0,0,0,0,0,0,0,DG31,0,0,0,0,0,0,0,0,0,0,0,0,0,0,~
0,0,0,0,0,0,0,0,0,0,0,0,0)';
      BIDIRECTIONAL='TRUE';
      INPUT_LOAD='(-0.01,0.01)';
      OUTPUT_LOAD='(1.0,-1.0)';
      PINUSE='BI';
    'DDR7_SB_DQ2':
      PIN_NUMBER='(0,0,0,0,0,0,0,0,0,0,0,0,0,0,DF32,0,0,0,0,0,0,0,0,0,0,0,0,0,0,~
0,0,0,0,0,0,0,0,0,0,0,0,0)';
      BIDIRECTIONAL='TRUE';
      INPUT_LOAD='(-0.01,0.01)';
      OUTPUT_LOAD='(1.0,-1.0)';
      PINUSE='BI';
    'DDR7_SB_DQ1':
      PIN_NUMBER='(0,0,0,0,0,0,0,0,0,0,0,0,0,0,DC31,0,0,0,0,0,0,0,0,0,0,0,0,0,0,~
0,0,0,0,0,0,0,0,0,0,0,0,0)';
      BIDIRECTIONAL='TRUE';
      INPUT_LOAD='(-0.01,0.01)';
      OUTPUT_LOAD='(1.0,-1.0)';
      PINUSE='BI';
    'DDR7_SB_DQ0':
      PIN_NUMBER='(0,0,0,0,0,0,0,0,0,0,0,0,0,0,DD32,0,0,0,0,0,0,0,0,0,0,0,0,0,0,~
0,0,0,0,0,0,0,0,0,0,0,0,0)';
      BIDIRECTIONAL='TRUE';
      INPUT_LOAD='(-0.01,0.01)';
      OUTPUT_LOAD='(1.0,-1.0)';
      PINUSE='BI';
    'DDR7_SB_DQS_DN9':
      PIN_NUMBER='(0,0,0,0,0,0,0,0,0,0,0,0,0,0,DD36,0,0,0,0,0,0,0,0,0,0,0,0,0,0,~
0,0,0,0,0,0,0,0,0,0,0,0,0)';
      BIDIRECTIONAL='TRUE';
      INPUT_LOAD='(-0.01,0.01)';
      OUTPUT_LOAD='(1.0,-1.0)';
      PINUSE='BI';
    'DDR7_SB_DQS_DN8':
      PIN_NUMBER='(0,0,0,0,0,0,0,0,0,0,0,0,0,0,DF18,0,0,0,0,0,0,0,0,0,0,0,0,0,0,~
0,0,0,0,0,0,0,0,0,0,0,0,0)';
      BIDIRECTIONAL='TRUE';
      INPUT_LOAD='(-0.01,0.01)';
      OUTPUT_LOAD='(1.0,-1.0)';
      PINUSE='BI';
    'DDR7_SB_DQS_DN7':
      PIN_NUMBER='(0,0,0,0,0,0,0,0,0,0,0,0,0,0,DR21,0,0,0,0,0,0,0,0,0,0,0,0,0,0,~
0,0,0,0,0,0,0,0,0,0,0,0,0)';
      BIDIRECTIONAL='TRUE';
      INPUT_LOAD='(-0.01,0.01)';
      OUTPUT_LOAD='(1.0,-1.0)';
      PINUSE='BI';
    'DDR7_SB_DQS_DN6':
      PIN_NUMBER='(0,0,0,0,0,0,0,0,0,0,0,0,0,0,DH24,0,0,0,0,0,0,0,0,0,0,0,0,0,0,~
0,0,0,0,0,0,0,0,0,0,0,0,0)';
      BIDIRECTIONAL='TRUE';
      INPUT_LOAD='(-0.01,0.01)';
      OUTPUT_LOAD='(1.0,-1.0)';
      PINUSE='BI';
    'DDR7_SB_DQS_DN5':
      PIN_NUMBER='(0,0,0,0,0,0,0,0,0,0,0,0,0,0,DH30,0,0,0,0,0,0,0,0,0,0,0,0,0,0,~
0,0,0,0,0,0,0,0,0,0,0,0,0)';
      BIDIRECTIONAL='TRUE';
      INPUT_LOAD='(-0.01,0.01)';
      OUTPUT_LOAD='(1.0,-1.0)';
      PINUSE='BI';
    'DDR7_SB_DQS_DN4':
      PIN_NUMBER='(0,0,0,0,0,0,0,0,0,0,0,0,0,0,DH36,0,0,0,0,0,0,0,0,0,0,0,0,0,0,~
0,0,0,0,0,0,0,0,0,0,0,0,0)';
      BIDIRECTIONAL='TRUE';
      INPUT_LOAD='(-0.01,0.01)';
      OUTPUT_LOAD='(1.0,-1.0)';
      PINUSE='BI';
    'DDR7_SB_DQS_DN3':
      PIN_NUMBER='(0,0,0,0,0,0,0,0,0,0,0,0,0,0,DB18,0,0,0,0,0,0,0,0,0,0,0,0,0,0,~
0,0,0,0,0,0,0,0,0,0,0,0,0)';
      BIDIRECTIONAL='TRUE';
      INPUT_LOAD='(-0.01,0.01)';
      OUTPUT_LOAD='(1.0,-1.0)';
      PINUSE='BI';
    'DDR7_SB_DQS_DN2':
      PIN_NUMBER='(0,0,0,0,0,0,0,0,0,0,0,0,0,0,DL21,0,0,0,0,0,0,0,0,0,0,0,0,0,0,~
0,0,0,0,0,0,0,0,0,0,0,0,0)';
      BIDIRECTIONAL='TRUE';
      INPUT_LOAD='(-0.01,0.01)';
      OUTPUT_LOAD='(1.0,-1.0)';
      PINUSE='BI';
    'DDR7_SB_DQS_DN1':
      PIN_NUMBER='(0,0,0,0,0,0,0,0,0,0,0,0,0,0,DD24,0,0,0,0,0,0,0,0,0,0,0,0,0,0,~
0,0,0,0,0,0,0,0,0,0,0,0,0)';
      BIDIRECTIONAL='TRUE';
      INPUT_LOAD='(-0.01,0.01)';
      OUTPUT_LOAD='(1.0,-1.0)';
      PINUSE='BI';
    'DDR7_SB_DQS_DN0':
      PIN_NUMBER='(0,0,0,0,0,0,0,0,0,0,0,0,0,0,DD30,0,0,0,0,0,0,0,0,0,0,0,0,0,0,~
0,0,0,0,0,0,0,0,0,0,0,0,0)';
      BIDIRECTIONAL='TRUE';
      INPUT_LOAD='(-0.01,0.01)';
      OUTPUT_LOAD='(1.0,-1.0)';
      PINUSE='BI';
    'DDR7_SB_DQS_DP9':
      PIN_NUMBER='(0,0,0,0,0,0,0,0,0,0,0,0,0,0,DB36,0,0,0,0,0,0,0,0,0,0,0,0,0,0,~
0,0,0,0,0,0,0,0,0,0,0,0,0)';
      BIDIRECTIONAL='TRUE';
      INPUT_LOAD='(-0.01,0.01)';
      OUTPUT_LOAD='(1.0,-1.0)';
      PINUSE='BI';
    'DDR7_SB_DQS_DP8':
      PIN_NUMBER='(0,0,0,0,0,0,0,0,0,0,0,0,0,0,DH18,0,0,0,0,0,0,0,0,0,0,0,0,0,0,~
0,0,0,0,0,0,0,0,0,0,0,0,0)';
      BIDIRECTIONAL='TRUE';
      INPUT_LOAD='(-0.01,0.01)';
      OUTPUT_LOAD='(1.0,-1.0)';
      PINUSE='BI';
    'DDR7_SB_DQS_DP7':
      PIN_NUMBER='(0,0,0,0,0,0,0,0,0,0,0,0,0,0,DN21,0,0,0,0,0,0,0,0,0,0,0,0,0,0,~
0,0,0,0,0,0,0,0,0,0,0,0,0)';
      BIDIRECTIONAL='TRUE';
      INPUT_LOAD='(-0.01,0.01)';
      OUTPUT_LOAD='(1.0,-1.0)';
      PINUSE='BI';
    'DDR7_SB_DQS_DP6':
      PIN_NUMBER='(0,0,0,0,0,0,0,0,0,0,0,0,0,0,DF24,0,0,0,0,0,0,0,0,0,0,0,0,0,0,~
0,0,0,0,0,0,0,0,0,0,0,0,0)';
      BIDIRECTIONAL='TRUE';
      INPUT_LOAD='(-0.01,0.01)';
      OUTPUT_LOAD='(1.0,-1.0)';
      PINUSE='BI';
    'DDR7_SB_DQS_DP5':
      PIN_NUMBER='(0,0,0,0,0,0,0,0,0,0,0,0,0,0,DF30,0,0,0,0,0,0,0,0,0,0,0,0,0,0,~
0,0,0,0,0,0,0,0,0,0,0,0,0)';
      BIDIRECTIONAL='TRUE';
      INPUT_LOAD='(-0.01,0.01)';
      OUTPUT_LOAD='(1.0,-1.0)';
      PINUSE='BI';
    'DDR7_SB_DQS_DP4':
      PIN_NUMBER='(0,0,0,0,0,0,0,0,0,0,0,0,0,0,DF36,0,0,0,0,0,0,0,0,0,0,0,0,0,0,~
0,0,0,0,0,0,0,0,0,0,0,0,0)';
      BIDIRECTIONAL='TRUE';
      INPUT_LOAD='(-0.01,0.01)';
      OUTPUT_LOAD='(1.0,-1.0)';
      PINUSE='BI';
    'DDR7_SB_DQS_DP3':
      PIN_NUMBER='(0,0,0,0,0,0,0,0,0,0,0,0,0,0,DD18,0,0,0,0,0,0,0,0,0,0,0,0,0,0,~
0,0,0,0,0,0,0,0,0,0,0,0,0)';
      BIDIRECTIONAL='TRUE';
      INPUT_LOAD='(-0.01,0.01)';
      OUTPUT_LOAD='(1.0,-1.0)';
      PINUSE='BI';
    'DDR7_SB_DQS_DP2':
      PIN_NUMBER='(0,0,0,0,0,0,0,0,0,0,0,0,0,0,DJ21,0,0,0,0,0,0,0,0,0,0,0,0,0,0,~
0,0,0,0,0,0,0,0,0,0,0,0,0)';
      BIDIRECTIONAL='TRUE';
      INPUT_LOAD='(-0.01,0.01)';
      OUTPUT_LOAD='(1.0,-1.0)';
      PINUSE='BI';
    'DDR7_SB_DQS_DP1':
      PIN_NUMBER='(0,0,0,0,0,0,0,0,0,0,0,0,0,0,DB24,0,0,0,0,0,0,0,0,0,0,0,0,0,0,~
0,0,0,0,0,0,0,0,0,0,0,0,0)';
      BIDIRECTIONAL='TRUE';
      INPUT_LOAD='(-0.01,0.01)';
      OUTPUT_LOAD='(1.0,-1.0)';
      PINUSE='BI';
    'DDR7_SB_DQS_DP0':
      PIN_NUMBER='(0,0,0,0,0,0,0,0,0,0,0,0,0,0,DB30,0,0,0,0,0,0,0,0,0,0,0,0,0,0,~
0,0,0,0,0,0,0,0,0,0,0,0,0)';
      BIDIRECTIONAL='TRUE';
      INPUT_LOAD='(-0.01,0.01)';
      OUTPUT_LOAD='(1.0,-1.0)';
      PINUSE='BI';
    'DDR7_SB_ECC7':
      PIN_NUMBER='(0,0,0,0,0,0,0,0,0,0,0,0,0,0,DC37,0,0,0,0,0,0,0,0,0,0,0,0,0,0,~
0,0,0,0,0,0,0,0,0,0,0,0,0)';
      BIDIRECTIONAL='TRUE';
      INPUT_LOAD='(-0.01,0.01)';
      OUTPUT_LOAD='(1.0,-1.0)';
      PINUSE='BI';
    'DDR7_SB_ECC6':
      PIN_NUMBER='(0,0,0,0,0,0,0,0,0,0,0,0,0,0,DD38,0,0,0,0,0,0,0,0,0,0,0,0,0,0,~
0,0,0,0,0,0,0,0,0,0,0,0,0)';
      BIDIRECTIONAL='TRUE';
      INPUT_LOAD='(-0.01,0.01)';
      OUTPUT_LOAD='(1.0,-1.0)';
      PINUSE='BI';
    'DDR7_SB_ECC5':
      PIN_NUMBER='(0,0,0,0,0,0,0,0,0,0,0,0,0,0,DG37,0,0,0,0,0,0,0,0,0,0,0,0,0,0,~
0,0,0,0,0,0,0,0,0,0,0,0,0)';
      BIDIRECTIONAL='TRUE';
      INPUT_LOAD='(-0.01,0.01)';
      OUTPUT_LOAD='(1.0,-1.0)';
      PINUSE='BI';
    'DDR7_SB_ECC4':
      PIN_NUMBER='(0,0,0,0,0,0,0,0,0,0,0,0,0,0,DF38,0,0,0,0,0,0,0,0,0,0,0,0,0,0,~
0,0,0,0,0,0,0,0,0,0,0,0,0)';
      BIDIRECTIONAL='TRUE';
      INPUT_LOAD='(-0.01,0.01)';
      OUTPUT_LOAD='(1.0,-1.0)';
      PINUSE='BI';
    'DDR7_SB_ECC3':
      PIN_NUMBER='(0,0,0,0,0,0,0,0,0,0,0,0,0,0,DF34,0,0,0,0,0,0,0,0,0,0,0,0,0,0,~
0,0,0,0,0,0,0,0,0,0,0,0,0)';
      BIDIRECTIONAL='TRUE';
      INPUT_LOAD='(-0.01,0.01)';
      OUTPUT_LOAD='(1.0,-1.0)';
      PINUSE='BI';
    'DDR7_SB_ECC2':
      PIN_NUMBER='(0,0,0,0,0,0,0,0,0,0,0,0,0,0,DG35,0,0,0,0,0,0,0,0,0,0,0,0,0,0,~
0,0,0,0,0,0,0,0,0,0,0,0,0)';
      BIDIRECTIONAL='TRUE';
      INPUT_LOAD='(-0.01,0.01)';
      OUTPUT_LOAD='(1.0,-1.0)';
      PINUSE='BI';
    'DDR7_SB_ECC1':
      PIN_NUMBER='(0,0,0,0,0,0,0,0,0,0,0,0,0,0,DD34,0,0,0,0,0,0,0,0,0,0,0,0,0,0,~
0,0,0,0,0,0,0,0,0,0,0,0,0)';
      BIDIRECTIONAL='TRUE';
      INPUT_LOAD='(-0.01,0.01)';
      OUTPUT_LOAD='(1.0,-1.0)';
      PINUSE='BI';
    'DDR7_SB_ECC0':
      PIN_NUMBER='(0,0,0,0,0,0,0,0,0,0,0,0,0,0,DC35,0,0,0,0,0,0,0,0,0,0,0,0,0,0,~
0,0,0,0,0,0,0,0,0,0,0,0,0)';
      BIDIRECTIONAL='TRUE';
      INPUT_LOAD='(-0.01,0.01)';
      OUTPUT_LOAD='(1.0,-1.0)';
      PINUSE='BI';
    'DDR7_SB_PAR':
      PIN_NUMBER='(0,0,0,0,0,0,0,0,0,0,0,0,0,0,DR39,0,0,0,0,0,0,0,0,0,0,0,0,0,0,~
0,0,0,0,0,0,0,0,0,0,0,0,0)';
      OUTPUT_LOAD='(1.0,-1.0)';
      PINUSE='OUT';
    'DMI_RX_DN7':
      PIN_NUMBER='(0,0,0,0,0,0,0,0,0,0,0,0,0,0,0,BU17,0,0,0,0,0,0,0,0,0,0,0,0,0,~
0,0,0,0,0,0,0,0,0,0,0,0,0)';
      INPUT_LOAD='(-0.01,0.01)';
      PINUSE='IN';
    'DMI_RX_DN6':
      PIN_NUMBER='(0,0,0,0,0,0,0,0,0,0,0,0,0,0,0,BP18,0,0,0,0,0,0,0,0,0,0,0,0,0,~
0,0,0,0,0,0,0,0,0,0,0,0,0)';
      INPUT_LOAD='(-0.01,0.01)';
      PINUSE='IN';
    'DMI_RX_DN5':
      PIN_NUMBER='(0,0,0,0,0,0,0,0,0,0,0,0,0,0,0,BN17,0,0,0,0,0,0,0,0,0,0,0,0,0,~
0,0,0,0,0,0,0,0,0,0,0,0,0)';
      INPUT_LOAD='(-0.01,0.01)';
      PINUSE='IN';
    'DMI_RX_DN4':
      PIN_NUMBER='(0,0,0,0,0,0,0,0,0,0,0,0,0,0,0,BK18,0,0,0,0,0,0,0,0,0,0,0,0,0,~
0,0,0,0,0,0,0,0,0,0,0,0,0)';
      INPUT_LOAD='(-0.01,0.01)';
      PINUSE='IN';
    'DMI_RX_DN3':
      PIN_NUMBER='(0,0,0,0,0,0,0,0,0,0,0,0,0,0,0,BJ17,0,0,0,0,0,0,0,0,0,0,0,0,0,~
0,0,0,0,0,0,0,0,0,0,0,0,0)';
      INPUT_LOAD='(-0.01,0.01)';
      PINUSE='IN';
    'DMI_RX_DN2':
      PIN_NUMBER='(0,0,0,0,0,0,0,0,0,0,0,0,0,0,0,BF18,0,0,0,0,0,0,0,0,0,0,0,0,0,~
0,0,0,0,0,0,0,0,0,0,0,0,0)';
      INPUT_LOAD='(-0.01,0.01)';
      PINUSE='IN';
    'DMI_RX_DN1':
      PIN_NUMBER='(0,0,0,0,0,0,0,0,0,0,0,0,0,0,0,BE17,0,0,0,0,0,0,0,0,0,0,0,0,0,~
0,0,0,0,0,0,0,0,0,0,0,0,0)';
      INPUT_LOAD='(-0.01,0.01)';
      PINUSE='IN';
    'DMI_RX_DN0':
      PIN_NUMBER='(0,0,0,0,0,0,0,0,0,0,0,0,0,0,0,BB18,0,0,0,0,0,0,0,0,0,0,0,0,0,~
0,0,0,0,0,0,0,0,0,0,0,0,0)';
      INPUT_LOAD='(-0.01,0.01)';
      PINUSE='IN';
    'DMI_RX_DP7':
      PIN_NUMBER='(0,0,0,0,0,0,0,0,0,0,0,0,0,0,0,BT18,0,0,0,0,0,0,0,0,0,0,0,0,0,~
0,0,0,0,0,0,0,0,0,0,0,0,0)';
      INPUT_LOAD='(-0.01,0.01)';
      PINUSE='IN';
    'DMI_RX_DP6':
      PIN_NUMBER='(0,0,0,0,0,0,0,0,0,0,0,0,0,0,0,BR19,0,0,0,0,0,0,0,0,0,0,0,0,0,~
0,0,0,0,0,0,0,0,0,0,0,0,0)';
      INPUT_LOAD='(-0.01,0.01)';
      PINUSE='IN';
    'DMI_RX_DP5':
      PIN_NUMBER='(0,0,0,0,0,0,0,0,0,0,0,0,0,0,0,BM18,0,0,0,0,0,0,0,0,0,0,0,0,0,~
0,0,0,0,0,0,0,0,0,0,0,0,0)';
      INPUT_LOAD='(-0.01,0.01)';
      PINUSE='IN';
    'DMI_RX_DP4':
      PIN_NUMBER='(0,0,0,0,0,0,0,0,0,0,0,0,0,0,0,BL19,0,0,0,0,0,0,0,0,0,0,0,0,0,~
0,0,0,0,0,0,0,0,0,0,0,0,0)';
      INPUT_LOAD='(-0.01,0.01)';
      PINUSE='IN';
    'DMI_RX_DP3':
      PIN_NUMBER='(0,0,0,0,0,0,0,0,0,0,0,0,0,0,0,BH18,0,0,0,0,0,0,0,0,0,0,0,0,0,~
0,0,0,0,0,0,0,0,0,0,0,0,0)';
      INPUT_LOAD='(-0.01,0.01)';
      PINUSE='IN';
    'DMI_RX_DP2':
      PIN_NUMBER='(0,0,0,0,0,0,0,0,0,0,0,0,0,0,0,BG19,0,0,0,0,0,0,0,0,0,0,0,0,0,~
0,0,0,0,0,0,0,0,0,0,0,0,0)';
      INPUT_LOAD='(-0.01,0.01)';
      PINUSE='IN';
    'DMI_RX_DP1':
      PIN_NUMBER='(0,0,0,0,0,0,0,0,0,0,0,0,0,0,0,BD18,0,0,0,0,0,0,0,0,0,0,0,0,0,~
0,0,0,0,0,0,0,0,0,0,0,0,0)';
      INPUT_LOAD='(-0.01,0.01)';
      PINUSE='IN';
    'DMI_RX_DP0':
      PIN_NUMBER='(0,0,0,0,0,0,0,0,0,0,0,0,0,0,0,BC19,0,0,0,0,0,0,0,0,0,0,0,0,0,~
0,0,0,0,0,0,0,0,0,0,0,0,0)';
      INPUT_LOAD='(-0.01,0.01)';
      PINUSE='IN';
    'DMI_TX_DN7':
      PIN_NUMBER='(0,0,0,0,0,0,0,0,0,0,0,0,0,0,0,CN17,0,0,0,0,0,0,0,0,0,0,0,0,0,~
0,0,0,0,0,0,0,0,0,0,0,0,0)';
      OUTPUT_LOAD='(1.0,-1.0)';
      PINUSE='OUT';
    'DMI_TX_DN6':
      PIN_NUMBER='(0,0,0,0,0,0,0,0,0,0,0,0,0,0,0,CK18,0,0,0,0,0,0,0,0,0,0,0,0,0,~
0,0,0,0,0,0,0,0,0,0,0,0,0)';
      OUTPUT_LOAD='(1.0,-1.0)';
      PINUSE='OUT';
    'DMI_TX_DN5':
      PIN_NUMBER='(0,0,0,0,0,0,0,0,0,0,0,0,0,0,0,CJ17,0,0,0,0,0,0,0,0,0,0,0,0,0,~
0,0,0,0,0,0,0,0,0,0,0,0,0)';
      OUTPUT_LOAD='(1.0,-1.0)';
      PINUSE='OUT';
    'DMI_TX_DN4':
      PIN_NUMBER='(0,0,0,0,0,0,0,0,0,0,0,0,0,0,0,CF18,0,0,0,0,0,0,0,0,0,0,0,0,0,~
0,0,0,0,0,0,0,0,0,0,0,0,0)';
      OUTPUT_LOAD='(1.0,-1.0)';
      PINUSE='OUT';
    'DMI_TX_DN3':
      PIN_NUMBER='(0,0,0,0,0,0,0,0,0,0,0,0,0,0,0,CE17,0,0,0,0,0,0,0,0,0,0,0,0,0,~
0,0,0,0,0,0,0,0,0,0,0,0,0)';
      OUTPUT_LOAD='(1.0,-1.0)';
      PINUSE='OUT';
    'DMI_TX_DN2':
      PIN_NUMBER='(0,0,0,0,0,0,0,0,0,0,0,0,0,0,0,CB18,0,0,0,0,0,0,0,0,0,0,0,0,0,~
0,0,0,0,0,0,0,0,0,0,0,0,0)';
      OUTPUT_LOAD='(1.0,-1.0)';
      PINUSE='OUT';
    'DMI_TX_DN1':
      PIN_NUMBER='(0,0,0,0,0,0,0,0,0,0,0,0,0,0,0,CA17,0,0,0,0,0,0,0,0,0,0,0,0,0,~
0,0,0,0,0,0,0,0,0,0,0,0,0)';
      OUTPUT_LOAD='(1.0,-1.0)';
      PINUSE='OUT';
    'DMI_TX_DN0':
      PIN_NUMBER='(0,0,0,0,0,0,0,0,0,0,0,0,0,0,0,BW19,0,0,0,0,0,0,0,0,0,0,0,0,0,~
0,0,0,0,0,0,0,0,0,0,0,0,0)';
      OUTPUT_LOAD='(1.0,-1.0)';
      PINUSE='OUT';
    'DMI_TX_DP7':
      PIN_NUMBER='(0,0,0,0,0,0,0,0,0,0,0,0,0,0,0,CM18,0,0,0,0,0,0,0,0,0,0,0,0,0,~
0,0,0,0,0,0,0,0,0,0,0,0,0)';
      OUTPUT_LOAD='(1.0,-1.0)';
      PINUSE='OUT';
    'DMI_TX_DP6':
      PIN_NUMBER='(0,0,0,0,0,0,0,0,0,0,0,0,0,0,0,CL19,0,0,0,0,0,0,0,0,0,0,0,0,0,~
0,0,0,0,0,0,0,0,0,0,0,0,0)';
      OUTPUT_LOAD='(1.0,-1.0)';
      PINUSE='OUT';
    'DMI_TX_DP5':
      PIN_NUMBER='(0,0,0,0,0,0,0,0,0,0,0,0,0,0,0,CH18,0,0,0,0,0,0,0,0,0,0,0,0,0,~
0,0,0,0,0,0,0,0,0,0,0,0,0)';
      OUTPUT_LOAD='(1.0,-1.0)';
      PINUSE='OUT';
    'DMI_TX_DP4':
      PIN_NUMBER='(0,0,0,0,0,0,0,0,0,0,0,0,0,0,0,CG19,0,0,0,0,0,0,0,0,0,0,0,0,0,~
0,0,0,0,0,0,0,0,0,0,0,0,0)';
      OUTPUT_LOAD='(1.0,-1.0)';
      PINUSE='OUT';
    'DMI_TX_DP3':
      PIN_NUMBER='(0,0,0,0,0,0,0,0,0,0,0,0,0,0,0,CD18,0,0,0,0,0,0,0,0,0,0,0,0,0,~
0,0,0,0,0,0,0,0,0,0,0,0,0)';
      OUTPUT_LOAD='(1.0,-1.0)';
      PINUSE='OUT';
    'DMI_TX_DP2':
      PIN_NUMBER='(0,0,0,0,0,0,0,0,0,0,0,0,0,0,0,CC19,0,0,0,0,0,0,0,0,0,0,0,0,0,~
0,0,0,0,0,0,0,0,0,0,0,0,0)';
      OUTPUT_LOAD='(1.0,-1.0)';
      PINUSE='OUT';
    'DMI_TX_DP1':
      PIN_NUMBER='(0,0,0,0,0,0,0,0,0,0,0,0,0,0,0,BY18,0,0,0,0,0,0,0,0,0,0,0,0,0,~
0,0,0,0,0,0,0,0,0,0,0,0,0)';
      OUTPUT_LOAD='(1.0,-1.0)';
      PINUSE='OUT';
    'DMI_TX_DP0':
      PIN_NUMBER='(0,0,0,0,0,0,0,0,0,0,0,0,0,0,0,CA19,0,0,0,0,0,0,0,0,0,0,0,0,0,~
0,0,0,0,0,0,0,0,0,0,0,0,0)';
      OUTPUT_LOAD='(1.0,-1.0)';
      PINUSE='OUT';
    'PE0_RX_DN15':
      PIN_NUMBER='(0,0,0,0,0,0,0,0,0,0,0,0,0,0,0,0,BA9,0,0,0,0,0,0,0,0,0,0,0,0,0~
,0,0,0,0,0,0,0,0,0,0,0,0)';
      INPUT_LOAD='(-0.01,0.01)';
      PINUSE='IN';
    'PE0_RX_DN14':
      PIN_NUMBER='(0,0,0,0,0,0,0,0,0,0,0,0,0,0,0,0,AV10,0,0,0,0,0,0,0,0,0,0,0,0,~
0,0,0,0,0,0,0,0,0,0,0,0,0)';
      INPUT_LOAD='(-0.01,0.01)';
      PINUSE='IN';
    'PE0_RX_DN13':
      PIN_NUMBER='(0,0,0,0,0,0,0,0,0,0,0,0,0,0,0,0,AU9,0,0,0,0,0,0,0,0,0,0,0,0,0~
,0,0,0,0,0,0,0,0,0,0,0,0)';
      INPUT_LOAD='(-0.01,0.01)';
      PINUSE='IN';
    'PE0_RX_DN12':
      PIN_NUMBER='(0,0,0,0,0,0,0,0,0,0,0,0,0,0,0,0,AP10,0,0,0,0,0,0,0,0,0,0,0,0,~
0,0,0,0,0,0,0,0,0,0,0,0,0)';
      INPUT_LOAD='(-0.01,0.01)';
      PINUSE='IN';
    'PE0_RX_DN11':
      PIN_NUMBER='(0,0,0,0,0,0,0,0,0,0,0,0,0,0,0,0,AM10,0,0,0,0,0,0,0,0,0,0,0,0,~
0,0,0,0,0,0,0,0,0,0,0,0,0)';
      INPUT_LOAD='(-0.01,0.01)';
      PINUSE='IN';
    'PE0_RX_DN10':
      PIN_NUMBER='(0,0,0,0,0,0,0,0,0,0,0,0,0,0,0,0,AK10,0,0,0,0,0,0,0,0,0,0,0,0,~
0,0,0,0,0,0,0,0,0,0,0,0,0)';
      INPUT_LOAD='(-0.01,0.01)';
      PINUSE='IN';
    'PE0_RX_DN9':
      PIN_NUMBER='(0,0,0,0,0,0,0,0,0,0,0,0,0,0,0,0,AJ9,0,0,0,0,0,0,0,0,0,0,0,0,0~
,0,0,0,0,0,0,0,0,0,0,0,0)';
      INPUT_LOAD='(-0.01,0.01)';
      PINUSE='IN';
    'PE0_RX_DN8':
      PIN_NUMBER='(0,0,0,0,0,0,0,0,0,0,0,0,0,0,0,0,AF10,0,0,0,0,0,0,0,0,0,0,0,0,~
0,0,0,0,0,0,0,0,0,0,0,0,0)';
      INPUT_LOAD='(-0.01,0.01)';
      PINUSE='IN';
    'PE0_RX_DN7':
      PIN_NUMBER='(0,0,0,0,0,0,0,0,0,0,0,0,0,0,0,0,AE9,0,0,0,0,0,0,0,0,0,0,0,0,0~
,0,0,0,0,0,0,0,0,0,0,0,0)';
      INPUT_LOAD='(-0.01,0.01)';
      PINUSE='IN';
    'PE0_RX_DN6':
      PIN_NUMBER='(0,0,0,0,0,0,0,0,0,0,0,0,0,0,0,0,AB10,0,0,0,0,0,0,0,0,0,0,0,0,~
0,0,0,0,0,0,0,0,0,0,0,0,0)';
      INPUT_LOAD='(-0.01,0.01)';
      PINUSE='IN';
    'PE0_RX_DN5':
      PIN_NUMBER='(0,0,0,0,0,0,0,0,0,0,0,0,0,0,0,0,AA9,0,0,0,0,0,0,0,0,0,0,0,0,0~
,0,0,0,0,0,0,0,0,0,0,0,0)';
      INPUT_LOAD='(-0.01,0.01)';
      PINUSE='IN';
    'PE0_RX_DN4':
      PIN_NUMBER='(0,0,0,0,0,0,0,0,0,0,0,0,0,0,0,0,V10,0,0,0,0,0,0,0,0,0,0,0,0,0~
,0,0,0,0,0,0,0,0,0,0,0,0)';
      INPUT_LOAD='(-0.01,0.01)';
      PINUSE='IN';
    'PE0_RX_DN3':
      PIN_NUMBER='(0,0,0,0,0,0,0,0,0,0,0,0,0,0,0,0,T10,0,0,0,0,0,0,0,0,0,0,0,0,0~
,0,0,0,0,0,0,0,0,0,0,0,0)';
      INPUT_LOAD='(-0.01,0.01)';
      PINUSE='IN';
    'PE0_RX_DN2':
      PIN_NUMBER='(0,0,0,0,0,0,0,0,0,0,0,0,0,0,0,0,P10,0,0,0,0,0,0,0,0,0,0,0,0,0~
,0,0,0,0,0,0,0,0,0,0,0,0)';
      INPUT_LOAD='(-0.01,0.01)';
      PINUSE='IN';
    'PE0_RX_DN1':
      PIN_NUMBER='(0,0,0,0,0,0,0,0,0,0,0,0,0,0,0,0,M10,0,0,0,0,0,0,0,0,0,0,0,0,0~
,0,0,0,0,0,0,0,0,0,0,0,0)';
      INPUT_LOAD='(-0.01,0.01)';
      PINUSE='IN';
    'PE0_RX_DN0':
      PIN_NUMBER='(0,0,0,0,0,0,0,0,0,0,0,0,0,0,0,0,K10,0,0,0,0,0,0,0,0,0,0,0,0,0~
,0,0,0,0,0,0,0,0,0,0,0,0)';
      INPUT_LOAD='(-0.01,0.01)';
      PINUSE='IN';
    'PE0_RX_DP15':
      PIN_NUMBER='(0,0,0,0,0,0,0,0,0,0,0,0,0,0,0,0,AY10,0,0,0,0,0,0,0,0,0,0,0,0,~
0,0,0,0,0,0,0,0,0,0,0,0,0)';
      INPUT_LOAD='(-0.01,0.01)';
      PINUSE='IN';
    'PE0_RX_DP14':
      PIN_NUMBER='(0,0,0,0,0,0,0,0,0,0,0,0,0,0,0,0,AW11,0,0,0,0,0,0,0,0,0,0,0,0,~
0,0,0,0,0,0,0,0,0,0,0,0,0)';
      INPUT_LOAD='(-0.01,0.01)';
      PINUSE='IN';
    'PE0_RX_DP13':
      PIN_NUMBER='(0,0,0,0,0,0,0,0,0,0,0,0,0,0,0,0,AT10,0,0,0,0,0,0,0,0,0,0,0,0,~
0,0,0,0,0,0,0,0,0,0,0,0,0)';
      INPUT_LOAD='(-0.01,0.01)';
      PINUSE='IN';
    'PE0_RX_DP12':
      PIN_NUMBER='(0,0,0,0,0,0,0,0,0,0,0,0,0,0,0,0,AR11,0,0,0,0,0,0,0,0,0,0,0,0,~
0,0,0,0,0,0,0,0,0,0,0,0,0)';
      INPUT_LOAD='(-0.01,0.01)';
      PINUSE='IN';
    'PE0_RX_DP11':
      PIN_NUMBER='(0,0,0,0,0,0,0,0,0,0,0,0,0,0,0,0,AN9,0,0,0,0,0,0,0,0,0,0,0,0,0~
,0,0,0,0,0,0,0,0,0,0,0,0)';
      INPUT_LOAD='(-0.01,0.01)';
      PINUSE='IN';
    'PE0_RX_DP10':
      PIN_NUMBER='(0,0,0,0,0,0,0,0,0,0,0,0,0,0,0,0,AL11,0,0,0,0,0,0,0,0,0,0,0,0,~
0,0,0,0,0,0,0,0,0,0,0,0,0)';
      INPUT_LOAD='(-0.01,0.01)';
      PINUSE='IN';
    'PE0_RX_DP9':
      PIN_NUMBER='(0,0,0,0,0,0,0,0,0,0,0,0,0,0,0,0,AH10,0,0,0,0,0,0,0,0,0,0,0,0,~
0,0,0,0,0,0,0,0,0,0,0,0,0)';
      INPUT_LOAD='(-0.01,0.01)';
      PINUSE='IN';
    'PE0_RX_DP8':
      PIN_NUMBER='(0,0,0,0,0,0,0,0,0,0,0,0,0,0,0,0,AG11,0,0,0,0,0,0,0,0,0,0,0,0,~
0,0,0,0,0,0,0,0,0,0,0,0,0)';
      INPUT_LOAD='(-0.01,0.01)';
      PINUSE='IN';
    'PE0_RX_DP7':
      PIN_NUMBER='(0,0,0,0,0,0,0,0,0,0,0,0,0,0,0,0,AD10,0,0,0,0,0,0,0,0,0,0,0,0,~
0,0,0,0,0,0,0,0,0,0,0,0,0)';
      INPUT_LOAD='(-0.01,0.01)';
      PINUSE='IN';
    'PE0_RX_DP6':
      PIN_NUMBER='(0,0,0,0,0,0,0,0,0,0,0,0,0,0,0,0,AC11,0,0,0,0,0,0,0,0,0,0,0,0,~
0,0,0,0,0,0,0,0,0,0,0,0,0)';
      INPUT_LOAD='(-0.01,0.01)';
      PINUSE='IN';
    'PE0_RX_DP5':
      PIN_NUMBER='(0,0,0,0,0,0,0,0,0,0,0,0,0,0,0,0,Y10,0,0,0,0,0,0,0,0,0,0,0,0,0~
,0,0,0,0,0,0,0,0,0,0,0,0)';
      INPUT_LOAD='(-0.01,0.01)';
      PINUSE='IN';
    'PE0_RX_DP4':
      PIN_NUMBER='(0,0,0,0,0,0,0,0,0,0,0,0,0,0,0,0,W11,0,0,0,0,0,0,0,0,0,0,0,0,0~
,0,0,0,0,0,0,0,0,0,0,0,0)';
      INPUT_LOAD='(-0.01,0.01)';
      PINUSE='IN';
    'PE0_RX_DP3':
      PIN_NUMBER='(0,0,0,0,0,0,0,0,0,0,0,0,0,0,0,0,U9,0,0,0,0,0,0,0,0,0,0,0,0,0,~
0,0,0,0,0,0,0,0,0,0,0,0)';
      INPUT_LOAD='(-0.01,0.01)';
      PINUSE='IN';
    'PE0_RX_DP2':
      PIN_NUMBER='(0,0,0,0,0,0,0,0,0,0,0,0,0,0,0,0,R11,0,0,0,0,0,0,0,0,0,0,0,0,0~
,0,0,0,0,0,0,0,0,0,0,0,0)';
      INPUT_LOAD='(-0.01,0.01)';
      PINUSE='IN';
    'PE0_RX_DP1':
      PIN_NUMBER='(0,0,0,0,0,0,0,0,0,0,0,0,0,0,0,0,N9,0,0,0,0,0,0,0,0,0,0,0,0,0,~
0,0,0,0,0,0,0,0,0,0,0,0)';
      INPUT_LOAD='(-0.01,0.01)';
      PINUSE='IN';
    'PE0_RX_DP0':
      PIN_NUMBER='(0,0,0,0,0,0,0,0,0,0,0,0,0,0,0,0,L11,0,0,0,0,0,0,0,0,0,0,0,0,0~
,0,0,0,0,0,0,0,0,0,0,0,0)';
      INPUT_LOAD='(-0.01,0.01)';
      PINUSE='IN';
    'PE0_TX_DN15':
      PIN_NUMBER='(0,0,0,0,0,0,0,0,0,0,0,0,0,0,0,0,BB14,0,0,0,0,0,0,0,0,0,0,0,0,~
0,0,0,0,0,0,0,0,0,0,0,0,0)';
      OUTPUT_LOAD='(1.0,-1.0)';
      PINUSE='OUT';
    'PE0_TX_DN14':
      PIN_NUMBER='(0,0,0,0,0,0,0,0,0,0,0,0,0,0,0,0,BA13,0,0,0,0,0,0,0,0,0,0,0,0,~
0,0,0,0,0,0,0,0,0,0,0,0,0)';
      OUTPUT_LOAD='(1.0,-1.0)';
      PINUSE='OUT';
    'PE0_TX_DN13':
      PIN_NUMBER='(0,0,0,0,0,0,0,0,0,0,0,0,0,0,0,0,AV14,0,0,0,0,0,0,0,0,0,0,0,0,~
0,0,0,0,0,0,0,0,0,0,0,0,0)';
      OUTPUT_LOAD='(1.0,-1.0)';
      PINUSE='OUT';
    'PE0_TX_DN12':
      PIN_NUMBER='(0,0,0,0,0,0,0,0,0,0,0,0,0,0,0,0,AU13,0,0,0,0,0,0,0,0,0,0,0,0,~
0,0,0,0,0,0,0,0,0,0,0,0,0)';
      OUTPUT_LOAD='(1.0,-1.0)';
      PINUSE='OUT';
    'PE0_TX_DN11':
      PIN_NUMBER='(0,0,0,0,0,0,0,0,0,0,0,0,0,0,0,0,AP14,0,0,0,0,0,0,0,0,0,0,0,0,~
0,0,0,0,0,0,0,0,0,0,0,0,0)';
      OUTPUT_LOAD='(1.0,-1.0)';
      PINUSE='OUT';
    'PE0_TX_DN10':
      PIN_NUMBER='(0,0,0,0,0,0,0,0,0,0,0,0,0,0,0,0,AN13,0,0,0,0,0,0,0,0,0,0,0,0,~
0,0,0,0,0,0,0,0,0,0,0,0,0)';
      OUTPUT_LOAD='(1.0,-1.0)';
      PINUSE='OUT';
    'PE0_TX_DN9':
      PIN_NUMBER='(0,0,0,0,0,0,0,0,0,0,0,0,0,0,0,0,AK14,0,0,0,0,0,0,0,0,0,0,0,0,~
0,0,0,0,0,0,0,0,0,0,0,0,0)';
      OUTPUT_LOAD='(1.0,-1.0)';
      PINUSE='OUT';
    'PE0_TX_DN8':
      PIN_NUMBER='(0,0,0,0,0,0,0,0,0,0,0,0,0,0,0,0,AJ13,0,0,0,0,0,0,0,0,0,0,0,0,~
0,0,0,0,0,0,0,0,0,0,0,0,0)';
      OUTPUT_LOAD='(1.0,-1.0)';
      PINUSE='OUT';
    'PE0_TX_DN7':
      PIN_NUMBER='(0,0,0,0,0,0,0,0,0,0,0,0,0,0,0,0,AF14,0,0,0,0,0,0,0,0,0,0,0,0,~
0,0,0,0,0,0,0,0,0,0,0,0,0)';
      OUTPUT_LOAD='(1.0,-1.0)';
      PINUSE='OUT';
    'PE0_TX_DN6':
      PIN_NUMBER='(0,0,0,0,0,0,0,0,0,0,0,0,0,0,0,0,AE13,0,0,0,0,0,0,0,0,0,0,0,0,~
0,0,0,0,0,0,0,0,0,0,0,0,0)';
      OUTPUT_LOAD='(1.0,-1.0)';
      PINUSE='OUT';
    'PE0_TX_DN5':
      PIN_NUMBER='(0,0,0,0,0,0,0,0,0,0,0,0,0,0,0,0,AB14,0,0,0,0,0,0,0,0,0,0,0,0,~
0,0,0,0,0,0,0,0,0,0,0,0,0)';
      OUTPUT_LOAD='(1.0,-1.0)';
      PINUSE='OUT';
    'PE0_TX_DN4':
      PIN_NUMBER='(0,0,0,0,0,0,0,0,0,0,0,0,0,0,0,0,AA13,0,0,0,0,0,0,0,0,0,0,0,0,~
0,0,0,0,0,0,0,0,0,0,0,0,0)';
      OUTPUT_LOAD='(1.0,-1.0)';
      PINUSE='OUT';
    'PE0_TX_DN3':
      PIN_NUMBER='(0,0,0,0,0,0,0,0,0,0,0,0,0,0,0,0,V14,0,0,0,0,0,0,0,0,0,0,0,0,0~
,0,0,0,0,0,0,0,0,0,0,0,0)';
      OUTPUT_LOAD='(1.0,-1.0)';
      PINUSE='OUT';
    'PE0_TX_DN2':
      PIN_NUMBER='(0,0,0,0,0,0,0,0,0,0,0,0,0,0,0,0,U13,0,0,0,0,0,0,0,0,0,0,0,0,0~
,0,0,0,0,0,0,0,0,0,0,0,0)';
      OUTPUT_LOAD='(1.0,-1.0)';
      PINUSE='OUT';
    'PE0_TX_DN1':
      PIN_NUMBER='(0,0,0,0,0,0,0,0,0,0,0,0,0,0,0,0,P14,0,0,0,0,0,0,0,0,0,0,0,0,0~
,0,0,0,0,0,0,0,0,0,0,0,0)';
      OUTPUT_LOAD='(1.0,-1.0)';
      PINUSE='OUT';
    'PE0_TX_DN0':
      PIN_NUMBER='(0,0,0,0,0,0,0,0,0,0,0,0,0,0,0,0,N13,0,0,0,0,0,0,0,0,0,0,0,0,0~
,0,0,0,0,0,0,0,0,0,0,0,0)';
      OUTPUT_LOAD='(1.0,-1.0)';
      PINUSE='OUT';
    'PE0_TX_DP15':
      PIN_NUMBER='(0,0,0,0,0,0,0,0,0,0,0,0,0,0,0,0,BC15,0,0,0,0,0,0,0,0,0,0,0,0,~
0,0,0,0,0,0,0,0,0,0,0,0,0)';
      OUTPUT_LOAD='(1.0,-1.0)';
      PINUSE='OUT';
    'PE0_TX_DP14':
      PIN_NUMBER='(0,0,0,0,0,0,0,0,0,0,0,0,0,0,0,0,AY14,0,0,0,0,0,0,0,0,0,0,0,0,~
0,0,0,0,0,0,0,0,0,0,0,0,0)';
      OUTPUT_LOAD='(1.0,-1.0)';
      PINUSE='OUT';
    'PE0_TX_DP13':
      PIN_NUMBER='(0,0,0,0,0,0,0,0,0,0,0,0,0,0,0,0,AW15,0,0,0,0,0,0,0,0,0,0,0,0,~
0,0,0,0,0,0,0,0,0,0,0,0,0)';
      OUTPUT_LOAD='(1.0,-1.0)';
      PINUSE='OUT';
    'PE0_TX_DP12':
      PIN_NUMBER='(0,0,0,0,0,0,0,0,0,0,0,0,0,0,0,0,AT14,0,0,0,0,0,0,0,0,0,0,0,0,~
0,0,0,0,0,0,0,0,0,0,0,0,0)';
      OUTPUT_LOAD='(1.0,-1.0)';
      PINUSE='OUT';
    'PE0_TX_DP11':
      PIN_NUMBER='(0,0,0,0,0,0,0,0,0,0,0,0,0,0,0,0,AR15,0,0,0,0,0,0,0,0,0,0,0,0,~
0,0,0,0,0,0,0,0,0,0,0,0,0)';
      OUTPUT_LOAD='(1.0,-1.0)';
      PINUSE='OUT';
    'PE0_TX_DP10':
      PIN_NUMBER='(0,0,0,0,0,0,0,0,0,0,0,0,0,0,0,0,AM14,0,0,0,0,0,0,0,0,0,0,0,0,~
0,0,0,0,0,0,0,0,0,0,0,0,0)';
      OUTPUT_LOAD='(1.0,-1.0)';
      PINUSE='OUT';
    'PE0_TX_DP9':
      PIN_NUMBER='(0,0,0,0,0,0,0,0,0,0,0,0,0,0,0,0,AL15,0,0,0,0,0,0,0,0,0,0,0,0,~
0,0,0,0,0,0,0,0,0,0,0,0,0)';
      OUTPUT_LOAD='(1.0,-1.0)';
      PINUSE='OUT';
    'PE0_TX_DP8':
      PIN_NUMBER='(0,0,0,0,0,0,0,0,0,0,0,0,0,0,0,0,AH14,0,0,0,0,0,0,0,0,0,0,0,0,~
0,0,0,0,0,0,0,0,0,0,0,0,0)';
      OUTPUT_LOAD='(1.0,-1.0)';
      PINUSE='OUT';
    'PE0_TX_DP7':
      PIN_NUMBER='(0,0,0,0,0,0,0,0,0,0,0,0,0,0,0,0,AG15,0,0,0,0,0,0,0,0,0,0,0,0,~
0,0,0,0,0,0,0,0,0,0,0,0,0)';
      OUTPUT_LOAD='(1.0,-1.0)';
      PINUSE='OUT';
    'PE0_TX_DP6':
      PIN_NUMBER='(0,0,0,0,0,0,0,0,0,0,0,0,0,0,0,0,AD14,0,0,0,0,0,0,0,0,0,0,0,0,~
0,0,0,0,0,0,0,0,0,0,0,0,0)';
      OUTPUT_LOAD='(1.0,-1.0)';
      PINUSE='OUT';
    'PE0_TX_DP5':
      PIN_NUMBER='(0,0,0,0,0,0,0,0,0,0,0,0,0,0,0,0,AC15,0,0,0,0,0,0,0,0,0,0,0,0,~
0,0,0,0,0,0,0,0,0,0,0,0,0)';
      OUTPUT_LOAD='(1.0,-1.0)';
      PINUSE='OUT';
    'PE0_TX_DP4':
      PIN_NUMBER='(0,0,0,0,0,0,0,0,0,0,0,0,0,0,0,0,Y14,0,0,0,0,0,0,0,0,0,0,0,0,0~
,0,0,0,0,0,0,0,0,0,0,0,0)';
      OUTPUT_LOAD='(1.0,-1.0)';
      PINUSE='OUT';
    'PE0_TX_DP3':
      PIN_NUMBER='(0,0,0,0,0,0,0,0,0,0,0,0,0,0,0,0,W15,0,0,0,0,0,0,0,0,0,0,0,0,0~
,0,0,0,0,0,0,0,0,0,0,0,0)';
      OUTPUT_LOAD='(1.0,-1.0)';
      PINUSE='OUT';
    'PE0_TX_DP2':
      PIN_NUMBER='(0,0,0,0,0,0,0,0,0,0,0,0,0,0,0,0,T14,0,0,0,0,0,0,0,0,0,0,0,0,0~
,0,0,0,0,0,0,0,0,0,0,0,0)';
      OUTPUT_LOAD='(1.0,-1.0)';
      PINUSE='OUT';
    'PE0_TX_DP1':
      PIN_NUMBER='(0,0,0,0,0,0,0,0,0,0,0,0,0,0,0,0,R15,0,0,0,0,0,0,0,0,0,0,0,0,0~
,0,0,0,0,0,0,0,0,0,0,0,0)';
      OUTPUT_LOAD='(1.0,-1.0)';
      PINUSE='OUT';
    'PE0_TX_DP0':
      PIN_NUMBER='(0,0,0,0,0,0,0,0,0,0,0,0,0,0,0,0,M14,0,0,0,0,0,0,0,0,0,0,0,0,0~
,0,0,0,0,0,0,0,0,0,0,0,0)';
      OUTPUT_LOAD='(1.0,-1.0)';
      PINUSE='OUT';
    'PE1_RX_DN15':
      PIN_NUMBER='(0,0,0,0,0,0,0,0,0,0,0,0,0,0,0,0,0,BC11,0,0,0,0,0,0,0,0,0,0,0,~
0,0,0,0,0,0,0,0,0,0,0,0,0)';
      INPUT_LOAD='(-0.01,0.01)';
      PINUSE='IN';
    'PE1_RX_DN14':
      PIN_NUMBER='(0,0,0,0,0,0,0,0,0,0,0,0,0,0,0,0,0,BF10,0,0,0,0,0,0,0,0,0,0,0,~
0,0,0,0,0,0,0,0,0,0,0,0,0)';
      INPUT_LOAD='(-0.01,0.01)';
      PINUSE='IN';
    'PE1_RX_DN13':
      PIN_NUMBER='(0,0,0,0,0,0,0,0,0,0,0,0,0,0,0,0,0,BG11,0,0,0,0,0,0,0,0,0,0,0,~
0,0,0,0,0,0,0,0,0,0,0,0,0)';
      INPUT_LOAD='(-0.01,0.01)';
      PINUSE='IN';
    'PE1_RX_DN12':
      PIN_NUMBER='(0,0,0,0,0,0,0,0,0,0,0,0,0,0,0,0,0,BK10,0,0,0,0,0,0,0,0,0,0,0,~
0,0,0,0,0,0,0,0,0,0,0,0,0)';
      INPUT_LOAD='(-0.01,0.01)';
      PINUSE='IN';
    'PE1_RX_DN11':
      PIN_NUMBER='(0,0,0,0,0,0,0,0,0,0,0,0,0,0,0,0,0,BL11,0,0,0,0,0,0,0,0,0,0,0,~
0,0,0,0,0,0,0,0,0,0,0,0,0)';
      INPUT_LOAD='(-0.01,0.01)';
      PINUSE='IN';
    'PE1_RX_DN10':
      PIN_NUMBER='(0,0,0,0,0,0,0,0,0,0,0,0,0,0,0,0,0,BP10,0,0,0,0,0,0,0,0,0,0,0,~
0,0,0,0,0,0,0,0,0,0,0,0,0)';
      INPUT_LOAD='(-0.01,0.01)';
      PINUSE='IN';
    'PE1_RX_DN9':
      PIN_NUMBER='(0,0,0,0,0,0,0,0,0,0,0,0,0,0,0,0,0,BR11,0,0,0,0,0,0,0,0,0,0,0,~
0,0,0,0,0,0,0,0,0,0,0,0,0)';
      INPUT_LOAD='(-0.01,0.01)';
      PINUSE='IN';
    'PE1_RX_DN8':
      PIN_NUMBER='(0,0,0,0,0,0,0,0,0,0,0,0,0,0,0,0,0,BV10,0,0,0,0,0,0,0,0,0,0,0,~
0,0,0,0,0,0,0,0,0,0,0,0,0)';
      INPUT_LOAD='(-0.01,0.01)';
      PINUSE='IN';
    'PE1_RX_DN7':
      PIN_NUMBER='(0,0,0,0,0,0,0,0,0,0,0,0,0,0,0,0,0,BW11,0,0,0,0,0,0,0,0,0,0,0,~
0,0,0,0,0,0,0,0,0,0,0,0,0)';
      INPUT_LOAD='(-0.01,0.01)';
      PINUSE='IN';
    'PE1_RX_DN6':
      PIN_NUMBER='(0,0,0,0,0,0,0,0,0,0,0,0,0,0,0,0,0,CB10,0,0,0,0,0,0,0,0,0,0,0,~
0,0,0,0,0,0,0,0,0,0,0,0,0)';
      INPUT_LOAD='(-0.01,0.01)';
      PINUSE='IN';
    'PE1_RX_DN5':
      PIN_NUMBER='(0,0,0,0,0,0,0,0,0,0,0,0,0,0,0,0,0,CC11,0,0,0,0,0,0,0,0,0,0,0,~
0,0,0,0,0,0,0,0,0,0,0,0,0)';
      INPUT_LOAD='(-0.01,0.01)';
      PINUSE='IN';
    'PE1_RX_DN4':
      PIN_NUMBER='(0,0,0,0,0,0,0,0,0,0,0,0,0,0,0,0,0,CF10,0,0,0,0,0,0,0,0,0,0,0,~
0,0,0,0,0,0,0,0,0,0,0,0,0)';
      INPUT_LOAD='(-0.01,0.01)';
      PINUSE='IN';
    'PE1_RX_DN3':
      PIN_NUMBER='(0,0,0,0,0,0,0,0,0,0,0,0,0,0,0,0,0,CG11,0,0,0,0,0,0,0,0,0,0,0,~
0,0,0,0,0,0,0,0,0,0,0,0,0)';
      INPUT_LOAD='(-0.01,0.01)';
      PINUSE='IN';
    'PE1_RX_DN2':
      PIN_NUMBER='(0,0,0,0,0,0,0,0,0,0,0,0,0,0,0,0,0,CK10,0,0,0,0,0,0,0,0,0,0,0,~
0,0,0,0,0,0,0,0,0,0,0,0,0)';
      INPUT_LOAD='(-0.01,0.01)';
      PINUSE='IN';
    'PE1_RX_DN1':
      PIN_NUMBER='(0,0,0,0,0,0,0,0,0,0,0,0,0,0,0,0,0,CL11,0,0,0,0,0,0,0,0,0,0,0,~
0,0,0,0,0,0,0,0,0,0,0,0,0)';
      INPUT_LOAD='(-0.01,0.01)';
      PINUSE='IN';
    'PE1_RX_DN0':
      PIN_NUMBER='(0,0,0,0,0,0,0,0,0,0,0,0,0,0,0,0,0,CP10,0,0,0,0,0,0,0,0,0,0,0,~
0,0,0,0,0,0,0,0,0,0,0,0,0)';
      INPUT_LOAD='(-0.01,0.01)';
      PINUSE='IN';
    'PE1_RX_DP15':
      PIN_NUMBER='(0,0,0,0,0,0,0,0,0,0,0,0,0,0,0,0,0,BD10,0,0,0,0,0,0,0,0,0,0,0,~
0,0,0,0,0,0,0,0,0,0,0,0,0)';
      INPUT_LOAD='(-0.01,0.01)';
      PINUSE='IN';
    'PE1_RX_DP14':
      PIN_NUMBER='(0,0,0,0,0,0,0,0,0,0,0,0,0,0,0,0,0,BE9,0,0,0,0,0,0,0,0,0,0,0,0~
,0,0,0,0,0,0,0,0,0,0,0,0)';
      INPUT_LOAD='(-0.01,0.01)';
      PINUSE='IN';
    'PE1_RX_DP13':
      PIN_NUMBER='(0,0,0,0,0,0,0,0,0,0,0,0,0,0,0,0,0,BH10,0,0,0,0,0,0,0,0,0,0,0,~
0,0,0,0,0,0,0,0,0,0,0,0,0)';
      INPUT_LOAD='(-0.01,0.01)';
      PINUSE='IN';
    'PE1_RX_DP12':
      PIN_NUMBER='(0,0,0,0,0,0,0,0,0,0,0,0,0,0,0,0,0,BJ9,0,0,0,0,0,0,0,0,0,0,0,0~
,0,0,0,0,0,0,0,0,0,0,0,0)';
      INPUT_LOAD='(-0.01,0.01)';
      PINUSE='IN';
    'PE1_RX_DP11':
      PIN_NUMBER='(0,0,0,0,0,0,0,0,0,0,0,0,0,0,0,0,0,BM10,0,0,0,0,0,0,0,0,0,0,0,~
0,0,0,0,0,0,0,0,0,0,0,0,0)';
      INPUT_LOAD='(-0.01,0.01)';
      PINUSE='IN';
    'PE1_RX_DP10':
      PIN_NUMBER='(0,0,0,0,0,0,0,0,0,0,0,0,0,0,0,0,0,BN9,0,0,0,0,0,0,0,0,0,0,0,0~
,0,0,0,0,0,0,0,0,0,0,0,0)';
      INPUT_LOAD='(-0.01,0.01)';
      PINUSE='IN';
    'PE1_RX_DP9':
      PIN_NUMBER='(0,0,0,0,0,0,0,0,0,0,0,0,0,0,0,0,0,BT10,0,0,0,0,0,0,0,0,0,0,0,~
0,0,0,0,0,0,0,0,0,0,0,0,0)';
      INPUT_LOAD='(-0.01,0.01)';
      PINUSE='IN';
    'PE1_RX_DP8':
      PIN_NUMBER='(0,0,0,0,0,0,0,0,0,0,0,0,0,0,0,0,0,BU9,0,0,0,0,0,0,0,0,0,0,0,0~
,0,0,0,0,0,0,0,0,0,0,0,0)';
      INPUT_LOAD='(-0.01,0.01)';
      PINUSE='IN';
    'PE1_RX_DP7':
      PIN_NUMBER='(0,0,0,0,0,0,0,0,0,0,0,0,0,0,0,0,0,BY10,0,0,0,0,0,0,0,0,0,0,0,~
0,0,0,0,0,0,0,0,0,0,0,0,0)';
      INPUT_LOAD='(-0.01,0.01)';
      PINUSE='IN';
    'PE1_RX_DP6':
      PIN_NUMBER='(0,0,0,0,0,0,0,0,0,0,0,0,0,0,0,0,0,CA9,0,0,0,0,0,0,0,0,0,0,0,0~
,0,0,0,0,0,0,0,0,0,0,0,0)';
      INPUT_LOAD='(-0.01,0.01)';
      PINUSE='IN';
    'PE1_RX_DP5':
      PIN_NUMBER='(0,0,0,0,0,0,0,0,0,0,0,0,0,0,0,0,0,CD10,0,0,0,0,0,0,0,0,0,0,0,~
0,0,0,0,0,0,0,0,0,0,0,0,0)';
      INPUT_LOAD='(-0.01,0.01)';
      PINUSE='IN';
    'PE1_RX_DP4':
      PIN_NUMBER='(0,0,0,0,0,0,0,0,0,0,0,0,0,0,0,0,0,CE9,0,0,0,0,0,0,0,0,0,0,0,0~
,0,0,0,0,0,0,0,0,0,0,0,0)';
      INPUT_LOAD='(-0.01,0.01)';
      PINUSE='IN';
    'PE1_RX_DP3':
      PIN_NUMBER='(0,0,0,0,0,0,0,0,0,0,0,0,0,0,0,0,0,CH10,0,0,0,0,0,0,0,0,0,0,0,~
0,0,0,0,0,0,0,0,0,0,0,0,0)';
      INPUT_LOAD='(-0.01,0.01)';
      PINUSE='IN';
    'PE1_RX_DP2':
      PIN_NUMBER='(0,0,0,0,0,0,0,0,0,0,0,0,0,0,0,0,0,CJ9,0,0,0,0,0,0,0,0,0,0,0,0~
,0,0,0,0,0,0,0,0,0,0,0,0)';
      INPUT_LOAD='(-0.01,0.01)';
      PINUSE='IN';
    'PE1_RX_DP1':
      PIN_NUMBER='(0,0,0,0,0,0,0,0,0,0,0,0,0,0,0,0,0,CM10,0,0,0,0,0,0,0,0,0,0,0,~
0,0,0,0,0,0,0,0,0,0,0,0,0)';
      INPUT_LOAD='(-0.01,0.01)';
      PINUSE='IN';
    'PE1_RX_DP0':
      PIN_NUMBER='(0,0,0,0,0,0,0,0,0,0,0,0,0,0,0,0,0,CN9,0,0,0,0,0,0,0,0,0,0,0,0~
,0,0,0,0,0,0,0,0,0,0,0,0)';
      INPUT_LOAD='(-0.01,0.01)';
      PINUSE='IN';
    'PE1_TX_DN15':
      PIN_NUMBER='(0,0,0,0,0,0,0,0,0,0,0,0,0,0,0,0,0,BE13,0,0,0,0,0,0,0,0,0,0,0,~
0,0,0,0,0,0,0,0,0,0,0,0,0)';
      OUTPUT_LOAD='(1.0,-1.0)';
      PINUSE='OUT';
    'PE1_TX_DN14':
      PIN_NUMBER='(0,0,0,0,0,0,0,0,0,0,0,0,0,0,0,0,0,BF14,0,0,0,0,0,0,0,0,0,0,0,~
0,0,0,0,0,0,0,0,0,0,0,0,0)';
      OUTPUT_LOAD='(1.0,-1.0)';
      PINUSE='OUT';
    'PE1_TX_DN13':
      PIN_NUMBER='(0,0,0,0,0,0,0,0,0,0,0,0,0,0,0,0,0,BJ13,0,0,0,0,0,0,0,0,0,0,0,~
0,0,0,0,0,0,0,0,0,0,0,0,0)';
      OUTPUT_LOAD='(1.0,-1.0)';
      PINUSE='OUT';
    'PE1_TX_DN12':
      PIN_NUMBER='(0,0,0,0,0,0,0,0,0,0,0,0,0,0,0,0,0,BK14,0,0,0,0,0,0,0,0,0,0,0,~
0,0,0,0,0,0,0,0,0,0,0,0,0)';
      OUTPUT_LOAD='(1.0,-1.0)';
      PINUSE='OUT';
    'PE1_TX_DN11':
      PIN_NUMBER='(0,0,0,0,0,0,0,0,0,0,0,0,0,0,0,0,0,BN13,0,0,0,0,0,0,0,0,0,0,0,~
0,0,0,0,0,0,0,0,0,0,0,0,0)';
      OUTPUT_LOAD='(1.0,-1.0)';
      PINUSE='OUT';
    'PE1_TX_DN10':
      PIN_NUMBER='(0,0,0,0,0,0,0,0,0,0,0,0,0,0,0,0,0,BP14,0,0,0,0,0,0,0,0,0,0,0,~
0,0,0,0,0,0,0,0,0,0,0,0,0)';
      OUTPUT_LOAD='(1.0,-1.0)';
      PINUSE='OUT';
    'PE1_TX_DN9':
      PIN_NUMBER='(0,0,0,0,0,0,0,0,0,0,0,0,0,0,0,0,0,BU13,0,0,0,0,0,0,0,0,0,0,0,~
0,0,0,0,0,0,0,0,0,0,0,0,0)';
      OUTPUT_LOAD='(1.0,-1.0)';
      PINUSE='OUT';
    'PE1_TX_DN8':
      PIN_NUMBER='(0,0,0,0,0,0,0,0,0,0,0,0,0,0,0,0,0,BV14,0,0,0,0,0,0,0,0,0,0,0,~
0,0,0,0,0,0,0,0,0,0,0,0,0)';
      OUTPUT_LOAD='(1.0,-1.0)';
      PINUSE='OUT';
    'PE1_TX_DN7':
      PIN_NUMBER='(0,0,0,0,0,0,0,0,0,0,0,0,0,0,0,0,0,CA13,0,0,0,0,0,0,0,0,0,0,0,~
0,0,0,0,0,0,0,0,0,0,0,0,0)';
      OUTPUT_LOAD='(1.0,-1.0)';
      PINUSE='OUT';
    'PE1_TX_DN6':
      PIN_NUMBER='(0,0,0,0,0,0,0,0,0,0,0,0,0,0,0,0,0,CB14,0,0,0,0,0,0,0,0,0,0,0,~
0,0,0,0,0,0,0,0,0,0,0,0,0)';
      OUTPUT_LOAD='(1.0,-1.0)';
      PINUSE='OUT';
    'PE1_TX_DN5':
      PIN_NUMBER='(0,0,0,0,0,0,0,0,0,0,0,0,0,0,0,0,0,CE13,0,0,0,0,0,0,0,0,0,0,0,~
0,0,0,0,0,0,0,0,0,0,0,0,0)';
      OUTPUT_LOAD='(1.0,-1.0)';
      PINUSE='OUT';
    'PE1_TX_DN4':
      PIN_NUMBER='(0,0,0,0,0,0,0,0,0,0,0,0,0,0,0,0,0,CF14,0,0,0,0,0,0,0,0,0,0,0,~
0,0,0,0,0,0,0,0,0,0,0,0,0)';
      OUTPUT_LOAD='(1.0,-1.0)';
      PINUSE='OUT';
    'PE1_TX_DN3':
      PIN_NUMBER='(0,0,0,0,0,0,0,0,0,0,0,0,0,0,0,0,0,CJ13,0,0,0,0,0,0,0,0,0,0,0,~
0,0,0,0,0,0,0,0,0,0,0,0,0)';
      OUTPUT_LOAD='(1.0,-1.0)';
      PINUSE='OUT';
    'PE1_TX_DN2':
      PIN_NUMBER='(0,0,0,0,0,0,0,0,0,0,0,0,0,0,0,0,0,CK14,0,0,0,0,0,0,0,0,0,0,0,~
0,0,0,0,0,0,0,0,0,0,0,0,0)';
      OUTPUT_LOAD='(1.0,-1.0)';
      PINUSE='OUT';
    'PE1_TX_DN1':
      PIN_NUMBER='(0,0,0,0,0,0,0,0,0,0,0,0,0,0,0,0,0,CN13,0,0,0,0,0,0,0,0,0,0,0,~
0,0,0,0,0,0,0,0,0,0,0,0,0)';
      OUTPUT_LOAD='(1.0,-1.0)';
      PINUSE='OUT';
    'PE1_TX_DN0':
      PIN_NUMBER='(0,0,0,0,0,0,0,0,0,0,0,0,0,0,0,0,0,CP14,0,0,0,0,0,0,0,0,0,0,0,~
0,0,0,0,0,0,0,0,0,0,0,0,0)';
      OUTPUT_LOAD='(1.0,-1.0)';
      PINUSE='OUT';
    'PE1_TX_DP15':
      PIN_NUMBER='(0,0,0,0,0,0,0,0,0,0,0,0,0,0,0,0,0,BD14,0,0,0,0,0,0,0,0,0,0,0,~
0,0,0,0,0,0,0,0,0,0,0,0,0)';
      OUTPUT_LOAD='(1.0,-1.0)';
      PINUSE='OUT';
    'PE1_TX_DP14':
      PIN_NUMBER='(0,0,0,0,0,0,0,0,0,0,0,0,0,0,0,0,0,BG15,0,0,0,0,0,0,0,0,0,0,0,~
0,0,0,0,0,0,0,0,0,0,0,0,0)';
      OUTPUT_LOAD='(1.0,-1.0)';
      PINUSE='OUT';
    'PE1_TX_DP13':
      PIN_NUMBER='(0,0,0,0,0,0,0,0,0,0,0,0,0,0,0,0,0,BH14,0,0,0,0,0,0,0,0,0,0,0,~
0,0,0,0,0,0,0,0,0,0,0,0,0)';
      OUTPUT_LOAD='(1.0,-1.0)';
      PINUSE='OUT';
    'PE1_TX_DP12':
      PIN_NUMBER='(0,0,0,0,0,0,0,0,0,0,0,0,0,0,0,0,0,BL15,0,0,0,0,0,0,0,0,0,0,0,~
0,0,0,0,0,0,0,0,0,0,0,0,0)';
      OUTPUT_LOAD='(1.0,-1.0)';
      PINUSE='OUT';
    'PE1_TX_DP11':
      PIN_NUMBER='(0,0,0,0,0,0,0,0,0,0,0,0,0,0,0,0,0,BM14,0,0,0,0,0,0,0,0,0,0,0,~
0,0,0,0,0,0,0,0,0,0,0,0,0)';
      OUTPUT_LOAD='(1.0,-1.0)';
      PINUSE='OUT';
    'PE1_TX_DP10':
      PIN_NUMBER='(0,0,0,0,0,0,0,0,0,0,0,0,0,0,0,0,0,BR15,0,0,0,0,0,0,0,0,0,0,0,~
0,0,0,0,0,0,0,0,0,0,0,0,0)';
      OUTPUT_LOAD='(1.0,-1.0)';
      PINUSE='OUT';
    'PE1_TX_DP9':
      PIN_NUMBER='(0,0,0,0,0,0,0,0,0,0,0,0,0,0,0,0,0,BT14,0,0,0,0,0,0,0,0,0,0,0,~
0,0,0,0,0,0,0,0,0,0,0,0,0)';
      OUTPUT_LOAD='(1.0,-1.0)';
      PINUSE='OUT';
    'PE1_TX_DP8':
      PIN_NUMBER='(0,0,0,0,0,0,0,0,0,0,0,0,0,0,0,0,0,BW15,0,0,0,0,0,0,0,0,0,0,0,~
0,0,0,0,0,0,0,0,0,0,0,0,0)';
      OUTPUT_LOAD='(1.0,-1.0)';
      PINUSE='OUT';
    'PE1_TX_DP7':
      PIN_NUMBER='(0,0,0,0,0,0,0,0,0,0,0,0,0,0,0,0,0,BY14,0,0,0,0,0,0,0,0,0,0,0,~
0,0,0,0,0,0,0,0,0,0,0,0,0)';
      OUTPUT_LOAD='(1.0,-1.0)';
      PINUSE='OUT';
    'PE1_TX_DP6':
      PIN_NUMBER='(0,0,0,0,0,0,0,0,0,0,0,0,0,0,0,0,0,CC15,0,0,0,0,0,0,0,0,0,0,0,~
0,0,0,0,0,0,0,0,0,0,0,0,0)';
      OUTPUT_LOAD='(1.0,-1.0)';
      PINUSE='OUT';
    'PE1_TX_DP5':
      PIN_NUMBER='(0,0,0,0,0,0,0,0,0,0,0,0,0,0,0,0,0,CD14,0,0,0,0,0,0,0,0,0,0,0,~
0,0,0,0,0,0,0,0,0,0,0,0,0)';
      OUTPUT_LOAD='(1.0,-1.0)';
      PINUSE='OUT';
    'PE1_TX_DP4':
      PIN_NUMBER='(0,0,0,0,0,0,0,0,0,0,0,0,0,0,0,0,0,CG15,0,0,0,0,0,0,0,0,0,0,0,~
0,0,0,0,0,0,0,0,0,0,0,0,0)';
      OUTPUT_LOAD='(1.0,-1.0)';
      PINUSE='OUT';
    'PE1_TX_DP3':
      PIN_NUMBER='(0,0,0,0,0,0,0,0,0,0,0,0,0,0,0,0,0,CH14,0,0,0,0,0,0,0,0,0,0,0,~
0,0,0,0,0,0,0,0,0,0,0,0,0)';
      OUTPUT_LOAD='(1.0,-1.0)';
      PINUSE='OUT';
    'PE1_TX_DP2':
      PIN_NUMBER='(0,0,0,0,0,0,0,0,0,0,0,0,0,0,0,0,0,CL15,0,0,0,0,0,0,0,0,0,0,0,~
0,0,0,0,0,0,0,0,0,0,0,0,0)';
      OUTPUT_LOAD='(1.0,-1.0)';
      PINUSE='OUT';
    'PE1_TX_DP1':
      PIN_NUMBER='(0,0,0,0,0,0,0,0,0,0,0,0,0,0,0,0,0,CM14,0,0,0,0,0,0,0,0,0,0,0,~
0,0,0,0,0,0,0,0,0,0,0,0,0)';
      OUTPUT_LOAD='(1.0,-1.0)';
      PINUSE='OUT';
    'PE1_TX_DP0':
      PIN_NUMBER='(0,0,0,0,0,0,0,0,0,0,0,0,0,0,0,0,0,CR15,0,0,0,0,0,0,0,0,0,0,0,~
0,0,0,0,0,0,0,0,0,0,0,0,0)';
      OUTPUT_LOAD='(1.0,-1.0)';
      PINUSE='OUT';
    'PE2_RX_DN15':
      PIN_NUMBER='(0,0,0,0,0,0,0,0,0,0,0,0,0,0,0,0,0,0,EH10,0,0,0,0,0,0,0,0,0,0,~
0,0,0,0,0,0,0,0,0,0,0,0,0)';
      INPUT_LOAD='(-0.01,0.01)';
      PINUSE='IN';
    'PE2_RX_DN14':
      PIN_NUMBER='(0,0,0,0,0,0,0,0,0,0,0,0,0,0,0,0,0,0,EE9,0,0,0,0,0,0,0,0,0,0,0~
,0,0,0,0,0,0,0,0,0,0,0,0)';
      INPUT_LOAD='(-0.01,0.01)';
      PINUSE='IN';
    'PE2_RX_DN13':
      PIN_NUMBER='(0,0,0,0,0,0,0,0,0,0,0,0,0,0,0,0,0,0,ED10,0,0,0,0,0,0,0,0,0,0,~
0,0,0,0,0,0,0,0,0,0,0,0,0)';
      INPUT_LOAD='(-0.01,0.01)';
      PINUSE='IN';
    'PE2_RX_DN12':
      PIN_NUMBER='(0,0,0,0,0,0,0,0,0,0,0,0,0,0,0,0,0,0,EA9,0,0,0,0,0,0,0,0,0,0,0~
,0,0,0,0,0,0,0,0,0,0,0,0)';
      INPUT_LOAD='(-0.01,0.01)';
      PINUSE='IN';
    'PE2_RX_DN11':
      PIN_NUMBER='(0,0,0,0,0,0,0,0,0,0,0,0,0,0,0,0,0,0,DY10,0,0,0,0,0,0,0,0,0,0,~
0,0,0,0,0,0,0,0,0,0,0,0,0)';
      INPUT_LOAD='(-0.01,0.01)';
      PINUSE='IN';
    'PE2_RX_DN10':
      PIN_NUMBER='(0,0,0,0,0,0,0,0,0,0,0,0,0,0,0,0,0,0,DU9,0,0,0,0,0,0,0,0,0,0,0~
,0,0,0,0,0,0,0,0,0,0,0,0)';
      INPUT_LOAD='(-0.01,0.01)';
      PINUSE='IN';
    'PE2_RX_DN9':
      PIN_NUMBER='(0,0,0,0,0,0,0,0,0,0,0,0,0,0,0,0,0,0,DT10,0,0,0,0,0,0,0,0,0,0,~
0,0,0,0,0,0,0,0,0,0,0,0,0)';
      INPUT_LOAD='(-0.01,0.01)';
      PINUSE='IN';
    'PE2_RX_DN8':
      PIN_NUMBER='(0,0,0,0,0,0,0,0,0,0,0,0,0,0,0,0,0,0,DN9,0,0,0,0,0,0,0,0,0,0,0~
,0,0,0,0,0,0,0,0,0,0,0,0)';
      INPUT_LOAD='(-0.01,0.01)';
      PINUSE='IN';
    'PE2_RX_DN7':
      PIN_NUMBER='(0,0,0,0,0,0,0,0,0,0,0,0,0,0,0,0,0,0,DM10,0,0,0,0,0,0,0,0,0,0,~
0,0,0,0,0,0,0,0,0,0,0,0,0)';
      INPUT_LOAD='(-0.01,0.01)';
      PINUSE='IN';
    'PE2_RX_DN6':
      PIN_NUMBER='(0,0,0,0,0,0,0,0,0,0,0,0,0,0,0,0,0,0,DJ9,0,0,0,0,0,0,0,0,0,0,0~
,0,0,0,0,0,0,0,0,0,0,0,0)';
      INPUT_LOAD='(-0.01,0.01)';
      PINUSE='IN';
    'PE2_RX_DN5':
      PIN_NUMBER='(0,0,0,0,0,0,0,0,0,0,0,0,0,0,0,0,0,0,DH10,0,0,0,0,0,0,0,0,0,0,~
0,0,0,0,0,0,0,0,0,0,0,0,0)';
      INPUT_LOAD='(-0.01,0.01)';
      PINUSE='IN';
    'PE2_RX_DN4':
      PIN_NUMBER='(0,0,0,0,0,0,0,0,0,0,0,0,0,0,0,0,0,0,DE9,0,0,0,0,0,0,0,0,0,0,0~
,0,0,0,0,0,0,0,0,0,0,0,0)';
      INPUT_LOAD='(-0.01,0.01)';
      PINUSE='IN';
    'PE2_RX_DN3':
      PIN_NUMBER='(0,0,0,0,0,0,0,0,0,0,0,0,0,0,0,0,0,0,DD10,0,0,0,0,0,0,0,0,0,0,~
0,0,0,0,0,0,0,0,0,0,0,0,0)';
      INPUT_LOAD='(-0.01,0.01)';
      PINUSE='IN';
    'PE2_RX_DN2':
      PIN_NUMBER='(0,0,0,0,0,0,0,0,0,0,0,0,0,0,0,0,0,0,DA9,0,0,0,0,0,0,0,0,0,0,0~
,0,0,0,0,0,0,0,0,0,0,0,0)';
      INPUT_LOAD='(-0.01,0.01)';
      PINUSE='IN';
    'PE2_RX_DN1':
      PIN_NUMBER='(0,0,0,0,0,0,0,0,0,0,0,0,0,0,0,0,0,0,CY10,0,0,0,0,0,0,0,0,0,0,~
0,0,0,0,0,0,0,0,0,0,0,0,0)';
      INPUT_LOAD='(-0.01,0.01)';
      PINUSE='IN';
    'PE2_RX_DN0':
      PIN_NUMBER='(0,0,0,0,0,0,0,0,0,0,0,0,0,0,0,0,0,0,CU9,0,0,0,0,0,0,0,0,0,0,0~
,0,0,0,0,0,0,0,0,0,0,0,0)';
      INPUT_LOAD='(-0.01,0.01)';
      PINUSE='IN';
    'PE2_RX_DP15':
      PIN_NUMBER='(0,0,0,0,0,0,0,0,0,0,0,0,0,0,0,0,0,0,EG11,0,0,0,0,0,0,0,0,0,0,~
0,0,0,0,0,0,0,0,0,0,0,0,0)';
      INPUT_LOAD='(-0.01,0.01)';
      PINUSE='IN';
    'PE2_RX_DP14':
      PIN_NUMBER='(0,0,0,0,0,0,0,0,0,0,0,0,0,0,0,0,0,0,EF10,0,0,0,0,0,0,0,0,0,0,~
0,0,0,0,0,0,0,0,0,0,0,0,0)';
      INPUT_LOAD='(-0.01,0.01)';
      PINUSE='IN';
    'PE2_RX_DP13':
      PIN_NUMBER='(0,0,0,0,0,0,0,0,0,0,0,0,0,0,0,0,0,0,EC11,0,0,0,0,0,0,0,0,0,0,~
0,0,0,0,0,0,0,0,0,0,0,0,0)';
      INPUT_LOAD='(-0.01,0.01)';
      PINUSE='IN';
    'PE2_RX_DP12':
      PIN_NUMBER='(0,0,0,0,0,0,0,0,0,0,0,0,0,0,0,0,0,0,EB10,0,0,0,0,0,0,0,0,0,0,~
0,0,0,0,0,0,0,0,0,0,0,0,0)';
      INPUT_LOAD='(-0.01,0.01)';
      PINUSE='IN';
    'PE2_RX_DP11':
      PIN_NUMBER='(0,0,0,0,0,0,0,0,0,0,0,0,0,0,0,0,0,0,DW11,0,0,0,0,0,0,0,0,0,0,~
0,0,0,0,0,0,0,0,0,0,0,0,0)';
      INPUT_LOAD='(-0.01,0.01)';
      PINUSE='IN';
    'PE2_RX_DP10':
      PIN_NUMBER='(0,0,0,0,0,0,0,0,0,0,0,0,0,0,0,0,0,0,DV10,0,0,0,0,0,0,0,0,0,0,~
0,0,0,0,0,0,0,0,0,0,0,0,0)';
      INPUT_LOAD='(-0.01,0.01)';
      PINUSE='IN';
    'PE2_RX_DP9':
      PIN_NUMBER='(0,0,0,0,0,0,0,0,0,0,0,0,0,0,0,0,0,0,DR11,0,0,0,0,0,0,0,0,0,0,~
0,0,0,0,0,0,0,0,0,0,0,0,0)';
      INPUT_LOAD='(-0.01,0.01)';
      PINUSE='IN';
    'PE2_RX_DP8':
      PIN_NUMBER='(0,0,0,0,0,0,0,0,0,0,0,0,0,0,0,0,0,0,DP10,0,0,0,0,0,0,0,0,0,0,~
0,0,0,0,0,0,0,0,0,0,0,0,0)';
      INPUT_LOAD='(-0.01,0.01)';
      PINUSE='IN';
    'PE2_RX_DP7':
      PIN_NUMBER='(0,0,0,0,0,0,0,0,0,0,0,0,0,0,0,0,0,0,DL11,0,0,0,0,0,0,0,0,0,0,~
0,0,0,0,0,0,0,0,0,0,0,0,0)';
      INPUT_LOAD='(-0.01,0.01)';
      PINUSE='IN';
    'PE2_RX_DP6':
      PIN_NUMBER='(0,0,0,0,0,0,0,0,0,0,0,0,0,0,0,0,0,0,DK10,0,0,0,0,0,0,0,0,0,0,~
0,0,0,0,0,0,0,0,0,0,0,0,0)';
      INPUT_LOAD='(-0.01,0.01)';
      PINUSE='IN';
    'PE2_RX_DP5':
      PIN_NUMBER='(0,0,0,0,0,0,0,0,0,0,0,0,0,0,0,0,0,0,DG11,0,0,0,0,0,0,0,0,0,0,~
0,0,0,0,0,0,0,0,0,0,0,0,0)';
      INPUT_LOAD='(-0.01,0.01)';
      PINUSE='IN';
    'PE2_RX_DP4':
      PIN_NUMBER='(0,0,0,0,0,0,0,0,0,0,0,0,0,0,0,0,0,0,DF10,0,0,0,0,0,0,0,0,0,0,~
0,0,0,0,0,0,0,0,0,0,0,0,0)';
      INPUT_LOAD='(-0.01,0.01)';
      PINUSE='IN';
    'PE2_RX_DP3':
      PIN_NUMBER='(0,0,0,0,0,0,0,0,0,0,0,0,0,0,0,0,0,0,DC11,0,0,0,0,0,0,0,0,0,0,~
0,0,0,0,0,0,0,0,0,0,0,0,0)';
      INPUT_LOAD='(-0.01,0.01)';
      PINUSE='IN';
    'PE2_RX_DP2':
      PIN_NUMBER='(0,0,0,0,0,0,0,0,0,0,0,0,0,0,0,0,0,0,DB10,0,0,0,0,0,0,0,0,0,0,~
0,0,0,0,0,0,0,0,0,0,0,0,0)';
      INPUT_LOAD='(-0.01,0.01)';
      PINUSE='IN';
    'PE2_RX_DP1':
      PIN_NUMBER='(0,0,0,0,0,0,0,0,0,0,0,0,0,0,0,0,0,0,CW11,0,0,0,0,0,0,0,0,0,0,~
0,0,0,0,0,0,0,0,0,0,0,0,0)';
      INPUT_LOAD='(-0.01,0.01)';
      PINUSE='IN';
    'PE2_RX_DP0':
      PIN_NUMBER='(0,0,0,0,0,0,0,0,0,0,0,0,0,0,0,0,0,0,CV10,0,0,0,0,0,0,0,0,0,0,~
0,0,0,0,0,0,0,0,0,0,0,0,0)';
      INPUT_LOAD='(-0.01,0.01)';
      PINUSE='IN';
    'PE2_TX_DN15':
      PIN_NUMBER='(0,0,0,0,0,0,0,0,0,0,0,0,0,0,0,0,0,0,EF14,0,0,0,0,0,0,0,0,0,0,~
0,0,0,0,0,0,0,0,0,0,0,0,0)';
      OUTPUT_LOAD='(1.0,-1.0)';
      PINUSE='OUT';
    'PE2_TX_DN14':
      PIN_NUMBER='(0,0,0,0,0,0,0,0,0,0,0,0,0,0,0,0,0,0,EE13,0,0,0,0,0,0,0,0,0,0,~
0,0,0,0,0,0,0,0,0,0,0,0,0)';
      OUTPUT_LOAD='(1.0,-1.0)';
      PINUSE='OUT';
    'PE2_TX_DN13':
      PIN_NUMBER='(0,0,0,0,0,0,0,0,0,0,0,0,0,0,0,0,0,0,EB14,0,0,0,0,0,0,0,0,0,0,~
0,0,0,0,0,0,0,0,0,0,0,0,0)';
      OUTPUT_LOAD='(1.0,-1.0)';
      PINUSE='OUT';
    'PE2_TX_DN12':
      PIN_NUMBER='(0,0,0,0,0,0,0,0,0,0,0,0,0,0,0,0,0,0,EA13,0,0,0,0,0,0,0,0,0,0,~
0,0,0,0,0,0,0,0,0,0,0,0,0)';
      OUTPUT_LOAD='(1.0,-1.0)';
      PINUSE='OUT';
    'PE2_TX_DN11':
      PIN_NUMBER='(0,0,0,0,0,0,0,0,0,0,0,0,0,0,0,0,0,0,DV14,0,0,0,0,0,0,0,0,0,0,~
0,0,0,0,0,0,0,0,0,0,0,0,0)';
      OUTPUT_LOAD='(1.0,-1.0)';
      PINUSE='OUT';
    'PE2_TX_DN10':
      PIN_NUMBER='(0,0,0,0,0,0,0,0,0,0,0,0,0,0,0,0,0,0,DU13,0,0,0,0,0,0,0,0,0,0,~
0,0,0,0,0,0,0,0,0,0,0,0,0)';
      OUTPUT_LOAD='(1.0,-1.0)';
      PINUSE='OUT';
    'PE2_TX_DN9':
      PIN_NUMBER='(0,0,0,0,0,0,0,0,0,0,0,0,0,0,0,0,0,0,DP14,0,0,0,0,0,0,0,0,0,0,~
0,0,0,0,0,0,0,0,0,0,0,0,0)';
      OUTPUT_LOAD='(1.0,-1.0)';
      PINUSE='OUT';
    'PE2_TX_DN8':
      PIN_NUMBER='(0,0,0,0,0,0,0,0,0,0,0,0,0,0,0,0,0,0,DN13,0,0,0,0,0,0,0,0,0,0,~
0,0,0,0,0,0,0,0,0,0,0,0,0)';
      OUTPUT_LOAD='(1.0,-1.0)';
      PINUSE='OUT';
    'PE2_TX_DN7':
      PIN_NUMBER='(0,0,0,0,0,0,0,0,0,0,0,0,0,0,0,0,0,0,DK14,0,0,0,0,0,0,0,0,0,0,~
0,0,0,0,0,0,0,0,0,0,0,0,0)';
      OUTPUT_LOAD='(1.0,-1.0)';
      PINUSE='OUT';
    'PE2_TX_DN6':
      PIN_NUMBER='(0,0,0,0,0,0,0,0,0,0,0,0,0,0,0,0,0,0,DJ13,0,0,0,0,0,0,0,0,0,0,~
0,0,0,0,0,0,0,0,0,0,0,0,0)';
      OUTPUT_LOAD='(1.0,-1.0)';
      PINUSE='OUT';
    'PE2_TX_DN5':
      PIN_NUMBER='(0,0,0,0,0,0,0,0,0,0,0,0,0,0,0,0,0,0,DF14,0,0,0,0,0,0,0,0,0,0,~
0,0,0,0,0,0,0,0,0,0,0,0,0)';
      OUTPUT_LOAD='(1.0,-1.0)';
      PINUSE='OUT';
    'PE2_TX_DN4':
      PIN_NUMBER='(0,0,0,0,0,0,0,0,0,0,0,0,0,0,0,0,0,0,DE13,0,0,0,0,0,0,0,0,0,0,~
0,0,0,0,0,0,0,0,0,0,0,0,0)';
      OUTPUT_LOAD='(1.0,-1.0)';
      PINUSE='OUT';
    'PE2_TX_DN3':
      PIN_NUMBER='(0,0,0,0,0,0,0,0,0,0,0,0,0,0,0,0,0,0,DB14,0,0,0,0,0,0,0,0,0,0,~
0,0,0,0,0,0,0,0,0,0,0,0,0)';
      OUTPUT_LOAD='(1.0,-1.0)';
      PINUSE='OUT';
    'PE2_TX_DN2':
      PIN_NUMBER='(0,0,0,0,0,0,0,0,0,0,0,0,0,0,0,0,0,0,DA13,0,0,0,0,0,0,0,0,0,0,~
0,0,0,0,0,0,0,0,0,0,0,0,0)';
      OUTPUT_LOAD='(1.0,-1.0)';
      PINUSE='OUT';
    'PE2_TX_DN1':
      PIN_NUMBER='(0,0,0,0,0,0,0,0,0,0,0,0,0,0,0,0,0,0,CV14,0,0,0,0,0,0,0,0,0,0,~
0,0,0,0,0,0,0,0,0,0,0,0,0)';
      OUTPUT_LOAD='(1.0,-1.0)';
      PINUSE='OUT';
    'PE2_TX_DN0':
      PIN_NUMBER='(0,0,0,0,0,0,0,0,0,0,0,0,0,0,0,0,0,0,CU13,0,0,0,0,0,0,0,0,0,0,~
0,0,0,0,0,0,0,0,0,0,0,0,0)';
      OUTPUT_LOAD='(1.0,-1.0)';
      PINUSE='OUT';
    'PE2_TX_DP15':
      PIN_NUMBER='(0,0,0,0,0,0,0,0,0,0,0,0,0,0,0,0,0,0,EG15,0,0,0,0,0,0,0,0,0,0,~
0,0,0,0,0,0,0,0,0,0,0,0,0)';
      OUTPUT_LOAD='(1.0,-1.0)';
      PINUSE='OUT';
    'PE2_TX_DP14':
      PIN_NUMBER='(0,0,0,0,0,0,0,0,0,0,0,0,0,0,0,0,0,0,ED14,0,0,0,0,0,0,0,0,0,0,~
0,0,0,0,0,0,0,0,0,0,0,0,0)';
      OUTPUT_LOAD='(1.0,-1.0)';
      PINUSE='OUT';
    'PE2_TX_DP13':
      PIN_NUMBER='(0,0,0,0,0,0,0,0,0,0,0,0,0,0,0,0,0,0,EC15,0,0,0,0,0,0,0,0,0,0,~
0,0,0,0,0,0,0,0,0,0,0,0,0)';
      OUTPUT_LOAD='(1.0,-1.0)';
      PINUSE='OUT';
    'PE2_TX_DP12':
      PIN_NUMBER='(0,0,0,0,0,0,0,0,0,0,0,0,0,0,0,0,0,0,DY14,0,0,0,0,0,0,0,0,0,0,~
0,0,0,0,0,0,0,0,0,0,0,0,0)';
      OUTPUT_LOAD='(1.0,-1.0)';
      PINUSE='OUT';
    'PE2_TX_DP11':
      PIN_NUMBER='(0,0,0,0,0,0,0,0,0,0,0,0,0,0,0,0,0,0,DW15,0,0,0,0,0,0,0,0,0,0,~
0,0,0,0,0,0,0,0,0,0,0,0,0)';
      OUTPUT_LOAD='(1.0,-1.0)';
      PINUSE='OUT';
    'PE2_TX_DP10':
      PIN_NUMBER='(0,0,0,0,0,0,0,0,0,0,0,0,0,0,0,0,0,0,DT14,0,0,0,0,0,0,0,0,0,0,~
0,0,0,0,0,0,0,0,0,0,0,0,0)';
      OUTPUT_LOAD='(1.0,-1.0)';
      PINUSE='OUT';
    'PE2_TX_DP9':
      PIN_NUMBER='(0,0,0,0,0,0,0,0,0,0,0,0,0,0,0,0,0,0,DR15,0,0,0,0,0,0,0,0,0,0,~
0,0,0,0,0,0,0,0,0,0,0,0,0)';
      OUTPUT_LOAD='(1.0,-1.0)';
      PINUSE='OUT';
    'PE2_TX_DP8':
      PIN_NUMBER='(0,0,0,0,0,0,0,0,0,0,0,0,0,0,0,0,0,0,DM14,0,0,0,0,0,0,0,0,0,0,~
0,0,0,0,0,0,0,0,0,0,0,0,0)';
      OUTPUT_LOAD='(1.0,-1.0)';
      PINUSE='OUT';
    'PE2_TX_DP7':
      PIN_NUMBER='(0,0,0,0,0,0,0,0,0,0,0,0,0,0,0,0,0,0,DL15,0,0,0,0,0,0,0,0,0,0,~
0,0,0,0,0,0,0,0,0,0,0,0,0)';
      OUTPUT_LOAD='(1.0,-1.0)';
      PINUSE='OUT';
    'PE2_TX_DP6':
      PIN_NUMBER='(0,0,0,0,0,0,0,0,0,0,0,0,0,0,0,0,0,0,DH14,0,0,0,0,0,0,0,0,0,0,~
0,0,0,0,0,0,0,0,0,0,0,0,0)';
      OUTPUT_LOAD='(1.0,-1.0)';
      PINUSE='OUT';
    'PE2_TX_DP5':
      PIN_NUMBER='(0,0,0,0,0,0,0,0,0,0,0,0,0,0,0,0,0,0,DG15,0,0,0,0,0,0,0,0,0,0,~
0,0,0,0,0,0,0,0,0,0,0,0,0)';
      OUTPUT_LOAD='(1.0,-1.0)';
      PINUSE='OUT';
    'PE2_TX_DP4':
      PIN_NUMBER='(0,0,0,0,0,0,0,0,0,0,0,0,0,0,0,0,0,0,DD14,0,0,0,0,0,0,0,0,0,0,~
0,0,0,0,0,0,0,0,0,0,0,0,0)';
      OUTPUT_LOAD='(1.0,-1.0)';
      PINUSE='OUT';
    'PE2_TX_DP3':
      PIN_NUMBER='(0,0,0,0,0,0,0,0,0,0,0,0,0,0,0,0,0,0,DC15,0,0,0,0,0,0,0,0,0,0,~
0,0,0,0,0,0,0,0,0,0,0,0,0)';
      OUTPUT_LOAD='(1.0,-1.0)';
      PINUSE='OUT';
    'PE2_TX_DP2':
      PIN_NUMBER='(0,0,0,0,0,0,0,0,0,0,0,0,0,0,0,0,0,0,CY14,0,0,0,0,0,0,0,0,0,0,~
0,0,0,0,0,0,0,0,0,0,0,0,0)';
      OUTPUT_LOAD='(1.0,-1.0)';
      PINUSE='OUT';
    'PE2_TX_DP1':
      PIN_NUMBER='(0,0,0,0,0,0,0,0,0,0,0,0,0,0,0,0,0,0,CW15,0,0,0,0,0,0,0,0,0,0,~
0,0,0,0,0,0,0,0,0,0,0,0,0)';
      OUTPUT_LOAD='(1.0,-1.0)';
      PINUSE='OUT';
    'PE2_TX_DP0':
      PIN_NUMBER='(0,0,0,0,0,0,0,0,0,0,0,0,0,0,0,0,0,0,CT14,0,0,0,0,0,0,0,0,0,0,~
0,0,0,0,0,0,0,0,0,0,0,0,0)';
      OUTPUT_LOAD='(1.0,-1.0)';
      PINUSE='OUT';
    'PE3_RX_DN15':
      PIN_NUMBER='(0,0,0,0,0,0,0,0,0,0,0,0,0,0,0,0,0,0,0,CU90,0,0,0,0,0,0,0,0,0,~
0,0,0,0,0,0,0,0,0,0,0,0,0)';
      INPUT_LOAD='(-0.01,0.01)';
      PINUSE='IN';
    'PE3_RX_DN14':
      PIN_NUMBER='(0,0,0,0,0,0,0,0,0,0,0,0,0,0,0,0,0,0,0,CV89,0,0,0,0,0,0,0,0,0,~
0,0,0,0,0,0,0,0,0,0,0,0,0)';
      INPUT_LOAD='(-0.01,0.01)';
      PINUSE='IN';
    'PE3_RX_DN13':
      PIN_NUMBER='(0,0,0,0,0,0,0,0,0,0,0,0,0,0,0,0,0,0,0,DA90,0,0,0,0,0,0,0,0,0,~
0,0,0,0,0,0,0,0,0,0,0,0,0)';
      INPUT_LOAD='(-0.01,0.01)';
      PINUSE='IN';
    'PE3_RX_DN12':
      PIN_NUMBER='(0,0,0,0,0,0,0,0,0,0,0,0,0,0,0,0,0,0,0,DB89,0,0,0,0,0,0,0,0,0,~
0,0,0,0,0,0,0,0,0,0,0,0,0)';
      INPUT_LOAD='(-0.01,0.01)';
      PINUSE='IN';
    'PE3_RX_DN11':
      PIN_NUMBER='(0,0,0,0,0,0,0,0,0,0,0,0,0,0,0,0,0,0,0,DD91,0,0,0,0,0,0,0,0,0,~
0,0,0,0,0,0,0,0,0,0,0,0,0)';
      INPUT_LOAD='(-0.01,0.01)';
      PINUSE='IN';
    'PE3_RX_DN10':
      PIN_NUMBER='(0,0,0,0,0,0,0,0,0,0,0,0,0,0,0,0,0,0,0,DG90,0,0,0,0,0,0,0,0,0,~
0,0,0,0,0,0,0,0,0,0,0,0,0)';
      INPUT_LOAD='(-0.01,0.01)';
      PINUSE='IN';
    'PE3_RX_DN9':
      PIN_NUMBER='(0,0,0,0,0,0,0,0,0,0,0,0,0,0,0,0,0,0,0,DH91,0,0,0,0,0,0,0,0,0,~
0,0,0,0,0,0,0,0,0,0,0,0,0)';
      INPUT_LOAD='(-0.01,0.01)';
      PINUSE='IN';
    'PE3_RX_DN8':
      PIN_NUMBER='(0,0,0,0,0,0,0,0,0,0,0,0,0,0,0,0,0,0,0,DL90,0,0,0,0,0,0,0,0,0,~
0,0,0,0,0,0,0,0,0,0,0,0,0)';
      INPUT_LOAD='(-0.01,0.01)';
      PINUSE='IN';
    'PE3_RX_DN7':
      PIN_NUMBER='(0,0,0,0,0,0,0,0,0,0,0,0,0,0,0,0,0,0,0,DN90,0,0,0,0,0,0,0,0,0,~
0,0,0,0,0,0,0,0,0,0,0,0,0)';
      INPUT_LOAD='(-0.01,0.01)';
      PINUSE='IN';
    'PE3_RX_DN6':
      PIN_NUMBER='(0,0,0,0,0,0,0,0,0,0,0,0,0,0,0,0,0,0,0,DP89,0,0,0,0,0,0,0,0,0,~
0,0,0,0,0,0,0,0,0,0,0,0,0)';
      INPUT_LOAD='(-0.01,0.01)';
      PINUSE='IN';
    'PE3_RX_DN5':
      PIN_NUMBER='(0,0,0,0,0,0,0,0,0,0,0,0,0,0,0,0,0,0,0,DU90,0,0,0,0,0,0,0,0,0,~
0,0,0,0,0,0,0,0,0,0,0,0,0)';
      INPUT_LOAD='(-0.01,0.01)';
      PINUSE='IN';
    'PE3_RX_DN4':
      PIN_NUMBER='(0,0,0,0,0,0,0,0,0,0,0,0,0,0,0,0,0,0,0,DV89,0,0,0,0,0,0,0,0,0,~
0,0,0,0,0,0,0,0,0,0,0,0,0)';
      INPUT_LOAD='(-0.01,0.01)';
      PINUSE='IN';
    'PE3_RX_DN3':
      PIN_NUMBER='(0,0,0,0,0,0,0,0,0,0,0,0,0,0,0,0,0,0,0,DY91,0,0,0,0,0,0,0,0,0,~
0,0,0,0,0,0,0,0,0,0,0,0,0)';
      INPUT_LOAD='(-0.01,0.01)';
      PINUSE='IN';
    'PE3_RX_DN2':
      PIN_NUMBER='(0,0,0,0,0,0,0,0,0,0,0,0,0,0,0,0,0,0,0,EC90,0,0,0,0,0,0,0,0,0,~
0,0,0,0,0,0,0,0,0,0,0,0,0)';
      INPUT_LOAD='(-0.01,0.01)';
      PINUSE='IN';
    'PE3_RX_DN1':
      PIN_NUMBER='(0,0,0,0,0,0,0,0,0,0,0,0,0,0,0,0,0,0,0,ED91,0,0,0,0,0,0,0,0,0,~
0,0,0,0,0,0,0,0,0,0,0,0,0)';
      INPUT_LOAD='(-0.01,0.01)';
      PINUSE='IN';
    'PE3_RX_DN0':
      PIN_NUMBER='(0,0,0,0,0,0,0,0,0,0,0,0,0,0,0,0,0,0,0,EH89,0,0,0,0,0,0,0,0,0,~
0,0,0,0,0,0,0,0,0,0,0,0,0)';
      INPUT_LOAD='(-0.01,0.01)';
      PINUSE='IN';
    'PE3_RX_DP15':
      PIN_NUMBER='(0,0,0,0,0,0,0,0,0,0,0,0,0,0,0,0,0,0,0,CT91,0,0,0,0,0,0,0,0,0,~
0,0,0,0,0,0,0,0,0,0,0,0,0)';
      INPUT_LOAD='(-0.01,0.01)';
      PINUSE='IN';
    'PE3_RX_DP14':
      PIN_NUMBER='(0,0,0,0,0,0,0,0,0,0,0,0,0,0,0,0,0,0,0,CW90,0,0,0,0,0,0,0,0,0,~
0,0,0,0,0,0,0,0,0,0,0,0,0)';
      INPUT_LOAD='(-0.01,0.01)';
      PINUSE='IN';
    'PE3_RX_DP13':
      PIN_NUMBER='(0,0,0,0,0,0,0,0,0,0,0,0,0,0,0,0,0,0,0,CY91,0,0,0,0,0,0,0,0,0,~
0,0,0,0,0,0,0,0,0,0,0,0,0)';
      INPUT_LOAD='(-0.01,0.01)';
      PINUSE='IN';
    'PE3_RX_DP12':
      PIN_NUMBER='(0,0,0,0,0,0,0,0,0,0,0,0,0,0,0,0,0,0,0,DC90,0,0,0,0,0,0,0,0,0,~
0,0,0,0,0,0,0,0,0,0,0,0,0)';
      INPUT_LOAD='(-0.01,0.01)';
      PINUSE='IN';
    'PE3_RX_DP11':
      PIN_NUMBER='(0,0,0,0,0,0,0,0,0,0,0,0,0,0,0,0,0,0,0,DE90,0,0,0,0,0,0,0,0,0,~
0,0,0,0,0,0,0,0,0,0,0,0,0)';
      INPUT_LOAD='(-0.01,0.01)';
      PINUSE='IN';
    'PE3_RX_DP10':
      PIN_NUMBER='(0,0,0,0,0,0,0,0,0,0,0,0,0,0,0,0,0,0,0,DF89,0,0,0,0,0,0,0,0,0,~
0,0,0,0,0,0,0,0,0,0,0,0,0)';
      INPUT_LOAD='(-0.01,0.01)';
      PINUSE='IN';
    'PE3_RX_DP9':
      PIN_NUMBER='(0,0,0,0,0,0,0,0,0,0,0,0,0,0,0,0,0,0,0,DJ90,0,0,0,0,0,0,0,0,0,~
0,0,0,0,0,0,0,0,0,0,0,0,0)';
      INPUT_LOAD='(-0.01,0.01)';
      PINUSE='IN';
    'PE3_RX_DP8':
      PIN_NUMBER='(0,0,0,0,0,0,0,0,0,0,0,0,0,0,0,0,0,0,0,DK89,0,0,0,0,0,0,0,0,0,~
0,0,0,0,0,0,0,0,0,0,0,0,0)';
      INPUT_LOAD='(-0.01,0.01)';
      PINUSE='IN';
    'PE3_RX_DP7':
      PIN_NUMBER='(0,0,0,0,0,0,0,0,0,0,0,0,0,0,0,0,0,0,0,DM91,0,0,0,0,0,0,0,0,0,~
0,0,0,0,0,0,0,0,0,0,0,0,0)';
      INPUT_LOAD='(-0.01,0.01)';
      PINUSE='IN';
    'PE3_RX_DP6':
      PIN_NUMBER='(0,0,0,0,0,0,0,0,0,0,0,0,0,0,0,0,0,0,0,DR90,0,0,0,0,0,0,0,0,0,~
0,0,0,0,0,0,0,0,0,0,0,0,0)';
      INPUT_LOAD='(-0.01,0.01)';
      PINUSE='IN';
    'PE3_RX_DP5':
      PIN_NUMBER='(0,0,0,0,0,0,0,0,0,0,0,0,0,0,0,0,0,0,0,DT91,0,0,0,0,0,0,0,0,0,~
0,0,0,0,0,0,0,0,0,0,0,0,0)';
      INPUT_LOAD='(-0.01,0.01)';
      PINUSE='IN';
    'PE3_RX_DP4':
      PIN_NUMBER='(0,0,0,0,0,0,0,0,0,0,0,0,0,0,0,0,0,0,0,DW90,0,0,0,0,0,0,0,0,0,~
0,0,0,0,0,0,0,0,0,0,0,0,0)';
      INPUT_LOAD='(-0.01,0.01)';
      PINUSE='IN';
    'PE3_RX_DP3':
      PIN_NUMBER='(0,0,0,0,0,0,0,0,0,0,0,0,0,0,0,0,0,0,0,EA90,0,0,0,0,0,0,0,0,0,~
0,0,0,0,0,0,0,0,0,0,0,0,0)';
      INPUT_LOAD='(-0.01,0.01)';
      PINUSE='IN';
    'PE3_RX_DP2':
      PIN_NUMBER='(0,0,0,0,0,0,0,0,0,0,0,0,0,0,0,0,0,0,0,EB89,0,0,0,0,0,0,0,0,0,~
0,0,0,0,0,0,0,0,0,0,0,0,0)';
      INPUT_LOAD='(-0.01,0.01)';
      PINUSE='IN';
    'PE3_RX_DP1':
      PIN_NUMBER='(0,0,0,0,0,0,0,0,0,0,0,0,0,0,0,0,0,0,0,EE90,0,0,0,0,0,0,0,0,0,~
0,0,0,0,0,0,0,0,0,0,0,0,0)';
      INPUT_LOAD='(-0.01,0.01)';
      PINUSE='IN';
    'PE3_RX_DP0':
      PIN_NUMBER='(0,0,0,0,0,0,0,0,0,0,0,0,0,0,0,0,0,0,0,EJ90,0,0,0,0,0,0,0,0,0,~
0,0,0,0,0,0,0,0,0,0,0,0,0)';
      INPUT_LOAD='(-0.01,0.01)';
      PINUSE='IN';
    'PE3_TX_DN15':
      PIN_NUMBER='(0,0,0,0,0,0,0,0,0,0,0,0,0,0,0,0,0,0,0,CP85,0,0,0,0,0,0,0,0,0,~
0,0,0,0,0,0,0,0,0,0,0,0,0)';
      OUTPUT_LOAD='(1.0,-1.0)';
      PINUSE='OUT';
    'PE3_TX_DN14':
      PIN_NUMBER='(0,0,0,0,0,0,0,0,0,0,0,0,0,0,0,0,0,0,0,CT87,0,0,0,0,0,0,0,0,0,~
0,0,0,0,0,0,0,0,0,0,0,0,0)';
      OUTPUT_LOAD='(1.0,-1.0)';
      PINUSE='OUT';
    'PE3_TX_DN13':
      PIN_NUMBER='(0,0,0,0,0,0,0,0,0,0,0,0,0,0,0,0,0,0,0,CV85,0,0,0,0,0,0,0,0,0,~
0,0,0,0,0,0,0,0,0,0,0,0,0)';
      OUTPUT_LOAD='(1.0,-1.0)';
      PINUSE='OUT';
    'PE3_TX_DN12':
      PIN_NUMBER='(0,0,0,0,0,0,0,0,0,0,0,0,0,0,0,0,0,0,0,CY87,0,0,0,0,0,0,0,0,0,~
0,0,0,0,0,0,0,0,0,0,0,0,0)';
      OUTPUT_LOAD='(1.0,-1.0)';
      PINUSE='OUT';
    'PE3_TX_DN11':
      PIN_NUMBER='(0,0,0,0,0,0,0,0,0,0,0,0,0,0,0,0,0,0,0,DB85,0,0,0,0,0,0,0,0,0,~
0,0,0,0,0,0,0,0,0,0,0,0,0)';
      OUTPUT_LOAD='(1.0,-1.0)';
      PINUSE='OUT';
    'PE3_TX_DN10':
      PIN_NUMBER='(0,0,0,0,0,0,0,0,0,0,0,0,0,0,0,0,0,0,0,DD87,0,0,0,0,0,0,0,0,0,~
0,0,0,0,0,0,0,0,0,0,0,0,0)';
      OUTPUT_LOAD='(1.0,-1.0)';
      PINUSE='OUT';
    'PE3_TX_DN9':
      PIN_NUMBER='(0,0,0,0,0,0,0,0,0,0,0,0,0,0,0,0,0,0,0,DF85,0,0,0,0,0,0,0,0,0,~
0,0,0,0,0,0,0,0,0,0,0,0,0)';
      OUTPUT_LOAD='(1.0,-1.0)';
      PINUSE='OUT';
    'PE3_TX_DN8':
      PIN_NUMBER='(0,0,0,0,0,0,0,0,0,0,0,0,0,0,0,0,0,0,0,DH87,0,0,0,0,0,0,0,0,0,~
0,0,0,0,0,0,0,0,0,0,0,0,0)';
      OUTPUT_LOAD='(1.0,-1.0)';
      PINUSE='OUT';
    'PE3_TX_DN7':
      PIN_NUMBER='(0,0,0,0,0,0,0,0,0,0,0,0,0,0,0,0,0,0,0,DK85,0,0,0,0,0,0,0,0,0,~
0,0,0,0,0,0,0,0,0,0,0,0,0)';
      OUTPUT_LOAD='(1.0,-1.0)';
      PINUSE='OUT';
    'PE3_TX_DN6':
      PIN_NUMBER='(0,0,0,0,0,0,0,0,0,0,0,0,0,0,0,0,0,0,0,DM87,0,0,0,0,0,0,0,0,0,~
0,0,0,0,0,0,0,0,0,0,0,0,0)';
      OUTPUT_LOAD='(1.0,-1.0)';
      PINUSE='OUT';
    'PE3_TX_DN5':
      PIN_NUMBER='(0,0,0,0,0,0,0,0,0,0,0,0,0,0,0,0,0,0,0,DP85,0,0,0,0,0,0,0,0,0,~
0,0,0,0,0,0,0,0,0,0,0,0,0)';
      OUTPUT_LOAD='(1.0,-1.0)';
      PINUSE='OUT';
    'PE3_TX_DN4':
      PIN_NUMBER='(0,0,0,0,0,0,0,0,0,0,0,0,0,0,0,0,0,0,0,DT87,0,0,0,0,0,0,0,0,0,~
0,0,0,0,0,0,0,0,0,0,0,0,0)';
      OUTPUT_LOAD='(1.0,-1.0)';
      PINUSE='OUT';
    'PE3_TX_DN3':
      PIN_NUMBER='(0,0,0,0,0,0,0,0,0,0,0,0,0,0,0,0,0,0,0,DV85,0,0,0,0,0,0,0,0,0,~
0,0,0,0,0,0,0,0,0,0,0,0,0)';
      OUTPUT_LOAD='(1.0,-1.0)';
      PINUSE='OUT';
    'PE3_TX_DN2':
      PIN_NUMBER='(0,0,0,0,0,0,0,0,0,0,0,0,0,0,0,0,0,0,0,DY87,0,0,0,0,0,0,0,0,0,~
0,0,0,0,0,0,0,0,0,0,0,0,0)';
      OUTPUT_LOAD='(1.0,-1.0)';
      PINUSE='OUT';
    'PE3_TX_DN1':
      PIN_NUMBER='(0,0,0,0,0,0,0,0,0,0,0,0,0,0,0,0,0,0,0,EB85,0,0,0,0,0,0,0,0,0,~
0,0,0,0,0,0,0,0,0,0,0,0,0)';
      OUTPUT_LOAD='(1.0,-1.0)';
      PINUSE='OUT';
    'PE3_TX_DN0':
      PIN_NUMBER='(0,0,0,0,0,0,0,0,0,0,0,0,0,0,0,0,0,0,0,EE86,0,0,0,0,0,0,0,0,0,~
0,0,0,0,0,0,0,0,0,0,0,0,0)';
      OUTPUT_LOAD='(1.0,-1.0)';
      PINUSE='OUT';
    'PE3_TX_DP15':
      PIN_NUMBER='(0,0,0,0,0,0,0,0,0,0,0,0,0,0,0,0,0,0,0,CR86,0,0,0,0,0,0,0,0,0,~
0,0,0,0,0,0,0,0,0,0,0,0,0)';
      OUTPUT_LOAD='(1.0,-1.0)';
      PINUSE='OUT';
    'PE3_TX_DP14':
      PIN_NUMBER='(0,0,0,0,0,0,0,0,0,0,0,0,0,0,0,0,0,0,0,CU86,0,0,0,0,0,0,0,0,0,~
0,0,0,0,0,0,0,0,0,0,0,0,0)';
      OUTPUT_LOAD='(1.0,-1.0)';
      PINUSE='OUT';
    'PE3_TX_DP13':
      PIN_NUMBER='(0,0,0,0,0,0,0,0,0,0,0,0,0,0,0,0,0,0,0,CW86,0,0,0,0,0,0,0,0,0,~
0,0,0,0,0,0,0,0,0,0,0,0,0)';
      OUTPUT_LOAD='(1.0,-1.0)';
      PINUSE='OUT';
    'PE3_TX_DP12':
      PIN_NUMBER='(0,0,0,0,0,0,0,0,0,0,0,0,0,0,0,0,0,0,0,DA86,0,0,0,0,0,0,0,0,0,~
0,0,0,0,0,0,0,0,0,0,0,0,0)';
      OUTPUT_LOAD='(1.0,-1.0)';
      PINUSE='OUT';
    'PE3_TX_DP11':
      PIN_NUMBER='(0,0,0,0,0,0,0,0,0,0,0,0,0,0,0,0,0,0,0,DC86,0,0,0,0,0,0,0,0,0,~
0,0,0,0,0,0,0,0,0,0,0,0,0)';
      OUTPUT_LOAD='(1.0,-1.0)';
      PINUSE='OUT';
    'PE3_TX_DP10':
      PIN_NUMBER='(0,0,0,0,0,0,0,0,0,0,0,0,0,0,0,0,0,0,0,DE86,0,0,0,0,0,0,0,0,0,~
0,0,0,0,0,0,0,0,0,0,0,0,0)';
      OUTPUT_LOAD='(1.0,-1.0)';
      PINUSE='OUT';
    'PE3_TX_DP9':
      PIN_NUMBER='(0,0,0,0,0,0,0,0,0,0,0,0,0,0,0,0,0,0,0,DG86,0,0,0,0,0,0,0,0,0,~
0,0,0,0,0,0,0,0,0,0,0,0,0)';
      OUTPUT_LOAD='(1.0,-1.0)';
      PINUSE='OUT';
    'PE3_TX_DP8':
      PIN_NUMBER='(0,0,0,0,0,0,0,0,0,0,0,0,0,0,0,0,0,0,0,DJ86,0,0,0,0,0,0,0,0,0,~
0,0,0,0,0,0,0,0,0,0,0,0,0)';
      OUTPUT_LOAD='(1.0,-1.0)';
      PINUSE='OUT';
    'PE3_TX_DP7':
      PIN_NUMBER='(0,0,0,0,0,0,0,0,0,0,0,0,0,0,0,0,0,0,0,DL86,0,0,0,0,0,0,0,0,0,~
0,0,0,0,0,0,0,0,0,0,0,0,0)';
      OUTPUT_LOAD='(1.0,-1.0)';
      PINUSE='OUT';
    'PE3_TX_DP6':
      PIN_NUMBER='(0,0,0,0,0,0,0,0,0,0,0,0,0,0,0,0,0,0,0,DN86,0,0,0,0,0,0,0,0,0,~
0,0,0,0,0,0,0,0,0,0,0,0,0)';
      OUTPUT_LOAD='(1.0,-1.0)';
      PINUSE='OUT';
    'PE3_TX_DP5':
      PIN_NUMBER='(0,0,0,0,0,0,0,0,0,0,0,0,0,0,0,0,0,0,0,DR86,0,0,0,0,0,0,0,0,0,~
0,0,0,0,0,0,0,0,0,0,0,0,0)';
      OUTPUT_LOAD='(1.0,-1.0)';
      PINUSE='OUT';
    'PE3_TX_DP4':
      PIN_NUMBER='(0,0,0,0,0,0,0,0,0,0,0,0,0,0,0,0,0,0,0,DU86,0,0,0,0,0,0,0,0,0,~
0,0,0,0,0,0,0,0,0,0,0,0,0)';
      OUTPUT_LOAD='(1.0,-1.0)';
      PINUSE='OUT';
    'PE3_TX_DP3':
      PIN_NUMBER='(0,0,0,0,0,0,0,0,0,0,0,0,0,0,0,0,0,0,0,DW86,0,0,0,0,0,0,0,0,0,~
0,0,0,0,0,0,0,0,0,0,0,0,0)';
      OUTPUT_LOAD='(1.0,-1.0)';
      PINUSE='OUT';
    'PE3_TX_DP2':
      PIN_NUMBER='(0,0,0,0,0,0,0,0,0,0,0,0,0,0,0,0,0,0,0,EA86,0,0,0,0,0,0,0,0,0,~
0,0,0,0,0,0,0,0,0,0,0,0,0)';
      OUTPUT_LOAD='(1.0,-1.0)';
      PINUSE='OUT';
    'PE3_TX_DP1':
      PIN_NUMBER='(0,0,0,0,0,0,0,0,0,0,0,0,0,0,0,0,0,0,0,EC86,0,0,0,0,0,0,0,0,0,~
0,0,0,0,0,0,0,0,0,0,0,0,0)';
      OUTPUT_LOAD='(1.0,-1.0)';
      PINUSE='OUT';
    'PE3_TX_DP0':
      PIN_NUMBER='(0,0,0,0,0,0,0,0,0,0,0,0,0,0,0,0,0,0,0,ED87,0,0,0,0,0,0,0,0,0,~
0,0,0,0,0,0,0,0,0,0,0,0,0)';
      OUTPUT_LOAD='(1.0,-1.0)';
      PINUSE='OUT';
    'PE4_RX_DN15':
      PIN_NUMBER='(0,0,0,0,0,0,0,0,0,0,0,0,0,0,0,0,0,0,0,0,BB89,0,0,0,0,0,0,0,0,~
0,0,0,0,0,0,0,0,0,0,0,0,0)';
      INPUT_LOAD='(-0.01,0.01)';
      PINUSE='IN';
    'PE4_RX_DN14':
      PIN_NUMBER='(0,0,0,0,0,0,0,0,0,0,0,0,0,0,0,0,0,0,0,0,AY91,0,0,0,0,0,0,0,0,~
0,0,0,0,0,0,0,0,0,0,0,0,0)';
      INPUT_LOAD='(-0.01,0.01)';
      PINUSE='IN';
    'PE4_RX_DN13':
      PIN_NUMBER='(0,0,0,0,0,0,0,0,0,0,0,0,0,0,0,0,0,0,0,0,AV89,0,0,0,0,0,0,0,0,~
0,0,0,0,0,0,0,0,0,0,0,0,0)';
      INPUT_LOAD='(-0.01,0.01)';
      PINUSE='IN';
    'PE4_RX_DN12':
      PIN_NUMBER='(0,0,0,0,0,0,0,0,0,0,0,0,0,0,0,0,0,0,0,0,AT91,0,0,0,0,0,0,0,0,~
0,0,0,0,0,0,0,0,0,0,0,0,0)';
      INPUT_LOAD='(-0.01,0.01)';
      PINUSE='IN';
    'PE4_RX_DN11':
      PIN_NUMBER='(0,0,0,0,0,0,0,0,0,0,0,0,0,0,0,0,0,0,0,0,AP89,0,0,0,0,0,0,0,0,~
0,0,0,0,0,0,0,0,0,0,0,0,0)';
      INPUT_LOAD='(-0.01,0.01)';
      PINUSE='IN';
    'PE4_RX_DN10':
      PIN_NUMBER='(0,0,0,0,0,0,0,0,0,0,0,0,0,0,0,0,0,0,0,0,AM91,0,0,0,0,0,0,0,0,~
0,0,0,0,0,0,0,0,0,0,0,0,0)';
      INPUT_LOAD='(-0.01,0.01)';
      PINUSE='IN';
    'PE4_RX_DN9':
      PIN_NUMBER='(0,0,0,0,0,0,0,0,0,0,0,0,0,0,0,0,0,0,0,0,AK89,0,0,0,0,0,0,0,0,~
0,0,0,0,0,0,0,0,0,0,0,0,0)';
      INPUT_LOAD='(-0.01,0.01)';
      PINUSE='IN';
    'PE4_RX_DN8':
      PIN_NUMBER='(0,0,0,0,0,0,0,0,0,0,0,0,0,0,0,0,0,0,0,0,AH91,0,0,0,0,0,0,0,0,~
0,0,0,0,0,0,0,0,0,0,0,0,0)';
      INPUT_LOAD='(-0.01,0.01)';
      PINUSE='IN';
    'PE4_RX_DN7':
      PIN_NUMBER='(0,0,0,0,0,0,0,0,0,0,0,0,0,0,0,0,0,0,0,0,AF89,0,0,0,0,0,0,0,0,~
0,0,0,0,0,0,0,0,0,0,0,0,0)';
      INPUT_LOAD='(-0.01,0.01)';
      PINUSE='IN';
    'PE4_RX_DN6':
      PIN_NUMBER='(0,0,0,0,0,0,0,0,0,0,0,0,0,0,0,0,0,0,0,0,AD91,0,0,0,0,0,0,0,0,~
0,0,0,0,0,0,0,0,0,0,0,0,0)';
      INPUT_LOAD='(-0.01,0.01)';
      PINUSE='IN';
    'PE4_RX_DN5':
      PIN_NUMBER='(0,0,0,0,0,0,0,0,0,0,0,0,0,0,0,0,0,0,0,0,AB89,0,0,0,0,0,0,0,0,~
0,0,0,0,0,0,0,0,0,0,0,0,0)';
      INPUT_LOAD='(-0.01,0.01)';
      PINUSE='IN';
    'PE4_RX_DN4':
      PIN_NUMBER='(0,0,0,0,0,0,0,0,0,0,0,0,0,0,0,0,0,0,0,0,Y91,0,0,0,0,0,0,0,0,0~
,0,0,0,0,0,0,0,0,0,0,0,0)';
      INPUT_LOAD='(-0.01,0.01)';
      PINUSE='IN';
    'PE4_RX_DN3':
      PIN_NUMBER='(0,0,0,0,0,0,0,0,0,0,0,0,0,0,0,0,0,0,0,0,V89,0,0,0,0,0,0,0,0,0~
,0,0,0,0,0,0,0,0,0,0,0,0)';
      INPUT_LOAD='(-0.01,0.01)';
      PINUSE='IN';
    'PE4_RX_DN2':
      PIN_NUMBER='(0,0,0,0,0,0,0,0,0,0,0,0,0,0,0,0,0,0,0,0,T91,0,0,0,0,0,0,0,0,0~
,0,0,0,0,0,0,0,0,0,0,0,0)';
      INPUT_LOAD='(-0.01,0.01)';
      PINUSE='IN';
    'PE4_RX_DN1':
      PIN_NUMBER='(0,0,0,0,0,0,0,0,0,0,0,0,0,0,0,0,0,0,0,0,P89,0,0,0,0,0,0,0,0,0~
,0,0,0,0,0,0,0,0,0,0,0,0)';
      INPUT_LOAD='(-0.01,0.01)';
      PINUSE='IN';
    'PE4_RX_DN0':
      PIN_NUMBER='(0,0,0,0,0,0,0,0,0,0,0,0,0,0,0,0,0,0,0,0,J90,0,0,0,0,0,0,0,0,0~
,0,0,0,0,0,0,0,0,0,0,0,0)';
      INPUT_LOAD='(-0.01,0.01)';
      PINUSE='IN';
    'PE4_RX_DP15':
      PIN_NUMBER='(0,0,0,0,0,0,0,0,0,0,0,0,0,0,0,0,0,0,0,0,BA90,0,0,0,0,0,0,0,0,~
0,0,0,0,0,0,0,0,0,0,0,0,0)';
      INPUT_LOAD='(-0.01,0.01)';
      PINUSE='IN';
    'PE4_RX_DP14':
      PIN_NUMBER='(0,0,0,0,0,0,0,0,0,0,0,0,0,0,0,0,0,0,0,0,AW90,0,0,0,0,0,0,0,0,~
0,0,0,0,0,0,0,0,0,0,0,0,0)';
      INPUT_LOAD='(-0.01,0.01)';
      PINUSE='IN';
    'PE4_RX_DP13':
      PIN_NUMBER='(0,0,0,0,0,0,0,0,0,0,0,0,0,0,0,0,0,0,0,0,AU90,0,0,0,0,0,0,0,0,~
0,0,0,0,0,0,0,0,0,0,0,0,0)';
      INPUT_LOAD='(-0.01,0.01)';
      PINUSE='IN';
    'PE4_RX_DP12':
      PIN_NUMBER='(0,0,0,0,0,0,0,0,0,0,0,0,0,0,0,0,0,0,0,0,AR90,0,0,0,0,0,0,0,0,~
0,0,0,0,0,0,0,0,0,0,0,0,0)';
      INPUT_LOAD='(-0.01,0.01)';
      PINUSE='IN';
    'PE4_RX_DP11':
      PIN_NUMBER='(0,0,0,0,0,0,0,0,0,0,0,0,0,0,0,0,0,0,0,0,AN90,0,0,0,0,0,0,0,0,~
0,0,0,0,0,0,0,0,0,0,0,0,0)';
      INPUT_LOAD='(-0.01,0.01)';
      PINUSE='IN';
    'PE4_RX_DP10':
      PIN_NUMBER='(0,0,0,0,0,0,0,0,0,0,0,0,0,0,0,0,0,0,0,0,AL90,0,0,0,0,0,0,0,0,~
0,0,0,0,0,0,0,0,0,0,0,0,0)';
      INPUT_LOAD='(-0.01,0.01)';
      PINUSE='IN';
    'PE4_RX_DP9':
      PIN_NUMBER='(0,0,0,0,0,0,0,0,0,0,0,0,0,0,0,0,0,0,0,0,AJ90,0,0,0,0,0,0,0,0,~
0,0,0,0,0,0,0,0,0,0,0,0,0)';
      INPUT_LOAD='(-0.01,0.01)';
      PINUSE='IN';
    'PE4_RX_DP8':
      PIN_NUMBER='(0,0,0,0,0,0,0,0,0,0,0,0,0,0,0,0,0,0,0,0,AG90,0,0,0,0,0,0,0,0,~
0,0,0,0,0,0,0,0,0,0,0,0,0)';
      INPUT_LOAD='(-0.01,0.01)';
      PINUSE='IN';
    'PE4_RX_DP7':
      PIN_NUMBER='(0,0,0,0,0,0,0,0,0,0,0,0,0,0,0,0,0,0,0,0,AE90,0,0,0,0,0,0,0,0,~
0,0,0,0,0,0,0,0,0,0,0,0,0)';
      INPUT_LOAD='(-0.01,0.01)';
      PINUSE='IN';
    'PE4_RX_DP6':
      PIN_NUMBER='(0,0,0,0,0,0,0,0,0,0,0,0,0,0,0,0,0,0,0,0,AC90,0,0,0,0,0,0,0,0,~
0,0,0,0,0,0,0,0,0,0,0,0,0)';
      INPUT_LOAD='(-0.01,0.01)';
      PINUSE='IN';
    'PE4_RX_DP5':
      PIN_NUMBER='(0,0,0,0,0,0,0,0,0,0,0,0,0,0,0,0,0,0,0,0,AA90,0,0,0,0,0,0,0,0,~
0,0,0,0,0,0,0,0,0,0,0,0,0)';
      INPUT_LOAD='(-0.01,0.01)';
      PINUSE='IN';
    'PE4_RX_DP4':
      PIN_NUMBER='(0,0,0,0,0,0,0,0,0,0,0,0,0,0,0,0,0,0,0,0,W90,0,0,0,0,0,0,0,0,0~
,0,0,0,0,0,0,0,0,0,0,0,0)';
      INPUT_LOAD='(-0.01,0.01)';
      PINUSE='IN';
    'PE4_RX_DP3':
      PIN_NUMBER='(0,0,0,0,0,0,0,0,0,0,0,0,0,0,0,0,0,0,0,0,U90,0,0,0,0,0,0,0,0,0~
,0,0,0,0,0,0,0,0,0,0,0,0)';
      INPUT_LOAD='(-0.01,0.01)';
      PINUSE='IN';
    'PE4_RX_DP2':
      PIN_NUMBER='(0,0,0,0,0,0,0,0,0,0,0,0,0,0,0,0,0,0,0,0,R90,0,0,0,0,0,0,0,0,0~
,0,0,0,0,0,0,0,0,0,0,0,0)';
      INPUT_LOAD='(-0.01,0.01)';
      PINUSE='IN';
    'PE4_RX_DP1':
      PIN_NUMBER='(0,0,0,0,0,0,0,0,0,0,0,0,0,0,0,0,0,0,0,0,N90,0,0,0,0,0,0,0,0,0~
,0,0,0,0,0,0,0,0,0,0,0,0)';
      INPUT_LOAD='(-0.01,0.01)';
      PINUSE='IN';
    'PE4_RX_DP0':
      PIN_NUMBER='(0,0,0,0,0,0,0,0,0,0,0,0,0,0,0,0,0,0,0,0,K89,0,0,0,0,0,0,0,0,0~
,0,0,0,0,0,0,0,0,0,0,0,0)';
      INPUT_LOAD='(-0.01,0.01)';
      PINUSE='IN';
    'PE4_TX_DN15':
      PIN_NUMBER='(0,0,0,0,0,0,0,0,0,0,0,0,0,0,0,0,0,0,0,0,BA86,0,0,0,0,0,0,0,0,~
0,0,0,0,0,0,0,0,0,0,0,0,0)';
      OUTPUT_LOAD='(1.0,-1.0)';
      PINUSE='OUT';
    'PE4_TX_DN14':
      PIN_NUMBER='(0,0,0,0,0,0,0,0,0,0,0,0,0,0,0,0,0,0,0,0,AW86,0,0,0,0,0,0,0,0,~
0,0,0,0,0,0,0,0,0,0,0,0,0)';
      OUTPUT_LOAD='(1.0,-1.0)';
      PINUSE='OUT';
    'PE4_TX_DN13':
      PIN_NUMBER='(0,0,0,0,0,0,0,0,0,0,0,0,0,0,0,0,0,0,0,0,AU86,0,0,0,0,0,0,0,0,~
0,0,0,0,0,0,0,0,0,0,0,0,0)';
      OUTPUT_LOAD='(1.0,-1.0)';
      PINUSE='OUT';
    'PE4_TX_DN12':
      PIN_NUMBER='(0,0,0,0,0,0,0,0,0,0,0,0,0,0,0,0,0,0,0,0,AR86,0,0,0,0,0,0,0,0,~
0,0,0,0,0,0,0,0,0,0,0,0,0)';
      OUTPUT_LOAD='(1.0,-1.0)';
      PINUSE='OUT';
    'PE4_TX_DN11':
      PIN_NUMBER='(0,0,0,0,0,0,0,0,0,0,0,0,0,0,0,0,0,0,0,0,AP85,0,0,0,0,0,0,0,0,~
0,0,0,0,0,0,0,0,0,0,0,0,0)';
      OUTPUT_LOAD='(1.0,-1.0)';
      PINUSE='OUT';
    'PE4_TX_DN10':
      PIN_NUMBER='(0,0,0,0,0,0,0,0,0,0,0,0,0,0,0,0,0,0,0,0,AL86,0,0,0,0,0,0,0,0,~
0,0,0,0,0,0,0,0,0,0,0,0,0)';
      OUTPUT_LOAD='(1.0,-1.0)';
      PINUSE='OUT';
    'PE4_TX_DN9':
      PIN_NUMBER='(0,0,0,0,0,0,0,0,0,0,0,0,0,0,0,0,0,0,0,0,AJ86,0,0,0,0,0,0,0,0,~
0,0,0,0,0,0,0,0,0,0,0,0,0)';
      OUTPUT_LOAD='(1.0,-1.0)';
      PINUSE='OUT';
    'PE4_TX_DN8':
      PIN_NUMBER='(0,0,0,0,0,0,0,0,0,0,0,0,0,0,0,0,0,0,0,0,AG86,0,0,0,0,0,0,0,0,~
0,0,0,0,0,0,0,0,0,0,0,0,0)';
      OUTPUT_LOAD='(1.0,-1.0)';
      PINUSE='OUT';
    'PE4_TX_DN7':
      PIN_NUMBER='(0,0,0,0,0,0,0,0,0,0,0,0,0,0,0,0,0,0,0,0,AE86,0,0,0,0,0,0,0,0,~
0,0,0,0,0,0,0,0,0,0,0,0,0)';
      OUTPUT_LOAD='(1.0,-1.0)';
      PINUSE='OUT';
    'PE4_TX_DN6':
      PIN_NUMBER='(0,0,0,0,0,0,0,0,0,0,0,0,0,0,0,0,0,0,0,0,AC86,0,0,0,0,0,0,0,0,~
0,0,0,0,0,0,0,0,0,0,0,0,0)';
      OUTPUT_LOAD='(1.0,-1.0)';
      PINUSE='OUT';
    'PE4_TX_DN5':
      PIN_NUMBER='(0,0,0,0,0,0,0,0,0,0,0,0,0,0,0,0,0,0,0,0,AA86,0,0,0,0,0,0,0,0,~
0,0,0,0,0,0,0,0,0,0,0,0,0)';
      OUTPUT_LOAD='(1.0,-1.0)';
      PINUSE='OUT';
    'PE4_TX_DN4':
      PIN_NUMBER='(0,0,0,0,0,0,0,0,0,0,0,0,0,0,0,0,0,0,0,0,W86,0,0,0,0,0,0,0,0,0~
,0,0,0,0,0,0,0,0,0,0,0,0)';
      OUTPUT_LOAD='(1.0,-1.0)';
      PINUSE='OUT';
    'PE4_TX_DN3':
      PIN_NUMBER='(0,0,0,0,0,0,0,0,0,0,0,0,0,0,0,0,0,0,0,0,U86,0,0,0,0,0,0,0,0,0~
,0,0,0,0,0,0,0,0,0,0,0,0)';
      OUTPUT_LOAD='(1.0,-1.0)';
      PINUSE='OUT';
    'PE4_TX_DN2':
      PIN_NUMBER='(0,0,0,0,0,0,0,0,0,0,0,0,0,0,0,0,0,0,0,0,R86,0,0,0,0,0,0,0,0,0~
,0,0,0,0,0,0,0,0,0,0,0,0)';
      OUTPUT_LOAD='(1.0,-1.0)';
      PINUSE='OUT';
    'PE4_TX_DN1':
      PIN_NUMBER='(0,0,0,0,0,0,0,0,0,0,0,0,0,0,0,0,0,0,0,0,P85,0,0,0,0,0,0,0,0,0~
,0,0,0,0,0,0,0,0,0,0,0,0)';
      OUTPUT_LOAD='(1.0,-1.0)';
      PINUSE='OUT';
    'PE4_TX_DN0':
      PIN_NUMBER='(0,0,0,0,0,0,0,0,0,0,0,0,0,0,0,0,0,0,0,0,L86,0,0,0,0,0,0,0,0,0~
,0,0,0,0,0,0,0,0,0,0,0,0)';
      OUTPUT_LOAD='(1.0,-1.0)';
      PINUSE='OUT';
    'PE4_TX_DP15':
      PIN_NUMBER='(0,0,0,0,0,0,0,0,0,0,0,0,0,0,0,0,0,0,0,0,BB85,0,0,0,0,0,0,0,0,~
0,0,0,0,0,0,0,0,0,0,0,0,0)';
      OUTPUT_LOAD='(1.0,-1.0)';
      PINUSE='OUT';
    'PE4_TX_DP14':
      PIN_NUMBER='(0,0,0,0,0,0,0,0,0,0,0,0,0,0,0,0,0,0,0,0,AY87,0,0,0,0,0,0,0,0,~
0,0,0,0,0,0,0,0,0,0,0,0,0)';
      OUTPUT_LOAD='(1.0,-1.0)';
      PINUSE='OUT';
    'PE4_TX_DP13':
      PIN_NUMBER='(0,0,0,0,0,0,0,0,0,0,0,0,0,0,0,0,0,0,0,0,AV85,0,0,0,0,0,0,0,0,~
0,0,0,0,0,0,0,0,0,0,0,0,0)';
      OUTPUT_LOAD='(1.0,-1.0)';
      PINUSE='OUT';
    'PE4_TX_DP12':
      PIN_NUMBER='(0,0,0,0,0,0,0,0,0,0,0,0,0,0,0,0,0,0,0,0,AT87,0,0,0,0,0,0,0,0,~
0,0,0,0,0,0,0,0,0,0,0,0,0)';
      OUTPUT_LOAD='(1.0,-1.0)';
      PINUSE='OUT';
    'PE4_TX_DP11':
      PIN_NUMBER='(0,0,0,0,0,0,0,0,0,0,0,0,0,0,0,0,0,0,0,0,AN86,0,0,0,0,0,0,0,0,~
0,0,0,0,0,0,0,0,0,0,0,0,0)';
      OUTPUT_LOAD='(1.0,-1.0)';
      PINUSE='OUT';
    'PE4_TX_DP10':
      PIN_NUMBER='(0,0,0,0,0,0,0,0,0,0,0,0,0,0,0,0,0,0,0,0,AM87,0,0,0,0,0,0,0,0,~
0,0,0,0,0,0,0,0,0,0,0,0,0)';
      OUTPUT_LOAD='(1.0,-1.0)';
      PINUSE='OUT';
    'PE4_TX_DP9':
      PIN_NUMBER='(0,0,0,0,0,0,0,0,0,0,0,0,0,0,0,0,0,0,0,0,AK85,0,0,0,0,0,0,0,0,~
0,0,0,0,0,0,0,0,0,0,0,0,0)';
      OUTPUT_LOAD='(1.0,-1.0)';
      PINUSE='OUT';
    'PE4_TX_DP8':
      PIN_NUMBER='(0,0,0,0,0,0,0,0,0,0,0,0,0,0,0,0,0,0,0,0,AH87,0,0,0,0,0,0,0,0,~
0,0,0,0,0,0,0,0,0,0,0,0,0)';
      OUTPUT_LOAD='(1.0,-1.0)';
      PINUSE='OUT';
    'PE4_TX_DP7':
      PIN_NUMBER='(0,0,0,0,0,0,0,0,0,0,0,0,0,0,0,0,0,0,0,0,AF85,0,0,0,0,0,0,0,0,~
0,0,0,0,0,0,0,0,0,0,0,0,0)';
      OUTPUT_LOAD='(1.0,-1.0)';
      PINUSE='OUT';
    'PE4_TX_DP6':
      PIN_NUMBER='(0,0,0,0,0,0,0,0,0,0,0,0,0,0,0,0,0,0,0,0,AD87,0,0,0,0,0,0,0,0,~
0,0,0,0,0,0,0,0,0,0,0,0,0)';
      OUTPUT_LOAD='(1.0,-1.0)';
      PINUSE='OUT';
    'PE4_TX_DP5':
      PIN_NUMBER='(0,0,0,0,0,0,0,0,0,0,0,0,0,0,0,0,0,0,0,0,AB85,0,0,0,0,0,0,0,0,~
0,0,0,0,0,0,0,0,0,0,0,0,0)';
      OUTPUT_LOAD='(1.0,-1.0)';
      PINUSE='OUT';
    'PE4_TX_DP4':
      PIN_NUMBER='(0,0,0,0,0,0,0,0,0,0,0,0,0,0,0,0,0,0,0,0,Y87,0,0,0,0,0,0,0,0,0~
,0,0,0,0,0,0,0,0,0,0,0,0)';
      OUTPUT_LOAD='(1.0,-1.0)';
      PINUSE='OUT';
    'PE4_TX_DP3':
      PIN_NUMBER='(0,0,0,0,0,0,0,0,0,0,0,0,0,0,0,0,0,0,0,0,V85,0,0,0,0,0,0,0,0,0~
,0,0,0,0,0,0,0,0,0,0,0,0)';
      OUTPUT_LOAD='(1.0,-1.0)';
      PINUSE='OUT';
    'PE4_TX_DP2':
      PIN_NUMBER='(0,0,0,0,0,0,0,0,0,0,0,0,0,0,0,0,0,0,0,0,T87,0,0,0,0,0,0,0,0,0~
,0,0,0,0,0,0,0,0,0,0,0,0)';
      OUTPUT_LOAD='(1.0,-1.0)';
      PINUSE='OUT';
    'PE4_TX_DP1':
      PIN_NUMBER='(0,0,0,0,0,0,0,0,0,0,0,0,0,0,0,0,0,0,0,0,N86,0,0,0,0,0,0,0,0,0~
,0,0,0,0,0,0,0,0,0,0,0,0)';
      OUTPUT_LOAD='(1.0,-1.0)';
      PINUSE='OUT';
    'PE4_TX_DP0':
      PIN_NUMBER='(0,0,0,0,0,0,0,0,0,0,0,0,0,0,0,0,0,0,0,0,M87,0,0,0,0,0,0,0,0,0~
,0,0,0,0,0,0,0,0,0,0,0,0)';
      OUTPUT_LOAD='(1.0,-1.0)';
      PINUSE='OUT';
    'UPI0_RX_DN23':
      PIN_NUMBER='(0,0,0,0,0,0,0,0,0,0,0,0,0,0,0,0,0,0,0,0,0,BU5,0,0,0,0,0,0,0,0~
,0,0,0,0,0,0,0,0,0,0,0,0)';
      INPUT_LOAD='(-0.01,0.01)';
      PINUSE='IN';
    'UPI0_RX_DN22':
      PIN_NUMBER='(0,0,0,0,0,0,0,0,0,0,0,0,0,0,0,0,0,0,0,0,0,BR7,0,0,0,0,0,0,0,0~
,0,0,0,0,0,0,0,0,0,0,0,0)';
      INPUT_LOAD='(-0.01,0.01)';
      PINUSE='IN';
    'UPI0_RX_DN21':
      PIN_NUMBER='(0,0,0,0,0,0,0,0,0,0,0,0,0,0,0,0,0,0,0,0,0,BN5,0,0,0,0,0,0,0,0~
,0,0,0,0,0,0,0,0,0,0,0,0)';
      INPUT_LOAD='(-0.01,0.01)';
      PINUSE='IN';
    'UPI0_RX_DN20':
      PIN_NUMBER='(0,0,0,0,0,0,0,0,0,0,0,0,0,0,0,0,0,0,0,0,0,BK6,0,0,0,0,0,0,0,0~
,0,0,0,0,0,0,0,0,0,0,0,0)';
      INPUT_LOAD='(-0.01,0.01)';
      PINUSE='IN';
    'UPI0_RX_DN19':
      PIN_NUMBER='(0,0,0,0,0,0,0,0,0,0,0,0,0,0,0,0,0,0,0,0,0,BJ5,0,0,0,0,0,0,0,0~
,0,0,0,0,0,0,0,0,0,0,0,0)';
      INPUT_LOAD='(-0.01,0.01)';
      PINUSE='IN';
    'UPI0_RX_DN18':
      PIN_NUMBER='(0,0,0,0,0,0,0,0,0,0,0,0,0,0,0,0,0,0,0,0,0,BF6,0,0,0,0,0,0,0,0~
,0,0,0,0,0,0,0,0,0,0,0,0)';
      INPUT_LOAD='(-0.01,0.01)';
      PINUSE='IN';
    'UPI0_RX_DN17':
      PIN_NUMBER='(0,0,0,0,0,0,0,0,0,0,0,0,0,0,0,0,0,0,0,0,0,BE5,0,0,0,0,0,0,0,0~
,0,0,0,0,0,0,0,0,0,0,0,0)';
      INPUT_LOAD='(-0.01,0.01)';
      PINUSE='IN';
    'UPI0_RX_DN16':
      PIN_NUMBER='(0,0,0,0,0,0,0,0,0,0,0,0,0,0,0,0,0,0,0,0,0,BB6,0,0,0,0,0,0,0,0~
,0,0,0,0,0,0,0,0,0,0,0,0)';
      INPUT_LOAD='(-0.01,0.01)';
      PINUSE='IN';
    'UPI0_RX_DN15':
      PIN_NUMBER='(0,0,0,0,0,0,0,0,0,0,0,0,0,0,0,0,0,0,0,0,0,BA5,0,0,0,0,0,0,0,0~
,0,0,0,0,0,0,0,0,0,0,0,0)';
      INPUT_LOAD='(-0.01,0.01)';
      PINUSE='IN';
    'UPI0_RX_DN14':
      PIN_NUMBER='(0,0,0,0,0,0,0,0,0,0,0,0,0,0,0,0,0,0,0,0,0,AV6,0,0,0,0,0,0,0,0~
,0,0,0,0,0,0,0,0,0,0,0,0)';
      INPUT_LOAD='(-0.01,0.01)';
      PINUSE='IN';
    'UPI0_RX_DN13':
      PIN_NUMBER='(0,0,0,0,0,0,0,0,0,0,0,0,0,0,0,0,0,0,0,0,0,AU5,0,0,0,0,0,0,0,0~
,0,0,0,0,0,0,0,0,0,0,0,0)';
      INPUT_LOAD='(-0.01,0.01)';
      PINUSE='IN';
    'UPI0_RX_DN12':
      PIN_NUMBER='(0,0,0,0,0,0,0,0,0,0,0,0,0,0,0,0,0,0,0,0,0,AP6,0,0,0,0,0,0,0,0~
,0,0,0,0,0,0,0,0,0,0,0,0)';
      INPUT_LOAD='(-0.01,0.01)';
      PINUSE='IN';
    'UPI0_RX_DN11':
      PIN_NUMBER='(0,0,0,0,0,0,0,0,0,0,0,0,0,0,0,0,0,0,0,0,0,AN5,0,0,0,0,0,0,0,0~
,0,0,0,0,0,0,0,0,0,0,0,0)';
      INPUT_LOAD='(-0.01,0.01)';
      PINUSE='IN';
    'UPI0_RX_DN10':
      PIN_NUMBER='(0,0,0,0,0,0,0,0,0,0,0,0,0,0,0,0,0,0,0,0,0,AK6,0,0,0,0,0,0,0,0~
,0,0,0,0,0,0,0,0,0,0,0,0)';
      INPUT_LOAD='(-0.01,0.01)';
      PINUSE='IN';
    'UPI0_RX_DN9':
      PIN_NUMBER='(0,0,0,0,0,0,0,0,0,0,0,0,0,0,0,0,0,0,0,0,0,AH6,0,0,0,0,0,0,0,0~
,0,0,0,0,0,0,0,0,0,0,0,0)';
      INPUT_LOAD='(-0.01,0.01)';
      PINUSE='IN';
    'UPI0_RX_DN8':
      PIN_NUMBER='(0,0,0,0,0,0,0,0,0,0,0,0,0,0,0,0,0,0,0,0,0,AF6,0,0,0,0,0,0,0,0~
,0,0,0,0,0,0,0,0,0,0,0,0)';
      INPUT_LOAD='(-0.01,0.01)';
      PINUSE='IN';
    'UPI0_RX_DN7':
      PIN_NUMBER='(0,0,0,0,0,0,0,0,0,0,0,0,0,0,0,0,0,0,0,0,0,AE5,0,0,0,0,0,0,0,0~
,0,0,0,0,0,0,0,0,0,0,0,0)';
      INPUT_LOAD='(-0.01,0.01)';
      PINUSE='IN';
    'UPI0_RX_DN6':
      PIN_NUMBER='(0,0,0,0,0,0,0,0,0,0,0,0,0,0,0,0,0,0,0,0,0,AB6,0,0,0,0,0,0,0,0~
,0,0,0,0,0,0,0,0,0,0,0,0)';
      INPUT_LOAD='(-0.01,0.01)';
      PINUSE='IN';
    'UPI0_RX_DN5':
      PIN_NUMBER='(0,0,0,0,0,0,0,0,0,0,0,0,0,0,0,0,0,0,0,0,0,AA5,0,0,0,0,0,0,0,0~
,0,0,0,0,0,0,0,0,0,0,0,0)';
      INPUT_LOAD='(-0.01,0.01)';
      PINUSE='IN';
    'UPI0_RX_DN4':
      PIN_NUMBER='(0,0,0,0,0,0,0,0,0,0,0,0,0,0,0,0,0,0,0,0,0,V6,0,0,0,0,0,0,0,0,~
0,0,0,0,0,0,0,0,0,0,0,0)';
      INPUT_LOAD='(-0.01,0.01)';
      PINUSE='IN';
    'UPI0_RX_DN3':
      PIN_NUMBER='(0,0,0,0,0,0,0,0,0,0,0,0,0,0,0,0,0,0,0,0,0,U5,0,0,0,0,0,0,0,0,~
0,0,0,0,0,0,0,0,0,0,0,0)';
      INPUT_LOAD='(-0.01,0.01)';
      PINUSE='IN';
    'UPI0_RX_DN2':
      PIN_NUMBER='(0,0,0,0,0,0,0,0,0,0,0,0,0,0,0,0,0,0,0,0,0,P6,0,0,0,0,0,0,0,0,~
0,0,0,0,0,0,0,0,0,0,0,0)';
      INPUT_LOAD='(-0.01,0.01)';
      PINUSE='IN';
    'UPI0_RX_DN1':
      PIN_NUMBER='(0,0,0,0,0,0,0,0,0,0,0,0,0,0,0,0,0,0,0,0,0,N5,0,0,0,0,0,0,0,0,~
0,0,0,0,0,0,0,0,0,0,0,0)';
      INPUT_LOAD='(-0.01,0.01)';
      PINUSE='IN';
    'UPI0_RX_DN0':
      PIN_NUMBER='(0,0,0,0,0,0,0,0,0,0,0,0,0,0,0,0,0,0,0,0,0,K6,0,0,0,0,0,0,0,0,~
0,0,0,0,0,0,0,0,0,0,0,0)';
      INPUT_LOAD='(-0.01,0.01)';
      PINUSE='IN';
    'UPI0_RX_DP23':
      PIN_NUMBER='(0,0,0,0,0,0,0,0,0,0,0,0,0,0,0,0,0,0,0,0,0,BT6,0,0,0,0,0,0,0,0~
,0,0,0,0,0,0,0,0,0,0,0,0)';
      INPUT_LOAD='(-0.01,0.01)';
      PINUSE='IN';
    'UPI0_RX_DP22':
      PIN_NUMBER='(0,0,0,0,0,0,0,0,0,0,0,0,0,0,0,0,0,0,0,0,0,BP6,0,0,0,0,0,0,0,0~
,0,0,0,0,0,0,0,0,0,0,0,0)';
      INPUT_LOAD='(-0.01,0.01)';
      PINUSE='IN';
    'UPI0_RX_DP21':
      PIN_NUMBER='(0,0,0,0,0,0,0,0,0,0,0,0,0,0,0,0,0,0,0,0,0,BM6,0,0,0,0,0,0,0,0~
,0,0,0,0,0,0,0,0,0,0,0,0)';
      INPUT_LOAD='(-0.01,0.01)';
      PINUSE='IN';
    'UPI0_RX_DP20':
      PIN_NUMBER='(0,0,0,0,0,0,0,0,0,0,0,0,0,0,0,0,0,0,0,0,0,BL7,0,0,0,0,0,0,0,0~
,0,0,0,0,0,0,0,0,0,0,0,0)';
      INPUT_LOAD='(-0.01,0.01)';
      PINUSE='IN';
    'UPI0_RX_DP19':
      PIN_NUMBER='(0,0,0,0,0,0,0,0,0,0,0,0,0,0,0,0,0,0,0,0,0,BH6,0,0,0,0,0,0,0,0~
,0,0,0,0,0,0,0,0,0,0,0,0)';
      INPUT_LOAD='(-0.01,0.01)';
      PINUSE='IN';
    'UPI0_RX_DP18':
      PIN_NUMBER='(0,0,0,0,0,0,0,0,0,0,0,0,0,0,0,0,0,0,0,0,0,BG7,0,0,0,0,0,0,0,0~
,0,0,0,0,0,0,0,0,0,0,0,0)';
      INPUT_LOAD='(-0.01,0.01)';
      PINUSE='IN';
    'UPI0_RX_DP17':
      PIN_NUMBER='(0,0,0,0,0,0,0,0,0,0,0,0,0,0,0,0,0,0,0,0,0,BD6,0,0,0,0,0,0,0,0~
,0,0,0,0,0,0,0,0,0,0,0,0)';
      INPUT_LOAD='(-0.01,0.01)';
      PINUSE='IN';
    'UPI0_RX_DP16':
      PIN_NUMBER='(0,0,0,0,0,0,0,0,0,0,0,0,0,0,0,0,0,0,0,0,0,BC7,0,0,0,0,0,0,0,0~
,0,0,0,0,0,0,0,0,0,0,0,0)';
      INPUT_LOAD='(-0.01,0.01)';
      PINUSE='IN';
    'UPI0_RX_DP15':
      PIN_NUMBER='(0,0,0,0,0,0,0,0,0,0,0,0,0,0,0,0,0,0,0,0,0,AY6,0,0,0,0,0,0,0,0~
,0,0,0,0,0,0,0,0,0,0,0,0)';
      INPUT_LOAD='(-0.01,0.01)';
      PINUSE='IN';
    'UPI0_RX_DP14':
      PIN_NUMBER='(0,0,0,0,0,0,0,0,0,0,0,0,0,0,0,0,0,0,0,0,0,AW7,0,0,0,0,0,0,0,0~
,0,0,0,0,0,0,0,0,0,0,0,0)';
      INPUT_LOAD='(-0.01,0.01)';
      PINUSE='IN';
    'UPI0_RX_DP13':
      PIN_NUMBER='(0,0,0,0,0,0,0,0,0,0,0,0,0,0,0,0,0,0,0,0,0,AT6,0,0,0,0,0,0,0,0~
,0,0,0,0,0,0,0,0,0,0,0,0)';
      INPUT_LOAD='(-0.01,0.01)';
      PINUSE='IN';
    'UPI0_RX_DP12':
      PIN_NUMBER='(0,0,0,0,0,0,0,0,0,0,0,0,0,0,0,0,0,0,0,0,0,AR7,0,0,0,0,0,0,0,0~
,0,0,0,0,0,0,0,0,0,0,0,0)';
      INPUT_LOAD='(-0.01,0.01)';
      PINUSE='IN';
    'UPI0_RX_DP11':
      PIN_NUMBER='(0,0,0,0,0,0,0,0,0,0,0,0,0,0,0,0,0,0,0,0,0,AM6,0,0,0,0,0,0,0,0~
,0,0,0,0,0,0,0,0,0,0,0,0)';
      INPUT_LOAD='(-0.01,0.01)';
      PINUSE='IN';
    'UPI0_RX_DP10':
      PIN_NUMBER='(0,0,0,0,0,0,0,0,0,0,0,0,0,0,0,0,0,0,0,0,0,AL7,0,0,0,0,0,0,0,0~
,0,0,0,0,0,0,0,0,0,0,0,0)';
      INPUT_LOAD='(-0.01,0.01)';
      PINUSE='IN';
    'UPI0_RX_DP9':
      PIN_NUMBER='(0,0,0,0,0,0,0,0,0,0,0,0,0,0,0,0,0,0,0,0,0,AJ5,0,0,0,0,0,0,0,0~
,0,0,0,0,0,0,0,0,0,0,0,0)';
      INPUT_LOAD='(-0.01,0.01)';
      PINUSE='IN';
    'UPI0_RX_DP8':
      PIN_NUMBER='(0,0,0,0,0,0,0,0,0,0,0,0,0,0,0,0,0,0,0,0,0,AG7,0,0,0,0,0,0,0,0~
,0,0,0,0,0,0,0,0,0,0,0,0)';
      INPUT_LOAD='(-0.01,0.01)';
      PINUSE='IN';
    'UPI0_RX_DP7':
      PIN_NUMBER='(0,0,0,0,0,0,0,0,0,0,0,0,0,0,0,0,0,0,0,0,0,AD6,0,0,0,0,0,0,0,0~
,0,0,0,0,0,0,0,0,0,0,0,0)';
      INPUT_LOAD='(-0.01,0.01)';
      PINUSE='IN';
    'UPI0_RX_DP6':
      PIN_NUMBER='(0,0,0,0,0,0,0,0,0,0,0,0,0,0,0,0,0,0,0,0,0,AC7,0,0,0,0,0,0,0,0~
,0,0,0,0,0,0,0,0,0,0,0,0)';
      INPUT_LOAD='(-0.01,0.01)';
      PINUSE='IN';
    'UPI0_RX_DP5':
      PIN_NUMBER='(0,0,0,0,0,0,0,0,0,0,0,0,0,0,0,0,0,0,0,0,0,Y6,0,0,0,0,0,0,0,0,~
0,0,0,0,0,0,0,0,0,0,0,0)';
      INPUT_LOAD='(-0.01,0.01)';
      PINUSE='IN';
    'UPI0_RX_DP4':
      PIN_NUMBER='(0,0,0,0,0,0,0,0,0,0,0,0,0,0,0,0,0,0,0,0,0,W7,0,0,0,0,0,0,0,0,~
0,0,0,0,0,0,0,0,0,0,0,0)';
      INPUT_LOAD='(-0.01,0.01)';
      PINUSE='IN';
    'UPI0_RX_DP3':
      PIN_NUMBER='(0,0,0,0,0,0,0,0,0,0,0,0,0,0,0,0,0,0,0,0,0,T6,0,0,0,0,0,0,0,0,~
0,0,0,0,0,0,0,0,0,0,0,0)';
      INPUT_LOAD='(-0.01,0.01)';
      PINUSE='IN';
    'UPI0_RX_DP2':
      PIN_NUMBER='(0,0,0,0,0,0,0,0,0,0,0,0,0,0,0,0,0,0,0,0,0,R7,0,0,0,0,0,0,0,0,~
0,0,0,0,0,0,0,0,0,0,0,0)';
      INPUT_LOAD='(-0.01,0.01)';
      PINUSE='IN';
    'UPI0_RX_DP1':
      PIN_NUMBER='(0,0,0,0,0,0,0,0,0,0,0,0,0,0,0,0,0,0,0,0,0,M6,0,0,0,0,0,0,0,0,~
0,0,0,0,0,0,0,0,0,0,0,0)';
      INPUT_LOAD='(-0.01,0.01)';
      PINUSE='IN';
    'UPI0_RX_DP0':
      PIN_NUMBER='(0,0,0,0,0,0,0,0,0,0,0,0,0,0,0,0,0,0,0,0,0,L7,0,0,0,0,0,0,0,0,~
0,0,0,0,0,0,0,0,0,0,0,0)';
      INPUT_LOAD='(-0.01,0.01)';
      PINUSE='IN';
    'UPI0_TX_DN23':
      PIN_NUMBER='(0,0,0,0,0,0,0,0,0,0,0,0,0,0,0,0,0,0,0,0,0,BT2,0,0,0,0,0,0,0,0~
,0,0,0,0,0,0,0,0,0,0,0,0)';
      OUTPUT_LOAD='(1.0,-1.0)';
      PINUSE='OUT';
    'UPI0_TX_DN22':
      PIN_NUMBER='(0,0,0,0,0,0,0,0,0,0,0,0,0,0,0,0,0,0,0,0,0,BR3,0,0,0,0,0,0,0,0~
,0,0,0,0,0,0,0,0,0,0,0,0)';
      OUTPUT_LOAD='(1.0,-1.0)';
      PINUSE='OUT';
    'UPI0_TX_DN21':
      PIN_NUMBER='(0,0,0,0,0,0,0,0,0,0,0,0,0,0,0,0,0,0,0,0,0,BM2,0,0,0,0,0,0,0,0~
,0,0,0,0,0,0,0,0,0,0,0,0)';
      OUTPUT_LOAD='(1.0,-1.0)';
      PINUSE='OUT';
    'UPI0_TX_DN20':
      PIN_NUMBER='(0,0,0,0,0,0,0,0,0,0,0,0,0,0,0,0,0,0,0,0,0,BK2,0,0,0,0,0,0,0,0~
,0,0,0,0,0,0,0,0,0,0,0,0)';
      OUTPUT_LOAD='(1.0,-1.0)';
      PINUSE='OUT';
    'UPI0_TX_DN19':
      PIN_NUMBER='(0,0,0,0,0,0,0,0,0,0,0,0,0,0,0,0,0,0,0,0,0,BH2,0,0,0,0,0,0,0,0~
,0,0,0,0,0,0,0,0,0,0,0,0)';
      OUTPUT_LOAD='(1.0,-1.0)';
      PINUSE='OUT';
    'UPI0_TX_DN18':
      PIN_NUMBER='(0,0,0,0,0,0,0,0,0,0,0,0,0,0,0,0,0,0,0,0,0,BF2,0,0,0,0,0,0,0,0~
,0,0,0,0,0,0,0,0,0,0,0,0)';
      OUTPUT_LOAD='(1.0,-1.0)';
      PINUSE='OUT';
    'UPI0_TX_DN17':
      PIN_NUMBER='(0,0,0,0,0,0,0,0,0,0,0,0,0,0,0,0,0,0,0,0,0,BD2,0,0,0,0,0,0,0,0~
,0,0,0,0,0,0,0,0,0,0,0,0)';
      OUTPUT_LOAD='(1.0,-1.0)';
      PINUSE='OUT';
    'UPI0_TX_DN16':
      PIN_NUMBER='(0,0,0,0,0,0,0,0,0,0,0,0,0,0,0,0,0,0,0,0,0,BB2,0,0,0,0,0,0,0,0~
,0,0,0,0,0,0,0,0,0,0,0,0)';
      OUTPUT_LOAD='(1.0,-1.0)';
      PINUSE='OUT';
    'UPI0_TX_DN15':
      PIN_NUMBER='(0,0,0,0,0,0,0,0,0,0,0,0,0,0,0,0,0,0,0,0,0,AY2,0,0,0,0,0,0,0,0~
,0,0,0,0,0,0,0,0,0,0,0,0)';
      OUTPUT_LOAD='(1.0,-1.0)';
      PINUSE='OUT';
    'UPI0_TX_DN14':
      PIN_NUMBER='(0,0,0,0,0,0,0,0,0,0,0,0,0,0,0,0,0,0,0,0,0,AU1,0,0,0,0,0,0,0,0~
,0,0,0,0,0,0,0,0,0,0,0,0)';
      OUTPUT_LOAD='(1.0,-1.0)';
      PINUSE='OUT';
    'UPI0_TX_DN13':
      PIN_NUMBER='(0,0,0,0,0,0,0,0,0,0,0,0,0,0,0,0,0,0,0,0,0,AT2,0,0,0,0,0,0,0,0~
,0,0,0,0,0,0,0,0,0,0,0,0)';
      OUTPUT_LOAD='(1.0,-1.0)';
      PINUSE='OUT';
    'UPI0_TX_DN12':
      PIN_NUMBER='(0,0,0,0,0,0,0,0,0,0,0,0,0,0,0,0,0,0,0,0,0,AP2,0,0,0,0,0,0,0,0~
,0,0,0,0,0,0,0,0,0,0,0,0)';
      OUTPUT_LOAD='(1.0,-1.0)';
      PINUSE='OUT';
    'UPI0_TX_DN11':
      PIN_NUMBER='(0,0,0,0,0,0,0,0,0,0,0,0,0,0,0,0,0,0,0,0,0,AM2,0,0,0,0,0,0,0,0~
,0,0,0,0,0,0,0,0,0,0,0,0)';
      OUTPUT_LOAD='(1.0,-1.0)';
      PINUSE='OUT';
    'UPI0_TX_DN10':
      PIN_NUMBER='(0,0,0,0,0,0,0,0,0,0,0,0,0,0,0,0,0,0,0,0,0,AK2,0,0,0,0,0,0,0,0~
,0,0,0,0,0,0,0,0,0,0,0,0)';
      OUTPUT_LOAD='(1.0,-1.0)';
      PINUSE='OUT';
    'UPI0_TX_DN9':
      PIN_NUMBER='(0,0,0,0,0,0,0,0,0,0,0,0,0,0,0,0,0,0,0,0,0,AH2,0,0,0,0,0,0,0,0~
,0,0,0,0,0,0,0,0,0,0,0,0)';
      OUTPUT_LOAD='(1.0,-1.0)';
      PINUSE='OUT';
    'UPI0_TX_DN8':
      PIN_NUMBER='(0,0,0,0,0,0,0,0,0,0,0,0,0,0,0,0,0,0,0,0,0,AF2,0,0,0,0,0,0,0,0~
,0,0,0,0,0,0,0,0,0,0,0,0)';
      OUTPUT_LOAD='(1.0,-1.0)';
      PINUSE='OUT';
    'UPI0_TX_DN7':
      PIN_NUMBER='(0,0,0,0,0,0,0,0,0,0,0,0,0,0,0,0,0,0,0,0,0,AD2,0,0,0,0,0,0,0,0~
,0,0,0,0,0,0,0,0,0,0,0,0)';
      OUTPUT_LOAD='(1.0,-1.0)';
      PINUSE='OUT';
    'UPI0_TX_DN6':
      PIN_NUMBER='(0,0,0,0,0,0,0,0,0,0,0,0,0,0,0,0,0,0,0,0,0,AA1,0,0,0,0,0,0,0,0~
,0,0,0,0,0,0,0,0,0,0,0,0)';
      OUTPUT_LOAD='(1.0,-1.0)';
      PINUSE='OUT';
    'UPI0_TX_DN5':
      PIN_NUMBER='(0,0,0,0,0,0,0,0,0,0,0,0,0,0,0,0,0,0,0,0,0,Y2,0,0,0,0,0,0,0,0,~
0,0,0,0,0,0,0,0,0,0,0,0)';
      OUTPUT_LOAD='(1.0,-1.0)';
      PINUSE='OUT';
    'UPI0_TX_DN4':
      PIN_NUMBER='(0,0,0,0,0,0,0,0,0,0,0,0,0,0,0,0,0,0,0,0,0,U1,0,0,0,0,0,0,0,0,~
0,0,0,0,0,0,0,0,0,0,0,0)';
      OUTPUT_LOAD='(1.0,-1.0)';
      PINUSE='OUT';
    'UPI0_TX_DN3':
      PIN_NUMBER='(0,0,0,0,0,0,0,0,0,0,0,0,0,0,0,0,0,0,0,0,0,T2,0,0,0,0,0,0,0,0,~
0,0,0,0,0,0,0,0,0,0,0,0)';
      OUTPUT_LOAD='(1.0,-1.0)';
      PINUSE='OUT';
    'UPI0_TX_DN2':
      PIN_NUMBER='(0,0,0,0,0,0,0,0,0,0,0,0,0,0,0,0,0,0,0,0,0,N1,0,0,0,0,0,0,0,0,~
0,0,0,0,0,0,0,0,0,0,0,0)';
      OUTPUT_LOAD='(1.0,-1.0)';
      PINUSE='OUT';
    'UPI0_TX_DN1':
      PIN_NUMBER='(0,0,0,0,0,0,0,0,0,0,0,0,0,0,0,0,0,0,0,0,0,M2,0,0,0,0,0,0,0,0,~
0,0,0,0,0,0,0,0,0,0,0,0)';
      OUTPUT_LOAD='(1.0,-1.0)';
      PINUSE='OUT';
    'UPI0_TX_DN0':
      PIN_NUMBER='(0,0,0,0,0,0,0,0,0,0,0,0,0,0,0,0,0,0,0,0,0,K4,0,0,0,0,0,0,0,0,~
0,0,0,0,0,0,0,0,0,0,0,0)';
      OUTPUT_LOAD='(1.0,-1.0)';
      PINUSE='OUT';
    'UPI0_TX_DP23':
      PIN_NUMBER='(0,0,0,0,0,0,0,0,0,0,0,0,0,0,0,0,0,0,0,0,0,BU3,0,0,0,0,0,0,0,0~
,0,0,0,0,0,0,0,0,0,0,0,0)';
      OUTPUT_LOAD='(1.0,-1.0)';
      PINUSE='OUT';
    'UPI0_TX_DP22':
      PIN_NUMBER='(0,0,0,0,0,0,0,0,0,0,0,0,0,0,0,0,0,0,0,0,0,BN3,0,0,0,0,0,0,0,0~
,0,0,0,0,0,0,0,0,0,0,0,0)';
      OUTPUT_LOAD='(1.0,-1.0)';
      PINUSE='OUT';
    'UPI0_TX_DP21':
      PIN_NUMBER='(0,0,0,0,0,0,0,0,0,0,0,0,0,0,0,0,0,0,0,0,0,BL3,0,0,0,0,0,0,0,0~
,0,0,0,0,0,0,0,0,0,0,0,0)';
      OUTPUT_LOAD='(1.0,-1.0)';
      PINUSE='OUT';
    'UPI0_TX_DP20':
      PIN_NUMBER='(0,0,0,0,0,0,0,0,0,0,0,0,0,0,0,0,0,0,0,0,0,BJ1,0,0,0,0,0,0,0,0~
,0,0,0,0,0,0,0,0,0,0,0,0)';
      OUTPUT_LOAD='(1.0,-1.0)';
      PINUSE='OUT';
    'UPI0_TX_DP19':
      PIN_NUMBER='(0,0,0,0,0,0,0,0,0,0,0,0,0,0,0,0,0,0,0,0,0,BG3,0,0,0,0,0,0,0,0~
,0,0,0,0,0,0,0,0,0,0,0,0)';
      OUTPUT_LOAD='(1.0,-1.0)';
      PINUSE='OUT';
    'UPI0_TX_DP18':
      PIN_NUMBER='(0,0,0,0,0,0,0,0,0,0,0,0,0,0,0,0,0,0,0,0,0,BE1,0,0,0,0,0,0,0,0~
,0,0,0,0,0,0,0,0,0,0,0,0)';
      OUTPUT_LOAD='(1.0,-1.0)';
      PINUSE='OUT';
    'UPI0_TX_DP17':
      PIN_NUMBER='(0,0,0,0,0,0,0,0,0,0,0,0,0,0,0,0,0,0,0,0,0,BC3,0,0,0,0,0,0,0,0~
,0,0,0,0,0,0,0,0,0,0,0,0)';
      OUTPUT_LOAD='(1.0,-1.0)';
      PINUSE='OUT';
    'UPI0_TX_DP16':
      PIN_NUMBER='(0,0,0,0,0,0,0,0,0,0,0,0,0,0,0,0,0,0,0,0,0,BA1,0,0,0,0,0,0,0,0~
,0,0,0,0,0,0,0,0,0,0,0,0)';
      OUTPUT_LOAD='(1.0,-1.0)';
      PINUSE='OUT';
    'UPI0_TX_DP15':
      PIN_NUMBER='(0,0,0,0,0,0,0,0,0,0,0,0,0,0,0,0,0,0,0,0,0,AW3,0,0,0,0,0,0,0,0~
,0,0,0,0,0,0,0,0,0,0,0,0)';
      OUTPUT_LOAD='(1.0,-1.0)';
      PINUSE='OUT';
    'UPI0_TX_DP14':
      PIN_NUMBER='(0,0,0,0,0,0,0,0,0,0,0,0,0,0,0,0,0,0,0,0,0,AV2,0,0,0,0,0,0,0,0~
,0,0,0,0,0,0,0,0,0,0,0,0)';
      OUTPUT_LOAD='(1.0,-1.0)';
      PINUSE='OUT';
    'UPI0_TX_DP13':
      PIN_NUMBER='(0,0,0,0,0,0,0,0,0,0,0,0,0,0,0,0,0,0,0,0,0,AR3,0,0,0,0,0,0,0,0~
,0,0,0,0,0,0,0,0,0,0,0,0)';
      OUTPUT_LOAD='(1.0,-1.0)';
      PINUSE='OUT';
    'UPI0_TX_DP12':
      PIN_NUMBER='(0,0,0,0,0,0,0,0,0,0,0,0,0,0,0,0,0,0,0,0,0,AN1,0,0,0,0,0,0,0,0~
,0,0,0,0,0,0,0,0,0,0,0,0)';
      OUTPUT_LOAD='(1.0,-1.0)';
      PINUSE='OUT';
    'UPI0_TX_DP11':
      PIN_NUMBER='(0,0,0,0,0,0,0,0,0,0,0,0,0,0,0,0,0,0,0,0,0,AL3,0,0,0,0,0,0,0,0~
,0,0,0,0,0,0,0,0,0,0,0,0)';
      OUTPUT_LOAD='(1.0,-1.0)';
      PINUSE='OUT';
    'UPI0_TX_DP10':
      PIN_NUMBER='(0,0,0,0,0,0,0,0,0,0,0,0,0,0,0,0,0,0,0,0,0,AJ1,0,0,0,0,0,0,0,0~
,0,0,0,0,0,0,0,0,0,0,0,0)';
      OUTPUT_LOAD='(1.0,-1.0)';
      PINUSE='OUT';
    'UPI0_TX_DP9':
      PIN_NUMBER='(0,0,0,0,0,0,0,0,0,0,0,0,0,0,0,0,0,0,0,0,0,AG3,0,0,0,0,0,0,0,0~
,0,0,0,0,0,0,0,0,0,0,0,0)';
      OUTPUT_LOAD='(1.0,-1.0)';
      PINUSE='OUT';
    'UPI0_TX_DP8':
      PIN_NUMBER='(0,0,0,0,0,0,0,0,0,0,0,0,0,0,0,0,0,0,0,0,0,AE1,0,0,0,0,0,0,0,0~
,0,0,0,0,0,0,0,0,0,0,0,0)';
      OUTPUT_LOAD='(1.0,-1.0)';
      PINUSE='OUT';
    'UPI0_TX_DP7':
      PIN_NUMBER='(0,0,0,0,0,0,0,0,0,0,0,0,0,0,0,0,0,0,0,0,0,AC3,0,0,0,0,0,0,0,0~
,0,0,0,0,0,0,0,0,0,0,0,0)';
      OUTPUT_LOAD='(1.0,-1.0)';
      PINUSE='OUT';
    'UPI0_TX_DP6':
      PIN_NUMBER='(0,0,0,0,0,0,0,0,0,0,0,0,0,0,0,0,0,0,0,0,0,AB2,0,0,0,0,0,0,0,0~
,0,0,0,0,0,0,0,0,0,0,0,0)';
      OUTPUT_LOAD='(1.0,-1.0)';
      PINUSE='OUT';
    'UPI0_TX_DP5':
      PIN_NUMBER='(0,0,0,0,0,0,0,0,0,0,0,0,0,0,0,0,0,0,0,0,0,W3,0,0,0,0,0,0,0,0,~
0,0,0,0,0,0,0,0,0,0,0,0)';
      OUTPUT_LOAD='(1.0,-1.0)';
      PINUSE='OUT';
    'UPI0_TX_DP4':
      PIN_NUMBER='(0,0,0,0,0,0,0,0,0,0,0,0,0,0,0,0,0,0,0,0,0,V2,0,0,0,0,0,0,0,0,~
0,0,0,0,0,0,0,0,0,0,0,0)';
      OUTPUT_LOAD='(1.0,-1.0)';
      PINUSE='OUT';
    'UPI0_TX_DP3':
      PIN_NUMBER='(0,0,0,0,0,0,0,0,0,0,0,0,0,0,0,0,0,0,0,0,0,R3,0,0,0,0,0,0,0,0,~
0,0,0,0,0,0,0,0,0,0,0,0)';
      OUTPUT_LOAD='(1.0,-1.0)';
      PINUSE='OUT';
    'UPI0_TX_DP2':
      PIN_NUMBER='(0,0,0,0,0,0,0,0,0,0,0,0,0,0,0,0,0,0,0,0,0,P2,0,0,0,0,0,0,0,0,~
0,0,0,0,0,0,0,0,0,0,0,0)';
      OUTPUT_LOAD='(1.0,-1.0)';
      PINUSE='OUT';
    'UPI0_TX_DP1':
      PIN_NUMBER='(0,0,0,0,0,0,0,0,0,0,0,0,0,0,0,0,0,0,0,0,0,L3,0,0,0,0,0,0,0,0,~
0,0,0,0,0,0,0,0,0,0,0,0)';
      OUTPUT_LOAD='(1.0,-1.0)';
      PINUSE='OUT';
    'UPI0_TX_DP0':
      PIN_NUMBER='(0,0,0,0,0,0,0,0,0,0,0,0,0,0,0,0,0,0,0,0,0,J3,0,0,0,0,0,0,0,0,~
0,0,0,0,0,0,0,0,0,0,0,0)';
      OUTPUT_LOAD='(1.0,-1.0)';
      PINUSE='OUT';
    'UPI1_RX_DN23':
      PIN_NUMBER='(0,0,0,0,0,0,0,0,0,0,0,0,0,0,0,0,0,0,0,0,0,0,CB2,0,0,0,0,0,0,0~
,0,0,0,0,0,0,0,0,0,0,0,0)';
      INPUT_LOAD='(-0.01,0.01)';
      PINUSE='IN';
    'UPI1_RX_DN22':
      PIN_NUMBER='(0,0,0,0,0,0,0,0,0,0,0,0,0,0,0,0,0,0,0,0,0,0,CD2,0,0,0,0,0,0,0~
,0,0,0,0,0,0,0,0,0,0,0,0)';
      INPUT_LOAD='(-0.01,0.01)';
      PINUSE='IN';
    'UPI1_RX_DN21':
      PIN_NUMBER='(0,0,0,0,0,0,0,0,0,0,0,0,0,0,0,0,0,0,0,0,0,0,CF2,0,0,0,0,0,0,0~
,0,0,0,0,0,0,0,0,0,0,0,0)';
      INPUT_LOAD='(-0.01,0.01)';
      PINUSE='IN';
    'UPI1_RX_DN20':
      PIN_NUMBER='(0,0,0,0,0,0,0,0,0,0,0,0,0,0,0,0,0,0,0,0,0,0,CH2,0,0,0,0,0,0,0~
,0,0,0,0,0,0,0,0,0,0,0,0)';
      INPUT_LOAD='(-0.01,0.01)';
      PINUSE='IN';
    'UPI1_RX_DN19':
      PIN_NUMBER='(0,0,0,0,0,0,0,0,0,0,0,0,0,0,0,0,0,0,0,0,0,0,CJ1,0,0,0,0,0,0,0~
,0,0,0,0,0,0,0,0,0,0,0,0)';
      INPUT_LOAD='(-0.01,0.01)';
      PINUSE='IN';
    'UPI1_RX_DN18':
      PIN_NUMBER='(0,0,0,0,0,0,0,0,0,0,0,0,0,0,0,0,0,0,0,0,0,0,CL3,0,0,0,0,0,0,0~
,0,0,0,0,0,0,0,0,0,0,0,0)';
      INPUT_LOAD='(-0.01,0.01)';
      PINUSE='IN';
    'UPI1_RX_DN17':
      PIN_NUMBER='(0,0,0,0,0,0,0,0,0,0,0,0,0,0,0,0,0,0,0,0,0,0,CN1,0,0,0,0,0,0,0~
,0,0,0,0,0,0,0,0,0,0,0,0)';
      INPUT_LOAD='(-0.01,0.01)';
      PINUSE='IN';
    'UPI1_RX_DN16':
      PIN_NUMBER='(0,0,0,0,0,0,0,0,0,0,0,0,0,0,0,0,0,0,0,0,0,0,CR3,0,0,0,0,0,0,0~
,0,0,0,0,0,0,0,0,0,0,0,0)';
      INPUT_LOAD='(-0.01,0.01)';
      PINUSE='IN';
    'UPI1_RX_DN15':
      PIN_NUMBER='(0,0,0,0,0,0,0,0,0,0,0,0,0,0,0,0,0,0,0,0,0,0,CV2,0,0,0,0,0,0,0~
,0,0,0,0,0,0,0,0,0,0,0,0)';
      INPUT_LOAD='(-0.01,0.01)';
      PINUSE='IN';
    'UPI1_RX_DN14':
      PIN_NUMBER='(0,0,0,0,0,0,0,0,0,0,0,0,0,0,0,0,0,0,0,0,0,0,CY2,0,0,0,0,0,0,0~
,0,0,0,0,0,0,0,0,0,0,0,0)';
      INPUT_LOAD='(-0.01,0.01)';
      PINUSE='IN';
    'UPI1_RX_DN13':
      PIN_NUMBER='(0,0,0,0,0,0,0,0,0,0,0,0,0,0,0,0,0,0,0,0,0,0,DB2,0,0,0,0,0,0,0~
,0,0,0,0,0,0,0,0,0,0,0,0)';
      INPUT_LOAD='(-0.01,0.01)';
      PINUSE='IN';
    'UPI1_RX_DN12':
      PIN_NUMBER='(0,0,0,0,0,0,0,0,0,0,0,0,0,0,0,0,0,0,0,0,0,0,DD2,0,0,0,0,0,0,0~
,0,0,0,0,0,0,0,0,0,0,0,0)';
      INPUT_LOAD='(-0.01,0.01)';
      PINUSE='IN';
    'UPI1_RX_DN11':
      PIN_NUMBER='(0,0,0,0,0,0,0,0,0,0,0,0,0,0,0,0,0,0,0,0,0,0,DE1,0,0,0,0,0,0,0~
,0,0,0,0,0,0,0,0,0,0,0,0)';
      INPUT_LOAD='(-0.01,0.01)';
      PINUSE='IN';
    'UPI1_RX_DN10':
      PIN_NUMBER='(0,0,0,0,0,0,0,0,0,0,0,0,0,0,0,0,0,0,0,0,0,0,DG3,0,0,0,0,0,0,0~
,0,0,0,0,0,0,0,0,0,0,0,0)';
      INPUT_LOAD='(-0.01,0.01)';
      PINUSE='IN';
    'UPI1_RX_DN9':
      PIN_NUMBER='(0,0,0,0,0,0,0,0,0,0,0,0,0,0,0,0,0,0,0,0,0,0,DJ1,0,0,0,0,0,0,0~
,0,0,0,0,0,0,0,0,0,0,0,0)';
      INPUT_LOAD='(-0.01,0.01)';
      PINUSE='IN';
    'UPI1_RX_DN8':
      PIN_NUMBER='(0,0,0,0,0,0,0,0,0,0,0,0,0,0,0,0,0,0,0,0,0,0,DL3,0,0,0,0,0,0,0~
,0,0,0,0,0,0,0,0,0,0,0,0)';
      INPUT_LOAD='(-0.01,0.01)';
      PINUSE='IN';
    'UPI1_RX_DN7':
      PIN_NUMBER='(0,0,0,0,0,0,0,0,0,0,0,0,0,0,0,0,0,0,0,0,0,0,DN1,0,0,0,0,0,0,0~
,0,0,0,0,0,0,0,0,0,0,0,0)';
      INPUT_LOAD='(-0.01,0.01)';
      PINUSE='IN';
    'UPI1_RX_DN6':
      PIN_NUMBER='(0,0,0,0,0,0,0,0,0,0,0,0,0,0,0,0,0,0,0,0,0,0,DT2,0,0,0,0,0,0,0~
,0,0,0,0,0,0,0,0,0,0,0,0)';
      INPUT_LOAD='(-0.01,0.01)';
      PINUSE='IN';
    'UPI1_RX_DN5':
      PIN_NUMBER='(0,0,0,0,0,0,0,0,0,0,0,0,0,0,0,0,0,0,0,0,0,0,DU1,0,0,0,0,0,0,0~
,0,0,0,0,0,0,0,0,0,0,0,0)';
      INPUT_LOAD='(-0.01,0.01)';
      PINUSE='IN';
    'UPI1_RX_DN4':
      PIN_NUMBER='(0,0,0,0,0,0,0,0,0,0,0,0,0,0,0,0,0,0,0,0,0,0,DY2,0,0,0,0,0,0,0~
,0,0,0,0,0,0,0,0,0,0,0,0)';
      INPUT_LOAD='(-0.01,0.01)';
      PINUSE='IN';
    'UPI1_RX_DN3':
      PIN_NUMBER='(0,0,0,0,0,0,0,0,0,0,0,0,0,0,0,0,0,0,0,0,0,0,EA1,0,0,0,0,0,0,0~
,0,0,0,0,0,0,0,0,0,0,0,0)';
      INPUT_LOAD='(-0.01,0.01)';
      PINUSE='IN';
    'UPI1_RX_DN2':
      PIN_NUMBER='(0,0,0,0,0,0,0,0,0,0,0,0,0,0,0,0,0,0,0,0,0,0,ED2,0,0,0,0,0,0,0~
,0,0,0,0,0,0,0,0,0,0,0,0)';
      INPUT_LOAD='(-0.01,0.01)';
      PINUSE='IN';
    'UPI1_RX_DN1':
      PIN_NUMBER='(0,0,0,0,0,0,0,0,0,0,0,0,0,0,0,0,0,0,0,0,0,0,EE3,0,0,0,0,0,0,0~
,0,0,0,0,0,0,0,0,0,0,0,0)';
      INPUT_LOAD='(-0.01,0.01)';
      PINUSE='IN';
    'UPI1_RX_DN0':
      PIN_NUMBER='(0,0,0,0,0,0,0,0,0,0,0,0,0,0,0,0,0,0,0,0,0,0,EH2,0,0,0,0,0,0,0~
,0,0,0,0,0,0,0,0,0,0,0,0)';
      INPUT_LOAD='(-0.01,0.01)';
      PINUSE='IN';
    'UPI1_RX_DP23':
      PIN_NUMBER='(0,0,0,0,0,0,0,0,0,0,0,0,0,0,0,0,0,0,0,0,0,0,BY2,0,0,0,0,0,0,0~
,0,0,0,0,0,0,0,0,0,0,0,0)';
      INPUT_LOAD='(-0.01,0.01)';
      PINUSE='IN';
    'UPI1_RX_DP22':
      PIN_NUMBER='(0,0,0,0,0,0,0,0,0,0,0,0,0,0,0,0,0,0,0,0,0,0,CC3,0,0,0,0,0,0,0~
,0,0,0,0,0,0,0,0,0,0,0,0)';
      INPUT_LOAD='(-0.01,0.01)';
      PINUSE='IN';
    'UPI1_RX_DP21':
      PIN_NUMBER='(0,0,0,0,0,0,0,0,0,0,0,0,0,0,0,0,0,0,0,0,0,0,CE1,0,0,0,0,0,0,0~
,0,0,0,0,0,0,0,0,0,0,0,0)';
      INPUT_LOAD='(-0.01,0.01)';
      PINUSE='IN';
    'UPI1_RX_DP20':
      PIN_NUMBER='(0,0,0,0,0,0,0,0,0,0,0,0,0,0,0,0,0,0,0,0,0,0,CG3,0,0,0,0,0,0,0~
,0,0,0,0,0,0,0,0,0,0,0,0)';
      INPUT_LOAD='(-0.01,0.01)';
      PINUSE='IN';
    'UPI1_RX_DP19':
      PIN_NUMBER='(0,0,0,0,0,0,0,0,0,0,0,0,0,0,0,0,0,0,0,0,0,0,CK2,0,0,0,0,0,0,0~
,0,0,0,0,0,0,0,0,0,0,0,0)';
      INPUT_LOAD='(-0.01,0.01)';
      PINUSE='IN';
    'UPI1_RX_DP18':
      PIN_NUMBER='(0,0,0,0,0,0,0,0,0,0,0,0,0,0,0,0,0,0,0,0,0,0,CM2,0,0,0,0,0,0,0~
,0,0,0,0,0,0,0,0,0,0,0,0)';
      INPUT_LOAD='(-0.01,0.01)';
      PINUSE='IN';
    'UPI1_RX_DP17':
      PIN_NUMBER='(0,0,0,0,0,0,0,0,0,0,0,0,0,0,0,0,0,0,0,0,0,0,CP2,0,0,0,0,0,0,0~
,0,0,0,0,0,0,0,0,0,0,0,0)';
      INPUT_LOAD='(-0.01,0.01)';
      PINUSE='IN';
    'UPI1_RX_DP16':
      PIN_NUMBER='(0,0,0,0,0,0,0,0,0,0,0,0,0,0,0,0,0,0,0,0,0,0,CT2,0,0,0,0,0,0,0~
,0,0,0,0,0,0,0,0,0,0,0,0)';
      INPUT_LOAD='(-0.01,0.01)';
      PINUSE='IN';
    'UPI1_RX_DP15':
      PIN_NUMBER='(0,0,0,0,0,0,0,0,0,0,0,0,0,0,0,0,0,0,0,0,0,0,CU1,0,0,0,0,0,0,0~
,0,0,0,0,0,0,0,0,0,0,0,0)';
      INPUT_LOAD='(-0.01,0.01)';
      PINUSE='IN';
    'UPI1_RX_DP14':
      PIN_NUMBER='(0,0,0,0,0,0,0,0,0,0,0,0,0,0,0,0,0,0,0,0,0,0,CW3,0,0,0,0,0,0,0~
,0,0,0,0,0,0,0,0,0,0,0,0)';
      INPUT_LOAD='(-0.01,0.01)';
      PINUSE='IN';
    'UPI1_RX_DP13':
      PIN_NUMBER='(0,0,0,0,0,0,0,0,0,0,0,0,0,0,0,0,0,0,0,0,0,0,DA1,0,0,0,0,0,0,0~
,0,0,0,0,0,0,0,0,0,0,0,0)';
      INPUT_LOAD='(-0.01,0.01)';
      PINUSE='IN';
    'UPI1_RX_DP12':
      PIN_NUMBER='(0,0,0,0,0,0,0,0,0,0,0,0,0,0,0,0,0,0,0,0,0,0,DC3,0,0,0,0,0,0,0~
,0,0,0,0,0,0,0,0,0,0,0,0)';
      INPUT_LOAD='(-0.01,0.01)';
      PINUSE='IN';
    'UPI1_RX_DP11':
      PIN_NUMBER='(0,0,0,0,0,0,0,0,0,0,0,0,0,0,0,0,0,0,0,0,0,0,DF2,0,0,0,0,0,0,0~
,0,0,0,0,0,0,0,0,0,0,0,0)';
      INPUT_LOAD='(-0.01,0.01)';
      PINUSE='IN';
    'UPI1_RX_DP10':
      PIN_NUMBER='(0,0,0,0,0,0,0,0,0,0,0,0,0,0,0,0,0,0,0,0,0,0,DH2,0,0,0,0,0,0,0~
,0,0,0,0,0,0,0,0,0,0,0,0)';
      INPUT_LOAD='(-0.01,0.01)';
      PINUSE='IN';
    'UPI1_RX_DP9':
      PIN_NUMBER='(0,0,0,0,0,0,0,0,0,0,0,0,0,0,0,0,0,0,0,0,0,0,DK2,0,0,0,0,0,0,0~
,0,0,0,0,0,0,0,0,0,0,0,0)';
      INPUT_LOAD='(-0.01,0.01)';
      PINUSE='IN';
    'UPI1_RX_DP8':
      PIN_NUMBER='(0,0,0,0,0,0,0,0,0,0,0,0,0,0,0,0,0,0,0,0,0,0,DM2,0,0,0,0,0,0,0~
,0,0,0,0,0,0,0,0,0,0,0,0)';
      INPUT_LOAD='(-0.01,0.01)';
      PINUSE='IN';
    'UPI1_RX_DP7':
      PIN_NUMBER='(0,0,0,0,0,0,0,0,0,0,0,0,0,0,0,0,0,0,0,0,0,0,DP2,0,0,0,0,0,0,0~
,0,0,0,0,0,0,0,0,0,0,0,0)';
      INPUT_LOAD='(-0.01,0.01)';
      PINUSE='IN';
    'UPI1_RX_DP6':
      PIN_NUMBER='(0,0,0,0,0,0,0,0,0,0,0,0,0,0,0,0,0,0,0,0,0,0,DR3,0,0,0,0,0,0,0~
,0,0,0,0,0,0,0,0,0,0,0,0)';
      INPUT_LOAD='(-0.01,0.01)';
      PINUSE='IN';
    'UPI1_RX_DP5':
      PIN_NUMBER='(0,0,0,0,0,0,0,0,0,0,0,0,0,0,0,0,0,0,0,0,0,0,DV2,0,0,0,0,0,0,0~
,0,0,0,0,0,0,0,0,0,0,0,0)';
      INPUT_LOAD='(-0.01,0.01)';
      PINUSE='IN';
    'UPI1_RX_DP4':
      PIN_NUMBER='(0,0,0,0,0,0,0,0,0,0,0,0,0,0,0,0,0,0,0,0,0,0,DW3,0,0,0,0,0,0,0~
,0,0,0,0,0,0,0,0,0,0,0,0)';
      INPUT_LOAD='(-0.01,0.01)';
      PINUSE='IN';
    'UPI1_RX_DP3':
      PIN_NUMBER='(0,0,0,0,0,0,0,0,0,0,0,0,0,0,0,0,0,0,0,0,0,0,EB2,0,0,0,0,0,0,0~
,0,0,0,0,0,0,0,0,0,0,0,0)';
      INPUT_LOAD='(-0.01,0.01)';
      PINUSE='IN';
    'UPI1_RX_DP2':
      PIN_NUMBER='(0,0,0,0,0,0,0,0,0,0,0,0,0,0,0,0,0,0,0,0,0,0,EC3,0,0,0,0,0,0,0~
,0,0,0,0,0,0,0,0,0,0,0,0)';
      INPUT_LOAD='(-0.01,0.01)';
      PINUSE='IN';
    'UPI1_RX_DP1':
      PIN_NUMBER='(0,0,0,0,0,0,0,0,0,0,0,0,0,0,0,0,0,0,0,0,0,0,EG3,0,0,0,0,0,0,0~
,0,0,0,0,0,0,0,0,0,0,0,0)';
      INPUT_LOAD='(-0.01,0.01)';
      PINUSE='IN';
    'UPI1_RX_DP0':
      PIN_NUMBER='(0,0,0,0,0,0,0,0,0,0,0,0,0,0,0,0,0,0,0,0,0,0,EJ3,0,0,0,0,0,0,0~
,0,0,0,0,0,0,0,0,0,0,0,0)';
      INPUT_LOAD='(-0.01,0.01)';
      PINUSE='IN';
    'UPI1_TX_DN23':
      PIN_NUMBER='(0,0,0,0,0,0,0,0,0,0,0,0,0,0,0,0,0,0,0,0,0,0,BY6,0,0,0,0,0,0,0~
,0,0,0,0,0,0,0,0,0,0,0,0)';
      OUTPUT_LOAD='(1.0,-1.0)';
      PINUSE='OUT';
    'UPI1_TX_DN22':
      PIN_NUMBER='(0,0,0,0,0,0,0,0,0,0,0,0,0,0,0,0,0,0,0,0,0,0,CA5,0,0,0,0,0,0,0~
,0,0,0,0,0,0,0,0,0,0,0,0)';
      OUTPUT_LOAD='(1.0,-1.0)';
      PINUSE='OUT';
    'UPI1_TX_DN21':
      PIN_NUMBER='(0,0,0,0,0,0,0,0,0,0,0,0,0,0,0,0,0,0,0,0,0,0,CD6,0,0,0,0,0,0,0~
,0,0,0,0,0,0,0,0,0,0,0,0)';
      OUTPUT_LOAD='(1.0,-1.0)';
      PINUSE='OUT';
    'UPI1_TX_DN20':
      PIN_NUMBER='(0,0,0,0,0,0,0,0,0,0,0,0,0,0,0,0,0,0,0,0,0,0,CE5,0,0,0,0,0,0,0~
,0,0,0,0,0,0,0,0,0,0,0,0)';
      OUTPUT_LOAD='(1.0,-1.0)';
      PINUSE='OUT';
    'UPI1_TX_DN19':
      PIN_NUMBER='(0,0,0,0,0,0,0,0,0,0,0,0,0,0,0,0,0,0,0,0,0,0,CH6,0,0,0,0,0,0,0~
,0,0,0,0,0,0,0,0,0,0,0,0)';
      OUTPUT_LOAD='(1.0,-1.0)';
      PINUSE='OUT';
    'UPI1_TX_DN18':
      PIN_NUMBER='(0,0,0,0,0,0,0,0,0,0,0,0,0,0,0,0,0,0,0,0,0,0,CJ5,0,0,0,0,0,0,0~
,0,0,0,0,0,0,0,0,0,0,0,0)';
      OUTPUT_LOAD='(1.0,-1.0)';
      PINUSE='OUT';
    'UPI1_TX_DN17':
      PIN_NUMBER='(0,0,0,0,0,0,0,0,0,0,0,0,0,0,0,0,0,0,0,0,0,0,CM6,0,0,0,0,0,0,0~
,0,0,0,0,0,0,0,0,0,0,0,0)';
      OUTPUT_LOAD='(1.0,-1.0)';
      PINUSE='OUT';
    'UPI1_TX_DN16':
      PIN_NUMBER='(0,0,0,0,0,0,0,0,0,0,0,0,0,0,0,0,0,0,0,0,0,0,CN5,0,0,0,0,0,0,0~
,0,0,0,0,0,0,0,0,0,0,0,0)';
      OUTPUT_LOAD='(1.0,-1.0)';
      PINUSE='OUT';
    'UPI1_TX_DN15':
      PIN_NUMBER='(0,0,0,0,0,0,0,0,0,0,0,0,0,0,0,0,0,0,0,0,0,0,CT6,0,0,0,0,0,0,0~
,0,0,0,0,0,0,0,0,0,0,0,0)';
      OUTPUT_LOAD='(1.0,-1.0)';
      PINUSE='OUT';
    'UPI1_TX_DN14':
      PIN_NUMBER='(0,0,0,0,0,0,0,0,0,0,0,0,0,0,0,0,0,0,0,0,0,0,CU5,0,0,0,0,0,0,0~
,0,0,0,0,0,0,0,0,0,0,0,0)';
      OUTPUT_LOAD='(1.0,-1.0)';
      PINUSE='OUT';
    'UPI1_TX_DN13':
      PIN_NUMBER='(0,0,0,0,0,0,0,0,0,0,0,0,0,0,0,0,0,0,0,0,0,0,CY6,0,0,0,0,0,0,0~
,0,0,0,0,0,0,0,0,0,0,0,0)';
      OUTPUT_LOAD='(1.0,-1.0)';
      PINUSE='OUT';
    'UPI1_TX_DN12':
      PIN_NUMBER='(0,0,0,0,0,0,0,0,0,0,0,0,0,0,0,0,0,0,0,0,0,0,DA5,0,0,0,0,0,0,0~
,0,0,0,0,0,0,0,0,0,0,0,0)';
      OUTPUT_LOAD='(1.0,-1.0)';
      PINUSE='OUT';
    'UPI1_TX_DN11':
      PIN_NUMBER='(0,0,0,0,0,0,0,0,0,0,0,0,0,0,0,0,0,0,0,0,0,0,DD6,0,0,0,0,0,0,0~
,0,0,0,0,0,0,0,0,0,0,0,0)';
      OUTPUT_LOAD='(1.0,-1.0)';
      PINUSE='OUT';
    'UPI1_TX_DN10':
      PIN_NUMBER='(0,0,0,0,0,0,0,0,0,0,0,0,0,0,0,0,0,0,0,0,0,0,DE5,0,0,0,0,0,0,0~
,0,0,0,0,0,0,0,0,0,0,0,0)';
      OUTPUT_LOAD='(1.0,-1.0)';
      PINUSE='OUT';
    'UPI1_TX_DN9':
      PIN_NUMBER='(0,0,0,0,0,0,0,0,0,0,0,0,0,0,0,0,0,0,0,0,0,0,DH6,0,0,0,0,0,0,0~
,0,0,0,0,0,0,0,0,0,0,0,0)';
      OUTPUT_LOAD='(1.0,-1.0)';
      PINUSE='OUT';
    'UPI1_TX_DN8':
      PIN_NUMBER='(0,0,0,0,0,0,0,0,0,0,0,0,0,0,0,0,0,0,0,0,0,0,DK6,0,0,0,0,0,0,0~
,0,0,0,0,0,0,0,0,0,0,0,0)';
      OUTPUT_LOAD='(1.0,-1.0)';
      PINUSE='OUT';
    'UPI1_TX_DN7':
      PIN_NUMBER='(0,0,0,0,0,0,0,0,0,0,0,0,0,0,0,0,0,0,0,0,0,0,DL7,0,0,0,0,0,0,0~
,0,0,0,0,0,0,0,0,0,0,0,0)';
      OUTPUT_LOAD='(1.0,-1.0)';
      PINUSE='OUT';
    'UPI1_TX_DN6':
      PIN_NUMBER='(0,0,0,0,0,0,0,0,0,0,0,0,0,0,0,0,0,0,0,0,0,0,DP6,0,0,0,0,0,0,0~
,0,0,0,0,0,0,0,0,0,0,0,0)';
      OUTPUT_LOAD='(1.0,-1.0)';
      PINUSE='OUT';
    'UPI1_TX_DN5':
      PIN_NUMBER='(0,0,0,0,0,0,0,0,0,0,0,0,0,0,0,0,0,0,0,0,0,0,DT6,0,0,0,0,0,0,0~
,0,0,0,0,0,0,0,0,0,0,0,0)';
      OUTPUT_LOAD='(1.0,-1.0)';
      PINUSE='OUT';
    'UPI1_TX_DN4':
      PIN_NUMBER='(0,0,0,0,0,0,0,0,0,0,0,0,0,0,0,0,0,0,0,0,0,0,DV6,0,0,0,0,0,0,0~
,0,0,0,0,0,0,0,0,0,0,0,0)';
      OUTPUT_LOAD='(1.0,-1.0)';
      PINUSE='OUT';
    'UPI1_TX_DN3':
      PIN_NUMBER='(0,0,0,0,0,0,0,0,0,0,0,0,0,0,0,0,0,0,0,0,0,0,DY6,0,0,0,0,0,0,0~
,0,0,0,0,0,0,0,0,0,0,0,0)';
      OUTPUT_LOAD='(1.0,-1.0)';
      PINUSE='OUT';
    'UPI1_TX_DN2':
      PIN_NUMBER='(0,0,0,0,0,0,0,0,0,0,0,0,0,0,0,0,0,0,0,0,0,0,EB6,0,0,0,0,0,0,0~
,0,0,0,0,0,0,0,0,0,0,0,0)';
      OUTPUT_LOAD='(1.0,-1.0)';
      PINUSE='OUT';
    'UPI1_TX_DN1':
      PIN_NUMBER='(0,0,0,0,0,0,0,0,0,0,0,0,0,0,0,0,0,0,0,0,0,0,EC7,0,0,0,0,0,0,0~
,0,0,0,0,0,0,0,0,0,0,0,0)';
      OUTPUT_LOAD='(1.0,-1.0)';
      PINUSE='OUT';
    'UPI1_TX_DN0':
      PIN_NUMBER='(0,0,0,0,0,0,0,0,0,0,0,0,0,0,0,0,0,0,0,0,0,0,EF6,0,0,0,0,0,0,0~
,0,0,0,0,0,0,0,0,0,0,0,0)';
      OUTPUT_LOAD='(1.0,-1.0)';
      PINUSE='OUT';
    'UPI1_TX_DP23':
      PIN_NUMBER='(0,0,0,0,0,0,0,0,0,0,0,0,0,0,0,0,0,0,0,0,0,0,BW7,0,0,0,0,0,0,0~
,0,0,0,0,0,0,0,0,0,0,0,0)';
      OUTPUT_LOAD='(1.0,-1.0)';
      PINUSE='OUT';
    'UPI1_TX_DP22':
      PIN_NUMBER='(0,0,0,0,0,0,0,0,0,0,0,0,0,0,0,0,0,0,0,0,0,0,CB6,0,0,0,0,0,0,0~
,0,0,0,0,0,0,0,0,0,0,0,0)';
      OUTPUT_LOAD='(1.0,-1.0)';
      PINUSE='OUT';
    'UPI1_TX_DP21':
      PIN_NUMBER='(0,0,0,0,0,0,0,0,0,0,0,0,0,0,0,0,0,0,0,0,0,0,CC7,0,0,0,0,0,0,0~
,0,0,0,0,0,0,0,0,0,0,0,0)';
      OUTPUT_LOAD='(1.0,-1.0)';
      PINUSE='OUT';
    'UPI1_TX_DP20':
      PIN_NUMBER='(0,0,0,0,0,0,0,0,0,0,0,0,0,0,0,0,0,0,0,0,0,0,CF6,0,0,0,0,0,0,0~
,0,0,0,0,0,0,0,0,0,0,0,0)';
      OUTPUT_LOAD='(1.0,-1.0)';
      PINUSE='OUT';
    'UPI1_TX_DP19':
      PIN_NUMBER='(0,0,0,0,0,0,0,0,0,0,0,0,0,0,0,0,0,0,0,0,0,0,CG7,0,0,0,0,0,0,0~
,0,0,0,0,0,0,0,0,0,0,0,0)';
      OUTPUT_LOAD='(1.0,-1.0)';
      PINUSE='OUT';
    'UPI1_TX_DP18':
      PIN_NUMBER='(0,0,0,0,0,0,0,0,0,0,0,0,0,0,0,0,0,0,0,0,0,0,CK6,0,0,0,0,0,0,0~
,0,0,0,0,0,0,0,0,0,0,0,0)';
      OUTPUT_LOAD='(1.0,-1.0)';
      PINUSE='OUT';
    'UPI1_TX_DP17':
      PIN_NUMBER='(0,0,0,0,0,0,0,0,0,0,0,0,0,0,0,0,0,0,0,0,0,0,CL7,0,0,0,0,0,0,0~
,0,0,0,0,0,0,0,0,0,0,0,0)';
      OUTPUT_LOAD='(1.0,-1.0)';
      PINUSE='OUT';
    'UPI1_TX_DP16':
      PIN_NUMBER='(0,0,0,0,0,0,0,0,0,0,0,0,0,0,0,0,0,0,0,0,0,0,CP6,0,0,0,0,0,0,0~
,0,0,0,0,0,0,0,0,0,0,0,0)';
      OUTPUT_LOAD='(1.0,-1.0)';
      PINUSE='OUT';
    'UPI1_TX_DP15':
      PIN_NUMBER='(0,0,0,0,0,0,0,0,0,0,0,0,0,0,0,0,0,0,0,0,0,0,CR7,0,0,0,0,0,0,0~
,0,0,0,0,0,0,0,0,0,0,0,0)';
      OUTPUT_LOAD='(1.0,-1.0)';
      PINUSE='OUT';
    'UPI1_TX_DP14':
      PIN_NUMBER='(0,0,0,0,0,0,0,0,0,0,0,0,0,0,0,0,0,0,0,0,0,0,CV6,0,0,0,0,0,0,0~
,0,0,0,0,0,0,0,0,0,0,0,0)';
      OUTPUT_LOAD='(1.0,-1.0)';
      PINUSE='OUT';
    'UPI1_TX_DP13':
      PIN_NUMBER='(0,0,0,0,0,0,0,0,0,0,0,0,0,0,0,0,0,0,0,0,0,0,CW7,0,0,0,0,0,0,0~
,0,0,0,0,0,0,0,0,0,0,0,0)';
      OUTPUT_LOAD='(1.0,-1.0)';
      PINUSE='OUT';
    'UPI1_TX_DP12':
      PIN_NUMBER='(0,0,0,0,0,0,0,0,0,0,0,0,0,0,0,0,0,0,0,0,0,0,DB6,0,0,0,0,0,0,0~
,0,0,0,0,0,0,0,0,0,0,0,0)';
      OUTPUT_LOAD='(1.0,-1.0)';
      PINUSE='OUT';
    'UPI1_TX_DP11':
      PIN_NUMBER='(0,0,0,0,0,0,0,0,0,0,0,0,0,0,0,0,0,0,0,0,0,0,DC7,0,0,0,0,0,0,0~
,0,0,0,0,0,0,0,0,0,0,0,0)';
      OUTPUT_LOAD='(1.0,-1.0)';
      PINUSE='OUT';
    'UPI1_TX_DP10':
      PIN_NUMBER='(0,0,0,0,0,0,0,0,0,0,0,0,0,0,0,0,0,0,0,0,0,0,DF6,0,0,0,0,0,0,0~
,0,0,0,0,0,0,0,0,0,0,0,0)';
      OUTPUT_LOAD='(1.0,-1.0)';
      PINUSE='OUT';
    'UPI1_TX_DP9':
      PIN_NUMBER='(0,0,0,0,0,0,0,0,0,0,0,0,0,0,0,0,0,0,0,0,0,0,DG7,0,0,0,0,0,0,0~
,0,0,0,0,0,0,0,0,0,0,0,0)';
      OUTPUT_LOAD='(1.0,-1.0)';
      PINUSE='OUT';
    'UPI1_TX_DP8':
      PIN_NUMBER='(0,0,0,0,0,0,0,0,0,0,0,0,0,0,0,0,0,0,0,0,0,0,DJ5,0,0,0,0,0,0,0~
,0,0,0,0,0,0,0,0,0,0,0,0)';
      OUTPUT_LOAD='(1.0,-1.0)';
      PINUSE='OUT';
    'UPI1_TX_DP7':
      PIN_NUMBER='(0,0,0,0,0,0,0,0,0,0,0,0,0,0,0,0,0,0,0,0,0,0,DM6,0,0,0,0,0,0,0~
,0,0,0,0,0,0,0,0,0,0,0,0)';
      OUTPUT_LOAD='(1.0,-1.0)';
      PINUSE='OUT';
    'UPI1_TX_DP6':
      PIN_NUMBER='(0,0,0,0,0,0,0,0,0,0,0,0,0,0,0,0,0,0,0,0,0,0,DN5,0,0,0,0,0,0,0~
,0,0,0,0,0,0,0,0,0,0,0,0)';
      OUTPUT_LOAD='(1.0,-1.0)';
      PINUSE='OUT';
    'UPI1_TX_DP5':
      PIN_NUMBER='(0,0,0,0,0,0,0,0,0,0,0,0,0,0,0,0,0,0,0,0,0,0,DR7,0,0,0,0,0,0,0~
,0,0,0,0,0,0,0,0,0,0,0,0)';
      OUTPUT_LOAD='(1.0,-1.0)';
      PINUSE='OUT';
    'UPI1_TX_DP4':
      PIN_NUMBER='(0,0,0,0,0,0,0,0,0,0,0,0,0,0,0,0,0,0,0,0,0,0,DU5,0,0,0,0,0,0,0~
,0,0,0,0,0,0,0,0,0,0,0,0)';
      OUTPUT_LOAD='(1.0,-1.0)';
      PINUSE='OUT';
    'UPI1_TX_DP3':
      PIN_NUMBER='(0,0,0,0,0,0,0,0,0,0,0,0,0,0,0,0,0,0,0,0,0,0,DW7,0,0,0,0,0,0,0~
,0,0,0,0,0,0,0,0,0,0,0,0)';
      OUTPUT_LOAD='(1.0,-1.0)';
      PINUSE='OUT';
    'UPI1_TX_DP2':
      PIN_NUMBER='(0,0,0,0,0,0,0,0,0,0,0,0,0,0,0,0,0,0,0,0,0,0,EA5,0,0,0,0,0,0,0~
,0,0,0,0,0,0,0,0,0,0,0,0)';
      OUTPUT_LOAD='(1.0,-1.0)';
      PINUSE='OUT';
    'UPI1_TX_DP1':
      PIN_NUMBER='(0,0,0,0,0,0,0,0,0,0,0,0,0,0,0,0,0,0,0,0,0,0,ED6,0,0,0,0,0,0,0~
,0,0,0,0,0,0,0,0,0,0,0,0)';
      OUTPUT_LOAD='(1.0,-1.0)';
      PINUSE='OUT';
    'UPI1_TX_DP0':
      PIN_NUMBER='(0,0,0,0,0,0,0,0,0,0,0,0,0,0,0,0,0,0,0,0,0,0,EE5,0,0,0,0,0,0,0~
,0,0,0,0,0,0,0,0,0,0,0,0)';
      OUTPUT_LOAD='(1.0,-1.0)';
      PINUSE='OUT';
    'UPI2_RX_DN23':
      PIN_NUMBER='(0,0,0,0,0,0,0,0,0,0,0,0,0,0,0,0,0,0,0,0,0,0,0,BD73,0,0,0,0,0,~
0,0,0,0,0,0,0,0,0,0,0,0,0)';
      INPUT_LOAD='(-0.01,0.01)';
      PINUSE='IN';
    'UPI2_RX_DN22':
      PIN_NUMBER='(0,0,0,0,0,0,0,0,0,0,0,0,0,0,0,0,0,0,0,0,0,0,0,BK73,0,0,0,0,0,~
0,0,0,0,0,0,0,0,0,0,0,0,0)';
      INPUT_LOAD='(-0.01,0.01)';
      PINUSE='IN';
    'UPI2_RX_DN21':
      PIN_NUMBER='(0,0,0,0,0,0,0,0,0,0,0,0,0,0,0,0,0,0,0,0,0,0,0,BN74,0,0,0,0,0,~
0,0,0,0,0,0,0,0,0,0,0,0,0)';
      INPUT_LOAD='(-0.01,0.01)';
      PINUSE='IN';
    'UPI2_RX_DN20':
      PIN_NUMBER='(0,0,0,0,0,0,0,0,0,0,0,0,0,0,0,0,0,0,0,0,0,0,0,BG74,0,0,0,0,0,~
0,0,0,0,0,0,0,0,0,0,0,0,0)';
      INPUT_LOAD='(-0.01,0.01)';
      PINUSE='IN';
    'UPI2_RX_DN19':
      PIN_NUMBER='(0,0,0,0,0,0,0,0,0,0,0,0,0,0,0,0,0,0,0,0,0,0,0,BL76,0,0,0,0,0,~
0,0,0,0,0,0,0,0,0,0,0,0,0)';
      INPUT_LOAD='(-0.01,0.01)';
      PINUSE='IN';
    'UPI2_RX_DN18':
      PIN_NUMBER='(0,0,0,0,0,0,0,0,0,0,0,0,0,0,0,0,0,0,0,0,0,0,0,BJ76,0,0,0,0,0,~
0,0,0,0,0,0,0,0,0,0,0,0,0)';
      INPUT_LOAD='(-0.01,0.01)';
      PINUSE='IN';
    'UPI2_RX_DN17':
      PIN_NUMBER='(0,0,0,0,0,0,0,0,0,0,0,0,0,0,0,0,0,0,0,0,0,0,0,BH75,0,0,0,0,0,~
0,0,0,0,0,0,0,0,0,0,0,0,0)';
      INPUT_LOAD='(-0.01,0.01)';
      PINUSE='IN';
    'UPI2_RX_DN16':
      PIN_NUMBER='(0,0,0,0,0,0,0,0,0,0,0,0,0,0,0,0,0,0,0,0,0,0,0,AW74,0,0,0,0,0,~
0,0,0,0,0,0,0,0,0,0,0,0,0)';
      INPUT_LOAD='(-0.01,0.01)';
      PINUSE='IN';
    'UPI2_RX_DN15':
      PIN_NUMBER='(0,0,0,0,0,0,0,0,0,0,0,0,0,0,0,0,0,0,0,0,0,0,0,BB75,0,0,0,0,0,~
0,0,0,0,0,0,0,0,0,0,0,0,0)';
      INPUT_LOAD='(-0.01,0.01)';
      PINUSE='IN';
    'UPI2_RX_DN14':
      PIN_NUMBER='(0,0,0,0,0,0,0,0,0,0,0,0,0,0,0,0,0,0,0,0,0,0,0,AY75,0,0,0,0,0,~
0,0,0,0,0,0,0,0,0,0,0,0,0)';
      INPUT_LOAD='(-0.01,0.01)';
      PINUSE='IN';
    'UPI2_RX_DN13':
      PIN_NUMBER='(0,0,0,0,0,0,0,0,0,0,0,0,0,0,0,0,0,0,0,0,0,0,0,AV73,0,0,0,0,0,~
0,0,0,0,0,0,0,0,0,0,0,0,0)';
      INPUT_LOAD='(-0.01,0.01)';
      PINUSE='IN';
    'UPI2_RX_DN12':
      PIN_NUMBER='(0,0,0,0,0,0,0,0,0,0,0,0,0,0,0,0,0,0,0,0,0,0,0,BA72,0,0,0,0,0,~
0,0,0,0,0,0,0,0,0,0,0,0,0)';
      INPUT_LOAD='(-0.01,0.01)';
      PINUSE='IN';
    'UPI2_RX_DN11':
      PIN_NUMBER='(0,0,0,0,0,0,0,0,0,0,0,0,0,0,0,0,0,0,0,0,0,0,0,AG82,0,0,0,0,0,~
0,0,0,0,0,0,0,0,0,0,0,0,0)';
      INPUT_LOAD='(-0.01,0.01)';
      PINUSE='IN';
    'UPI2_RX_DN10':
      PIN_NUMBER='(0,0,0,0,0,0,0,0,0,0,0,0,0,0,0,0,0,0,0,0,0,0,0,AJ80,0,0,0,0,0,~
0,0,0,0,0,0,0,0,0,0,0,0,0)';
      INPUT_LOAD='(-0.01,0.01)';
      PINUSE='IN';
    'UPI2_RX_DN9':
      PIN_NUMBER='(0,0,0,0,0,0,0,0,0,0,0,0,0,0,0,0,0,0,0,0,0,0,0,AE82,0,0,0,0,0,~
0,0,0,0,0,0,0,0,0,0,0,0,0)';
      INPUT_LOAD='(-0.01,0.01)';
      PINUSE='IN';
    'UPI2_RX_DN8':
      PIN_NUMBER='(0,0,0,0,0,0,0,0,0,0,0,0,0,0,0,0,0,0,0,0,0,0,0,AF79,0,0,0,0,0,~
0,0,0,0,0,0,0,0,0,0,0,0,0)';
      INPUT_LOAD='(-0.01,0.01)';
      PINUSE='IN';
    'UPI2_RX_DN7':
      PIN_NUMBER='(0,0,0,0,0,0,0,0,0,0,0,0,0,0,0,0,0,0,0,0,0,0,0,AD81,0,0,0,0,0,~
0,0,0,0,0,0,0,0,0,0,0,0,0)';
      INPUT_LOAD='(-0.01,0.01)';
      PINUSE='IN';
    'UPI2_RX_DN6':
      PIN_NUMBER='(0,0,0,0,0,0,0,0,0,0,0,0,0,0,0,0,0,0,0,0,0,0,0,AC80,0,0,0,0,0,~
0,0,0,0,0,0,0,0,0,0,0,0,0)';
      INPUT_LOAD='(-0.01,0.01)';
      PINUSE='IN';
    'UPI2_RX_DN5':
      PIN_NUMBER='(0,0,0,0,0,0,0,0,0,0,0,0,0,0,0,0,0,0,0,0,0,0,0,L80,0,0,0,0,0,0~
,0,0,0,0,0,0,0,0,0,0,0,0)';
      INPUT_LOAD='(-0.01,0.01)';
      PINUSE='IN';
    'UPI2_RX_DN4':
      PIN_NUMBER='(0,0,0,0,0,0,0,0,0,0,0,0,0,0,0,0,0,0,0,0,0,0,0,J82,0,0,0,0,0,0~
,0,0,0,0,0,0,0,0,0,0,0,0)';
      INPUT_LOAD='(-0.01,0.01)';
      PINUSE='IN';
    'UPI2_RX_DN3':
      PIN_NUMBER='(0,0,0,0,0,0,0,0,0,0,0,0,0,0,0,0,0,0,0,0,0,0,0,K79,0,0,0,0,0,0~
,0,0,0,0,0,0,0,0,0,0,0,0)';
      INPUT_LOAD='(-0.01,0.01)';
      PINUSE='IN';
    'UPI2_RX_DN2':
      PIN_NUMBER='(0,0,0,0,0,0,0,0,0,0,0,0,0,0,0,0,0,0,0,0,0,0,0,G82,0,0,0,0,0,0~
,0,0,0,0,0,0,0,0,0,0,0,0)';
      INPUT_LOAD='(-0.01,0.01)';
      PINUSE='IN';
    'UPI2_RX_DN1':
      PIN_NUMBER='(0,0,0,0,0,0,0,0,0,0,0,0,0,0,0,0,0,0,0,0,0,0,0,F81,0,0,0,0,0,0~
,0,0,0,0,0,0,0,0,0,0,0,0)';
      INPUT_LOAD='(-0.01,0.01)';
      PINUSE='IN';
    'UPI2_RX_DN0':
      PIN_NUMBER='(0,0,0,0,0,0,0,0,0,0,0,0,0,0,0,0,0,0,0,0,0,0,0,E80,0,0,0,0,0,0~
,0,0,0,0,0,0,0,0,0,0,0,0)';
      INPUT_LOAD='(-0.01,0.01)';
      PINUSE='IN';
    'UPI2_RX_DP23':
      PIN_NUMBER='(0,0,0,0,0,0,0,0,0,0,0,0,0,0,0,0,0,0,0,0,0,0,0,BC74,0,0,0,0,0,~
0,0,0,0,0,0,0,0,0,0,0,0,0)';
      INPUT_LOAD='(-0.01,0.01)';
      PINUSE='IN';
    'UPI2_RX_DP22':
      PIN_NUMBER='(0,0,0,0,0,0,0,0,0,0,0,0,0,0,0,0,0,0,0,0,0,0,0,BL74,0,0,0,0,0,~
0,0,0,0,0,0,0,0,0,0,0,0,0)';
      INPUT_LOAD='(-0.01,0.01)';
      PINUSE='IN';
    'UPI2_RX_DP21':
      PIN_NUMBER='(0,0,0,0,0,0,0,0,0,0,0,0,0,0,0,0,0,0,0,0,0,0,0,BM75,0,0,0,0,0,~
0,0,0,0,0,0,0,0,0,0,0,0,0)';
      INPUT_LOAD='(-0.01,0.01)';
      PINUSE='IN';
    'UPI2_RX_DP20':
      PIN_NUMBER='(0,0,0,0,0,0,0,0,0,0,0,0,0,0,0,0,0,0,0,0,0,0,0,BJ74,0,0,0,0,0,~
0,0,0,0,0,0,0,0,0,0,0,0,0)';
      INPUT_LOAD='(-0.01,0.01)';
      PINUSE='IN';
    'UPI2_RX_DP19':
      PIN_NUMBER='(0,0,0,0,0,0,0,0,0,0,0,0,0,0,0,0,0,0,0,0,0,0,0,BN76,0,0,0,0,0,~
0,0,0,0,0,0,0,0,0,0,0,0,0)';
      INPUT_LOAD='(-0.01,0.01)';
      PINUSE='IN';
    'UPI2_RX_DP18':
      PIN_NUMBER='(0,0,0,0,0,0,0,0,0,0,0,0,0,0,0,0,0,0,0,0,0,0,0,BK77,0,0,0,0,0,~
0,0,0,0,0,0,0,0,0,0,0,0,0)';
      INPUT_LOAD='(-0.01,0.01)';
      PINUSE='IN';
    'UPI2_RX_DP17':
      PIN_NUMBER='(0,0,0,0,0,0,0,0,0,0,0,0,0,0,0,0,0,0,0,0,0,0,0,BG76,0,0,0,0,0,~
0,0,0,0,0,0,0,0,0,0,0,0,0)';
      INPUT_LOAD='(-0.01,0.01)';
      PINUSE='IN';
    'UPI2_RX_DP16':
      PIN_NUMBER='(0,0,0,0,0,0,0,0,0,0,0,0,0,0,0,0,0,0,0,0,0,0,0,AV75,0,0,0,0,0,~
0,0,0,0,0,0,0,0,0,0,0,0,0)';
      INPUT_LOAD='(-0.01,0.01)';
      PINUSE='IN';
    'UPI2_RX_DP15':
      PIN_NUMBER='(0,0,0,0,0,0,0,0,0,0,0,0,0,0,0,0,0,0,0,0,0,0,0,BD75,0,0,0,0,0,~
0,0,0,0,0,0,0,0,0,0,0,0,0)';
      INPUT_LOAD='(-0.01,0.01)';
      PINUSE='IN';
    'UPI2_RX_DP14':
      PIN_NUMBER='(0,0,0,0,0,0,0,0,0,0,0,0,0,0,0,0,0,0,0,0,0,0,0,BA76,0,0,0,0,0,~
0,0,0,0,0,0,0,0,0,0,0,0,0)';
      INPUT_LOAD='(-0.01,0.01)';
      PINUSE='IN';
    'UPI2_RX_DP13':
      PIN_NUMBER='(0,0,0,0,0,0,0,0,0,0,0,0,0,0,0,0,0,0,0,0,0,0,0,AY73,0,0,0,0,0,~
0,0,0,0,0,0,0,0,0,0,0,0,0)';
      INPUT_LOAD='(-0.01,0.01)';
      PINUSE='IN';
    'UPI2_RX_DP12':
      PIN_NUMBER='(0,0,0,0,0,0,0,0,0,0,0,0,0,0,0,0,0,0,0,0,0,0,0,BB73,0,0,0,0,0,~
0,0,0,0,0,0,0,0,0,0,0,0,0)';
      INPUT_LOAD='(-0.01,0.01)';
      PINUSE='IN';
    'UPI2_RX_DP11':
      PIN_NUMBER='(0,0,0,0,0,0,0,0,0,0,0,0,0,0,0,0,0,0,0,0,0,0,0,AJ82,0,0,0,0,0,~
0,0,0,0,0,0,0,0,0,0,0,0,0)';
      INPUT_LOAD='(-0.01,0.01)';
      PINUSE='IN';
    'UPI2_RX_DP10':
      PIN_NUMBER='(0,0,0,0,0,0,0,0,0,0,0,0,0,0,0,0,0,0,0,0,0,0,0,AH81,0,0,0,0,0,~
0,0,0,0,0,0,0,0,0,0,0,0,0)';
      INPUT_LOAD='(-0.01,0.01)';
      PINUSE='IN';
    'UPI2_RX_DP9':
      PIN_NUMBER='(0,0,0,0,0,0,0,0,0,0,0,0,0,0,0,0,0,0,0,0,0,0,0,AF83,0,0,0,0,0,~
0,0,0,0,0,0,0,0,0,0,0,0,0)';
      INPUT_LOAD='(-0.01,0.01)';
      PINUSE='IN';
    'UPI2_RX_DP8':
      PIN_NUMBER='(0,0,0,0,0,0,0,0,0,0,0,0,0,0,0,0,0,0,0,0,0,0,0,AG80,0,0,0,0,0,~
0,0,0,0,0,0,0,0,0,0,0,0,0)';
      INPUT_LOAD='(-0.01,0.01)';
      PINUSE='IN';
    'UPI2_RX_DP7':
      PIN_NUMBER='(0,0,0,0,0,0,0,0,0,0,0,0,0,0,0,0,0,0,0,0,0,0,0,AC82,0,0,0,0,0,~
0,0,0,0,0,0,0,0,0,0,0,0,0)';
      INPUT_LOAD='(-0.01,0.01)';
      PINUSE='IN';
    'UPI2_RX_DP6':
      PIN_NUMBER='(0,0,0,0,0,0,0,0,0,0,0,0,0,0,0,0,0,0,0,0,0,0,0,AE80,0,0,0,0,0,~
0,0,0,0,0,0,0,0,0,0,0,0,0)';
      INPUT_LOAD='(-0.01,0.01)';
      PINUSE='IN';
    'UPI2_RX_DP5':
      PIN_NUMBER='(0,0,0,0,0,0,0,0,0,0,0,0,0,0,0,0,0,0,0,0,0,0,0,K81,0,0,0,0,0,0~
,0,0,0,0,0,0,0,0,0,0,0,0)';
      INPUT_LOAD='(-0.01,0.01)';
      PINUSE='IN';
    'UPI2_RX_DP4':
      PIN_NUMBER='(0,0,0,0,0,0,0,0,0,0,0,0,0,0,0,0,0,0,0,0,0,0,0,L82,0,0,0,0,0,0~
,0,0,0,0,0,0,0,0,0,0,0,0)';
      INPUT_LOAD='(-0.01,0.01)';
      PINUSE='IN';
    'UPI2_RX_DP3':
      PIN_NUMBER='(0,0,0,0,0,0,0,0,0,0,0,0,0,0,0,0,0,0,0,0,0,0,0,M79,0,0,0,0,0,0~
,0,0,0,0,0,0,0,0,0,0,0,0)';
      INPUT_LOAD='(-0.01,0.01)';
      PINUSE='IN';
    'UPI2_RX_DP2':
      PIN_NUMBER='(0,0,0,0,0,0,0,0,0,0,0,0,0,0,0,0,0,0,0,0,0,0,0,H83,0,0,0,0,0,0~
,0,0,0,0,0,0,0,0,0,0,0,0)';
      INPUT_LOAD='(-0.01,0.01)';
      PINUSE='IN';
    'UPI2_RX_DP1':
      PIN_NUMBER='(0,0,0,0,0,0,0,0,0,0,0,0,0,0,0,0,0,0,0,0,0,0,0,E82,0,0,0,0,0,0~
,0,0,0,0,0,0,0,0,0,0,0,0)';
      INPUT_LOAD='(-0.01,0.01)';
      PINUSE='IN';
    'UPI2_RX_DP0':
      PIN_NUMBER='(0,0,0,0,0,0,0,0,0,0,0,0,0,0,0,0,0,0,0,0,0,0,0,G80,0,0,0,0,0,0~
,0,0,0,0,0,0,0,0,0,0,0,0)';
      INPUT_LOAD='(-0.01,0.01)';
      PINUSE='IN';
    'UPI2_TX_DN23':
      PIN_NUMBER='(0,0,0,0,0,0,0,0,0,0,0,0,0,0,0,0,0,0,0,0,0,0,0,BM71,0,0,0,0,0,~
0,0,0,0,0,0,0,0,0,0,0,0,0)';
      OUTPUT_LOAD='(1.0,-1.0)';
      PINUSE='OUT';
    'UPI2_TX_DN22':
      PIN_NUMBER='(0,0,0,0,0,0,0,0,0,0,0,0,0,0,0,0,0,0,0,0,0,0,0,BG80,0,0,0,0,0,~
0,0,0,0,0,0,0,0,0,0,0,0,0)';
      OUTPUT_LOAD='(1.0,-1.0)';
      PINUSE='OUT';
    'UPI2_TX_DN21':
      PIN_NUMBER='(0,0,0,0,0,0,0,0,0,0,0,0,0,0,0,0,0,0,0,0,0,0,0,BF81,0,0,0,0,0,~
0,0,0,0,0,0,0,0,0,0,0,0,0)';
      OUTPUT_LOAD='(1.0,-1.0)';
      PINUSE='OUT';
    'UPI2_TX_DN20':
      PIN_NUMBER='(0,0,0,0,0,0,0,0,0,0,0,0,0,0,0,0,0,0,0,0,0,0,0,BD79,0,0,0,0,0,~
0,0,0,0,0,0,0,0,0,0,0,0,0)';
      OUTPUT_LOAD='(1.0,-1.0)';
      PINUSE='OUT';
    'UPI2_TX_DN19':
      PIN_NUMBER='(0,0,0,0,0,0,0,0,0,0,0,0,0,0,0,0,0,0,0,0,0,0,0,BE82,0,0,0,0,0,~
0,0,0,0,0,0,0,0,0,0,0,0,0)';
      OUTPUT_LOAD='(1.0,-1.0)';
      PINUSE='OUT';
    'UPI2_TX_DN18':
      PIN_NUMBER='(0,0,0,0,0,0,0,0,0,0,0,0,0,0,0,0,0,0,0,0,0,0,0,BC82,0,0,0,0,0,~
0,0,0,0,0,0,0,0,0,0,0,0,0)';
      OUTPUT_LOAD='(1.0,-1.0)';
      PINUSE='OUT';
    'UPI2_TX_DN17':
      PIN_NUMBER='(0,0,0,0,0,0,0,0,0,0,0,0,0,0,0,0,0,0,0,0,0,0,0,BA80,0,0,0,0,0,~
0,0,0,0,0,0,0,0,0,0,0,0,0)';
      OUTPUT_LOAD='(1.0,-1.0)';
      PINUSE='OUT';
    'UPI2_TX_DN16':
      PIN_NUMBER='(0,0,0,0,0,0,0,0,0,0,0,0,0,0,0,0,0,0,0,0,0,0,0,AV81,0,0,0,0,0,~
0,0,0,0,0,0,0,0,0,0,0,0,0)';
      OUTPUT_LOAD='(1.0,-1.0)';
      PINUSE='OUT';
    'UPI2_TX_DN15':
      PIN_NUMBER='(0,0,0,0,0,0,0,0,0,0,0,0,0,0,0,0,0,0,0,0,0,0,0,AT83,0,0,0,0,0,~
0,0,0,0,0,0,0,0,0,0,0,0,0)';
      OUTPUT_LOAD='(1.0,-1.0)';
      PINUSE='OUT';
    'UPI2_TX_DN14':
      PIN_NUMBER='(0,0,0,0,0,0,0,0,0,0,0,0,0,0,0,0,0,0,0,0,0,0,0,AR80,0,0,0,0,0,~
0,0,0,0,0,0,0,0,0,0,0,0,0)';
      OUTPUT_LOAD='(1.0,-1.0)';
      PINUSE='OUT';
    'UPI2_TX_DN13':
      PIN_NUMBER='(0,0,0,0,0,0,0,0,0,0,0,0,0,0,0,0,0,0,0,0,0,0,0,AN82,0,0,0,0,0,~
0,0,0,0,0,0,0,0,0,0,0,0,0)';
      OUTPUT_LOAD='(1.0,-1.0)';
      PINUSE='OUT';
    'UPI2_TX_DN12':
      PIN_NUMBER='(0,0,0,0,0,0,0,0,0,0,0,0,0,0,0,0,0,0,0,0,0,0,0,AM81,0,0,0,0,0,~
0,0,0,0,0,0,0,0,0,0,0,0,0)';
      OUTPUT_LOAD='(1.0,-1.0)';
      PINUSE='OUT';
    'UPI2_TX_DN11':
      PIN_NUMBER='(0,0,0,0,0,0,0,0,0,0,0,0,0,0,0,0,0,0,0,0,0,0,0,AU78,0,0,0,0,0,~
0,0,0,0,0,0,0,0,0,0,0,0,0)';
      OUTPUT_LOAD='(1.0,-1.0)';
      PINUSE='OUT';
    'UPI2_TX_DN10':
      PIN_NUMBER='(0,0,0,0,0,0,0,0,0,0,0,0,0,0,0,0,0,0,0,0,0,0,0,AW78,0,0,0,0,0,~
0,0,0,0,0,0,0,0,0,0,0,0,0)';
      OUTPUT_LOAD='(1.0,-1.0)';
      PINUSE='OUT';
    'UPI2_TX_DN9':
      PIN_NUMBER='(0,0,0,0,0,0,0,0,0,0,0,0,0,0,0,0,0,0,0,0,0,0,0,Y81,0,0,0,0,0,0~
,0,0,0,0,0,0,0,0,0,0,0,0)';
      OUTPUT_LOAD='(1.0,-1.0)';
      PINUSE='OUT';
    'UPI2_TX_DN8':
      PIN_NUMBER='(0,0,0,0,0,0,0,0,0,0,0,0,0,0,0,0,0,0,0,0,0,0,0,V83,0,0,0,0,0,0~
,0,0,0,0,0,0,0,0,0,0,0,0)';
      OUTPUT_LOAD='(1.0,-1.0)';
      PINUSE='OUT';
    'UPI2_TX_DN7':
      PIN_NUMBER='(0,0,0,0,0,0,0,0,0,0,0,0,0,0,0,0,0,0,0,0,0,0,0,U80,0,0,0,0,0,0~
,0,0,0,0,0,0,0,0,0,0,0,0)';
      OUTPUT_LOAD='(1.0,-1.0)';
      PINUSE='OUT';
    'UPI2_TX_DN6':
      PIN_NUMBER='(0,0,0,0,0,0,0,0,0,0,0,0,0,0,0,0,0,0,0,0,0,0,0,R82,0,0,0,0,0,0~
,0,0,0,0,0,0,0,0,0,0,0,0)';
      OUTPUT_LOAD='(1.0,-1.0)';
      PINUSE='OUT';
    'UPI2_TX_DN5':
      PIN_NUMBER='(0,0,0,0,0,0,0,0,0,0,0,0,0,0,0,0,0,0,0,0,0,0,0,P81,0,0,0,0,0,0~
,0,0,0,0,0,0,0,0,0,0,0,0)';
      OUTPUT_LOAD='(1.0,-1.0)';
      PINUSE='OUT';
    'UPI2_TX_DN4':
      PIN_NUMBER='(0,0,0,0,0,0,0,0,0,0,0,0,0,0,0,0,0,0,0,0,0,0,0,H85,0,0,0,0,0,0~
,0,0,0,0,0,0,0,0,0,0,0,0)';
      OUTPUT_LOAD='(1.0,-1.0)';
      PINUSE='OUT';
    'UPI2_TX_DN3':
      PIN_NUMBER='(0,0,0,0,0,0,0,0,0,0,0,0,0,0,0,0,0,0,0,0,0,0,0,F87,0,0,0,0,0,0~
,0,0,0,0,0,0,0,0,0,0,0,0)';
      OUTPUT_LOAD='(1.0,-1.0)';
      PINUSE='OUT';
    'UPI2_TX_DN2':
      PIN_NUMBER='(0,0,0,0,0,0,0,0,0,0,0,0,0,0,0,0,0,0,0,0,0,0,0,D87,0,0,0,0,0,0~
,0,0,0,0,0,0,0,0,0,0,0,0)';
      OUTPUT_LOAD='(1.0,-1.0)';
      PINUSE='OUT';
    'UPI2_TX_DN1':
      PIN_NUMBER='(0,0,0,0,0,0,0,0,0,0,0,0,0,0,0,0,0,0,0,0,0,0,0,E84,0,0,0,0,0,0~
,0,0,0,0,0,0,0,0,0,0,0,0)';
      OUTPUT_LOAD='(1.0,-1.0)';
      PINUSE='OUT';
    'UPI2_TX_DN0':
      PIN_NUMBER='(0,0,0,0,0,0,0,0,0,0,0,0,0,0,0,0,0,0,0,0,0,0,0,B85,0,0,0,0,0,0~
,0,0,0,0,0,0,0,0,0,0,0,0)';
      OUTPUT_LOAD='(1.0,-1.0)';
      PINUSE='OUT';
    'UPI2_TX_DP23':
      PIN_NUMBER='(0,0,0,0,0,0,0,0,0,0,0,0,0,0,0,0,0,0,0,0,0,0,0,BN72,0,0,0,0,0,~
0,0,0,0,0,0,0,0,0,0,0,0,0)';
      OUTPUT_LOAD='(1.0,-1.0)';
      PINUSE='OUT';
    'UPI2_TX_DP22':
      PIN_NUMBER='(0,0,0,0,0,0,0,0,0,0,0,0,0,0,0,0,0,0,0,0,0,0,0,BE80,0,0,0,0,0,~
0,0,0,0,0,0,0,0,0,0,0,0,0)';
      OUTPUT_LOAD='(1.0,-1.0)';
      PINUSE='OUT';
    'UPI2_TX_DP21':
      PIN_NUMBER='(0,0,0,0,0,0,0,0,0,0,0,0,0,0,0,0,0,0,0,0,0,0,0,BG82,0,0,0,0,0,~
0,0,0,0,0,0,0,0,0,0,0,0,0)';
      OUTPUT_LOAD='(1.0,-1.0)';
      PINUSE='OUT';
    'UPI2_TX_DP20':
      PIN_NUMBER='(0,0,0,0,0,0,0,0,0,0,0,0,0,0,0,0,0,0,0,0,0,0,0,BC80,0,0,0,0,0,~
0,0,0,0,0,0,0,0,0,0,0,0,0)';
      OUTPUT_LOAD='(1.0,-1.0)';
      PINUSE='OUT';
    'UPI2_TX_DP19':
      PIN_NUMBER='(0,0,0,0,0,0,0,0,0,0,0,0,0,0,0,0,0,0,0,0,0,0,0,BD83,0,0,0,0,0,~
0,0,0,0,0,0,0,0,0,0,0,0,0)';
      OUTPUT_LOAD='(1.0,-1.0)';
      PINUSE='OUT';
    'UPI2_TX_DP18':
      PIN_NUMBER='(0,0,0,0,0,0,0,0,0,0,0,0,0,0,0,0,0,0,0,0,0,0,0,BA82,0,0,0,0,0,~
0,0,0,0,0,0,0,0,0,0,0,0,0)';
      OUTPUT_LOAD='(1.0,-1.0)';
      PINUSE='OUT';
    'UPI2_TX_DP17':
      PIN_NUMBER='(0,0,0,0,0,0,0,0,0,0,0,0,0,0,0,0,0,0,0,0,0,0,0,BB81,0,0,0,0,0,~
0,0,0,0,0,0,0,0,0,0,0,0,0)';
      OUTPUT_LOAD='(1.0,-1.0)';
      PINUSE='OUT';
    'UPI2_TX_DP16':
      PIN_NUMBER='(0,0,0,0,0,0,0,0,0,0,0,0,0,0,0,0,0,0,0,0,0,0,0,AU82,0,0,0,0,0,~
0,0,0,0,0,0,0,0,0,0,0,0,0)';
      OUTPUT_LOAD='(1.0,-1.0)';
      PINUSE='OUT';
    'UPI2_TX_DP15':
      PIN_NUMBER='(0,0,0,0,0,0,0,0,0,0,0,0,0,0,0,0,0,0,0,0,0,0,0,AV83,0,0,0,0,0,~
0,0,0,0,0,0,0,0,0,0,0,0,0)';
      OUTPUT_LOAD='(1.0,-1.0)';
      PINUSE='OUT';
    'UPI2_TX_DP14':
      PIN_NUMBER='(0,0,0,0,0,0,0,0,0,0,0,0,0,0,0,0,0,0,0,0,0,0,0,AT81,0,0,0,0,0,~
0,0,0,0,0,0,0,0,0,0,0,0,0)';
      OUTPUT_LOAD='(1.0,-1.0)';
      PINUSE='OUT';
    'UPI2_TX_DP13':
      PIN_NUMBER='(0,0,0,0,0,0,0,0,0,0,0,0,0,0,0,0,0,0,0,0,0,0,0,AM83,0,0,0,0,0,~
0,0,0,0,0,0,0,0,0,0,0,0,0)';
      OUTPUT_LOAD='(1.0,-1.0)';
      PINUSE='OUT';
    'UPI2_TX_DP12':
      PIN_NUMBER='(0,0,0,0,0,0,0,0,0,0,0,0,0,0,0,0,0,0,0,0,0,0,0,AP81,0,0,0,0,0,~
0,0,0,0,0,0,0,0,0,0,0,0,0)';
      OUTPUT_LOAD='(1.0,-1.0)';
      PINUSE='OUT';
    'UPI2_TX_DP11':
      PIN_NUMBER='(0,0,0,0,0,0,0,0,0,0,0,0,0,0,0,0,0,0,0,0,0,0,0,AV79,0,0,0,0,0,~
0,0,0,0,0,0,0,0,0,0,0,0,0)';
      OUTPUT_LOAD='(1.0,-1.0)';
      PINUSE='OUT';
    'UPI2_TX_DP10':
      PIN_NUMBER='(0,0,0,0,0,0,0,0,0,0,0,0,0,0,0,0,0,0,0,0,0,0,0,BA78,0,0,0,0,0,~
0,0,0,0,0,0,0,0,0,0,0,0,0)';
      OUTPUT_LOAD='(1.0,-1.0)';
      PINUSE='OUT';
    'UPI2_TX_DP9':
      PIN_NUMBER='(0,0,0,0,0,0,0,0,0,0,0,0,0,0,0,0,0,0,0,0,0,0,0,W82,0,0,0,0,0,0~
,0,0,0,0,0,0,0,0,0,0,0,0)';
      OUTPUT_LOAD='(1.0,-1.0)';
      PINUSE='OUT';
    'UPI2_TX_DP8':
      PIN_NUMBER='(0,0,0,0,0,0,0,0,0,0,0,0,0,0,0,0,0,0,0,0,0,0,0,Y83,0,0,0,0,0,0~
,0,0,0,0,0,0,0,0,0,0,0,0)';
      OUTPUT_LOAD='(1.0,-1.0)';
      PINUSE='OUT';
    'UPI2_TX_DP7':
      PIN_NUMBER='(0,0,0,0,0,0,0,0,0,0,0,0,0,0,0,0,0,0,0,0,0,0,0,V81,0,0,0,0,0,0~
,0,0,0,0,0,0,0,0,0,0,0,0)';
      OUTPUT_LOAD='(1.0,-1.0)';
      PINUSE='OUT';
    'UPI2_TX_DP6':
      PIN_NUMBER='(0,0,0,0,0,0,0,0,0,0,0,0,0,0,0,0,0,0,0,0,0,0,0,P83,0,0,0,0,0,0~
,0,0,0,0,0,0,0,0,0,0,0,0)';
      OUTPUT_LOAD='(1.0,-1.0)';
      PINUSE='OUT';
    'UPI2_TX_DP5':
      PIN_NUMBER='(0,0,0,0,0,0,0,0,0,0,0,0,0,0,0,0,0,0,0,0,0,0,0,T81,0,0,0,0,0,0~
,0,0,0,0,0,0,0,0,0,0,0,0)';
      OUTPUT_LOAD='(1.0,-1.0)';
      PINUSE='OUT';
    'UPI2_TX_DP4':
      PIN_NUMBER='(0,0,0,0,0,0,0,0,0,0,0,0,0,0,0,0,0,0,0,0,0,0,0,G86,0,0,0,0,0,0~
,0,0,0,0,0,0,0,0,0,0,0,0)';
      OUTPUT_LOAD='(1.0,-1.0)';
      PINUSE='OUT';
    'UPI2_TX_DP3':
      PIN_NUMBER='(0,0,0,0,0,0,0,0,0,0,0,0,0,0,0,0,0,0,0,0,0,0,0,H87,0,0,0,0,0,0~
,0,0,0,0,0,0,0,0,0,0,0,0)';
      OUTPUT_LOAD='(1.0,-1.0)';
      PINUSE='OUT';
    'UPI2_TX_DP2':
      PIN_NUMBER='(0,0,0,0,0,0,0,0,0,0,0,0,0,0,0,0,0,0,0,0,0,0,0,E88,0,0,0,0,0,0~
,0,0,0,0,0,0,0,0,0,0,0,0)';
      OUTPUT_LOAD='(1.0,-1.0)';
      PINUSE='OUT';
    'UPI2_TX_DP1':
      PIN_NUMBER='(0,0,0,0,0,0,0,0,0,0,0,0,0,0,0,0,0,0,0,0,0,0,0,F85,0,0,0,0,0,0~
,0,0,0,0,0,0,0,0,0,0,0,0)';
      OUTPUT_LOAD='(1.0,-1.0)';
      PINUSE='OUT';
    'UPI2_TX_DP0':
      PIN_NUMBER='(0,0,0,0,0,0,0,0,0,0,0,0,0,0,0,0,0,0,0,0,0,0,0,D85,0,0,0,0,0,0~
,0,0,0,0,0,0,0,0,0,0,0,0)';
      OUTPUT_LOAD='(1.0,-1.0)';
      PINUSE='OUT';
    'UPI3_RX_DN23':
      PIN_NUMBER='(0,0,0,0,0,0,0,0,0,0,0,0,0,0,0,0,0,0,0,0,0,0,0,0,DA78,0,0,0,0,~
0,0,0,0,0,0,0,0,0,0,0,0,0)';
      INPUT_LOAD='(-0.01,0.01)';
      PINUSE='IN';
    'UPI3_RX_DN22':
      PIN_NUMBER='(0,0,0,0,0,0,0,0,0,0,0,0,0,0,0,0,0,0,0,0,0,0,0,0,CT79,0,0,0,0,~
0,0,0,0,0,0,0,0,0,0,0,0,0)';
      INPUT_LOAD='(-0.01,0.01)';
      PINUSE='IN';
    'UPI3_RX_DN21':
      PIN_NUMBER='(0,0,0,0,0,0,0,0,0,0,0,0,0,0,0,0,0,0,0,0,0,0,0,0,CN80,0,0,0,0,~
0,0,0,0,0,0,0,0,0,0,0,0,0)';
      INPUT_LOAD='(-0.01,0.01)';
      PINUSE='IN';
    'UPI3_RX_DN20':
      PIN_NUMBER='(0,0,0,0,0,0,0,0,0,0,0,0,0,0,0,0,0,0,0,0,0,0,0,0,CP81,0,0,0,0,~
0,0,0,0,0,0,0,0,0,0,0,0,0)';
      INPUT_LOAD='(-0.01,0.01)';
      PINUSE='IN';
    'UPI3_RX_DN19':
      PIN_NUMBER='(0,0,0,0,0,0,0,0,0,0,0,0,0,0,0,0,0,0,0,0,0,0,0,0,CW80,0,0,0,0,~
0,0,0,0,0,0,0,0,0,0,0,0,0)';
      INPUT_LOAD='(-0.01,0.01)';
      PINUSE='IN';
    'UPI3_RX_DN18':
      PIN_NUMBER='(0,0,0,0,0,0,0,0,0,0,0,0,0,0,0,0,0,0,0,0,0,0,0,0,CR82,0,0,0,0,~
0,0,0,0,0,0,0,0,0,0,0,0,0)';
      INPUT_LOAD='(-0.01,0.01)';
      PINUSE='IN';
    'UPI3_RX_DN17':
      PIN_NUMBER='(0,0,0,0,0,0,0,0,0,0,0,0,0,0,0,0,0,0,0,0,0,0,0,0,CU82,0,0,0,0,~
0,0,0,0,0,0,0,0,0,0,0,0,0)';
      INPUT_LOAD='(-0.01,0.01)';
      PINUSE='IN';
    'UPI3_RX_DN16':
      PIN_NUMBER='(0,0,0,0,0,0,0,0,0,0,0,0,0,0,0,0,0,0,0,0,0,0,0,0,DF77,0,0,0,0,~
0,0,0,0,0,0,0,0,0,0,0,0,0)';
      INPUT_LOAD='(-0.01,0.01)';
      PINUSE='IN';
    'UPI3_RX_DN15':
      PIN_NUMBER='(0,0,0,0,0,0,0,0,0,0,0,0,0,0,0,0,0,0,0,0,0,0,0,0,DB81,0,0,0,0,~
0,0,0,0,0,0,0,0,0,0,0,0,0)';
      INPUT_LOAD='(-0.01,0.01)';
      PINUSE='IN';
    'UPI3_RX_DN14':
      PIN_NUMBER='(0,0,0,0,0,0,0,0,0,0,0,0,0,0,0,0,0,0,0,0,0,0,0,0,DC82,0,0,0,0,~
0,0,0,0,0,0,0,0,0,0,0,0,0)';
      INPUT_LOAD='(-0.01,0.01)';
      PINUSE='IN';
    'UPI3_RX_DN13':
      PIN_NUMBER='(0,0,0,0,0,0,0,0,0,0,0,0,0,0,0,0,0,0,0,0,0,0,0,0,DE80,0,0,0,0,~
0,0,0,0,0,0,0,0,0,0,0,0,0)';
      INPUT_LOAD='(-0.01,0.01)';
      PINUSE='IN';
    'UPI3_RX_DN12':
      PIN_NUMBER='(0,0,0,0,0,0,0,0,0,0,0,0,0,0,0,0,0,0,0,0,0,0,0,0,DF83,0,0,0,0,~
0,0,0,0,0,0,0,0,0,0,0,0,0)';
      INPUT_LOAD='(-0.01,0.01)';
      PINUSE='IN';
    'UPI3_RX_DN11':
      PIN_NUMBER='(0,0,0,0,0,0,0,0,0,0,0,0,0,0,0,0,0,0,0,0,0,0,0,0,DH81,0,0,0,0,~
0,0,0,0,0,0,0,0,0,0,0,0,0)';
      INPUT_LOAD='(-0.01,0.01)';
      PINUSE='IN';
    'UPI3_RX_DN10':
      PIN_NUMBER='(0,0,0,0,0,0,0,0,0,0,0,0,0,0,0,0,0,0,0,0,0,0,0,0,DG78,0,0,0,0,~
0,0,0,0,0,0,0,0,0,0,0,0,0)';
      INPUT_LOAD='(-0.01,0.01)';
      PINUSE='IN';
    'UPI3_RX_DN9':
      PIN_NUMBER='(0,0,0,0,0,0,0,0,0,0,0,0,0,0,0,0,0,0,0,0,0,0,0,0,DJ78,0,0,0,0,~
0,0,0,0,0,0,0,0,0,0,0,0,0)';
      INPUT_LOAD='(-0.01,0.01)';
      PINUSE='IN';
    'UPI3_RX_DN8':
      PIN_NUMBER='(0,0,0,0,0,0,0,0,0,0,0,0,0,0,0,0,0,0,0,0,0,0,0,0,DY81,0,0,0,0,~
0,0,0,0,0,0,0,0,0,0,0,0,0)';
      INPUT_LOAD='(-0.01,0.01)';
      PINUSE='IN';
    'UPI3_RX_DN7':
      PIN_NUMBER='(0,0,0,0,0,0,0,0,0,0,0,0,0,0,0,0,0,0,0,0,0,0,0,0,EA82,0,0,0,0,~
0,0,0,0,0,0,0,0,0,0,0,0,0)';
      INPUT_LOAD='(-0.01,0.01)';
      PINUSE='IN';
    'UPI3_RX_DN6':
      PIN_NUMBER='(0,0,0,0,0,0,0,0,0,0,0,0,0,0,0,0,0,0,0,0,0,0,0,0,EC80,0,0,0,0,~
0,0,0,0,0,0,0,0,0,0,0,0,0)';
      INPUT_LOAD='(-0.01,0.01)';
      PINUSE='IN';
    'UPI3_RX_DN5':
      PIN_NUMBER='(0,0,0,0,0,0,0,0,0,0,0,0,0,0,0,0,0,0,0,0,0,0,0,0,ED83,0,0,0,0,~
0,0,0,0,0,0,0,0,0,0,0,0,0)';
      INPUT_LOAD='(-0.01,0.01)';
      PINUSE='IN';
    'UPI3_RX_DN4':
      PIN_NUMBER='(0,0,0,0,0,0,0,0,0,0,0,0,0,0,0,0,0,0,0,0,0,0,0,0,EF81,0,0,0,0,~
0,0,0,0,0,0,0,0,0,0,0,0,0)';
      INPUT_LOAD='(-0.01,0.01)';
      PINUSE='IN';
    'UPI3_RX_DN3':
      PIN_NUMBER='(0,0,0,0,0,0,0,0,0,0,0,0,0,0,0,0,0,0,0,0,0,0,0,0,EK81,0,0,0,0,~
0,0,0,0,0,0,0,0,0,0,0,0,0)';
      INPUT_LOAD='(-0.01,0.01)';
      PINUSE='IN';
    'UPI3_RX_DN2':
      PIN_NUMBER='(0,0,0,0,0,0,0,0,0,0,0,0,0,0,0,0,0,0,0,0,0,0,0,0,EL82,0,0,0,0,~
0,0,0,0,0,0,0,0,0,0,0,0,0)';
      INPUT_LOAD='(-0.01,0.01)';
      PINUSE='IN';
    'UPI3_RX_DN1':
      PIN_NUMBER='(0,0,0,0,0,0,0,0,0,0,0,0,0,0,0,0,0,0,0,0,0,0,0,0,EP81,0,0,0,0,~
0,0,0,0,0,0,0,0,0,0,0,0,0)';
      INPUT_LOAD='(-0.01,0.01)';
      PINUSE='IN';
    'UPI3_RX_DN0':
      PIN_NUMBER='(0,0,0,0,0,0,0,0,0,0,0,0,0,0,0,0,0,0,0,0,0,0,0,0,EJ80,0,0,0,0,~
0,0,0,0,0,0,0,0,0,0,0,0,0)';
      INPUT_LOAD='(-0.01,0.01)';
      PINUSE='IN';
    'UPI3_RX_DP23':
      PIN_NUMBER='(0,0,0,0,0,0,0,0,0,0,0,0,0,0,0,0,0,0,0,0,0,0,0,0,DB79,0,0,0,0,~
0,0,0,0,0,0,0,0,0,0,0,0,0)';
      INPUT_LOAD='(-0.01,0.01)';
      PINUSE='IN';
    'UPI3_RX_DP22':
      PIN_NUMBER='(0,0,0,0,0,0,0,0,0,0,0,0,0,0,0,0,0,0,0,0,0,0,0,0,CU80,0,0,0,0,~
0,0,0,0,0,0,0,0,0,0,0,0,0)';
      INPUT_LOAD='(-0.01,0.01)';
      PINUSE='IN';
    'UPI3_RX_DP21':
      PIN_NUMBER='(0,0,0,0,0,0,0,0,0,0,0,0,0,0,0,0,0,0,0,0,0,0,0,0,CR80,0,0,0,0,~
0,0,0,0,0,0,0,0,0,0,0,0,0)';
      INPUT_LOAD='(-0.01,0.01)';
      PINUSE='IN';
    'UPI3_RX_DP20':
      PIN_NUMBER='(0,0,0,0,0,0,0,0,0,0,0,0,0,0,0,0,0,0,0,0,0,0,0,0,CN82,0,0,0,0,~
0,0,0,0,0,0,0,0,0,0,0,0,0)';
      INPUT_LOAD='(-0.01,0.01)';
      PINUSE='IN';
    'UPI3_RX_DP19':
      PIN_NUMBER='(0,0,0,0,0,0,0,0,0,0,0,0,0,0,0,0,0,0,0,0,0,0,0,0,CV81,0,0,0,0,~
0,0,0,0,0,0,0,0,0,0,0,0,0)';
      INPUT_LOAD='(-0.01,0.01)';
      PINUSE='IN';
    'UPI3_RX_DP18':
      PIN_NUMBER='(0,0,0,0,0,0,0,0,0,0,0,0,0,0,0,0,0,0,0,0,0,0,0,0,CT83,0,0,0,0,~
0,0,0,0,0,0,0,0,0,0,0,0,0)';
      INPUT_LOAD='(-0.01,0.01)';
      PINUSE='IN';
    'UPI3_RX_DP17':
      PIN_NUMBER='(0,0,0,0,0,0,0,0,0,0,0,0,0,0,0,0,0,0,0,0,0,0,0,0,CW82,0,0,0,0,~
0,0,0,0,0,0,0,0,0,0,0,0,0)';
      INPUT_LOAD='(-0.01,0.01)';
      PINUSE='IN';
    'UPI3_RX_DP16':
      PIN_NUMBER='(0,0,0,0,0,0,0,0,0,0,0,0,0,0,0,0,0,0,0,0,0,0,0,0,DE78,0,0,0,0,~
0,0,0,0,0,0,0,0,0,0,0,0,0)';
      INPUT_LOAD='(-0.01,0.01)';
      PINUSE='IN';
    'UPI3_RX_DP15':
      PIN_NUMBER='(0,0,0,0,0,0,0,0,0,0,0,0,0,0,0,0,0,0,0,0,0,0,0,0,DD81,0,0,0,0,~
0,0,0,0,0,0,0,0,0,0,0,0,0)';
      INPUT_LOAD='(-0.01,0.01)';
      PINUSE='IN';
    'UPI3_RX_DP14':
      PIN_NUMBER='(0,0,0,0,0,0,0,0,0,0,0,0,0,0,0,0,0,0,0,0,0,0,0,0,DB83,0,0,0,0,~
0,0,0,0,0,0,0,0,0,0,0,0,0)';
      INPUT_LOAD='(-0.01,0.01)';
      PINUSE='IN';
    'UPI3_RX_DP13':
      PIN_NUMBER='(0,0,0,0,0,0,0,0,0,0,0,0,0,0,0,0,0,0,0,0,0,0,0,0,DF81,0,0,0,0,~
0,0,0,0,0,0,0,0,0,0,0,0,0)';
      INPUT_LOAD='(-0.01,0.01)';
      PINUSE='IN';
    'UPI3_RX_DP12':
      PIN_NUMBER='(0,0,0,0,0,0,0,0,0,0,0,0,0,0,0,0,0,0,0,0,0,0,0,0,DH83,0,0,0,0,~
0,0,0,0,0,0,0,0,0,0,0,0,0)';
      INPUT_LOAD='(-0.01,0.01)';
      PINUSE='IN';
    'UPI3_RX_DP11':
      PIN_NUMBER='(0,0,0,0,0,0,0,0,0,0,0,0,0,0,0,0,0,0,0,0,0,0,0,0,DG82,0,0,0,0,~
0,0,0,0,0,0,0,0,0,0,0,0,0)';
      INPUT_LOAD='(-0.01,0.01)';
      PINUSE='IN';
    'UPI3_RX_DP10':
      PIN_NUMBER='(0,0,0,0,0,0,0,0,0,0,0,0,0,0,0,0,0,0,0,0,0,0,0,0,DH79,0,0,0,0,~
0,0,0,0,0,0,0,0,0,0,0,0,0)';
      INPUT_LOAD='(-0.01,0.01)';
      PINUSE='IN';
    'UPI3_RX_DP9':
      PIN_NUMBER='(0,0,0,0,0,0,0,0,0,0,0,0,0,0,0,0,0,0,0,0,0,0,0,0,DL78,0,0,0,0,~
0,0,0,0,0,0,0,0,0,0,0,0,0)';
      INPUT_LOAD='(-0.01,0.01)';
      PINUSE='IN';
    'UPI3_RX_DP8':
      PIN_NUMBER='(0,0,0,0,0,0,0,0,0,0,0,0,0,0,0,0,0,0,0,0,0,0,0,0,EB81,0,0,0,0,~
0,0,0,0,0,0,0,0,0,0,0,0,0)';
      INPUT_LOAD='(-0.01,0.01)';
      PINUSE='IN';
    'UPI3_RX_DP7':
      PIN_NUMBER='(0,0,0,0,0,0,0,0,0,0,0,0,0,0,0,0,0,0,0,0,0,0,0,0,DY83,0,0,0,0,~
0,0,0,0,0,0,0,0,0,0,0,0,0)';
      INPUT_LOAD='(-0.01,0.01)';
      PINUSE='IN';
    'UPI3_RX_DP6':
      PIN_NUMBER='(0,0,0,0,0,0,0,0,0,0,0,0,0,0,0,0,0,0,0,0,0,0,0,0,ED81,0,0,0,0,~
0,0,0,0,0,0,0,0,0,0,0,0,0)';
      INPUT_LOAD='(-0.01,0.01)';
      PINUSE='IN';
    'UPI3_RX_DP5':
      PIN_NUMBER='(0,0,0,0,0,0,0,0,0,0,0,0,0,0,0,0,0,0,0,0,0,0,0,0,EF83,0,0,0,0,~
0,0,0,0,0,0,0,0,0,0,0,0,0)';
      INPUT_LOAD='(-0.01,0.01)';
      PINUSE='IN';
    'UPI3_RX_DP4':
      PIN_NUMBER='(0,0,0,0,0,0,0,0,0,0,0,0,0,0,0,0,0,0,0,0,0,0,0,0,EE82,0,0,0,0,~
0,0,0,0,0,0,0,0,0,0,0,0,0)';
      INPUT_LOAD='(-0.01,0.01)';
      PINUSE='IN';
    'UPI3_RX_DP3':
      PIN_NUMBER='(0,0,0,0,0,0,0,0,0,0,0,0,0,0,0,0,0,0,0,0,0,0,0,0,EJ82,0,0,0,0,~
0,0,0,0,0,0,0,0,0,0,0,0,0)';
      INPUT_LOAD='(-0.01,0.01)';
      PINUSE='IN';
    'UPI3_RX_DP2':
      PIN_NUMBER='(0,0,0,0,0,0,0,0,0,0,0,0,0,0,0,0,0,0,0,0,0,0,0,0,EN82,0,0,0,0,~
0,0,0,0,0,0,0,0,0,0,0,0,0)';
      INPUT_LOAD='(-0.01,0.01)';
      PINUSE='IN';
    'UPI3_RX_DP1':
      PIN_NUMBER='(0,0,0,0,0,0,0,0,0,0,0,0,0,0,0,0,0,0,0,0,0,0,0,0,ER82,0,0,0,0,~
0,0,0,0,0,0,0,0,0,0,0,0,0)';
      INPUT_LOAD='(-0.01,0.01)';
      PINUSE='IN';
    'UPI3_RX_DP0':
      PIN_NUMBER='(0,0,0,0,0,0,0,0,0,0,0,0,0,0,0,0,0,0,0,0,0,0,0,0,EL80,0,0,0,0,~
0,0,0,0,0,0,0,0,0,0,0,0,0)';
      INPUT_LOAD='(-0.01,0.01)';
      PINUSE='IN';
    'UPI3_TX_DN23':
      PIN_NUMBER='(0,0,0,0,0,0,0,0,0,0,0,0,0,0,0,0,0,0,0,0,0,0,0,0,CF73,0,0,0,0,~
0,0,0,0,0,0,0,0,0,0,0,0,0)';
      OUTPUT_LOAD='(1.0,-1.0)';
      PINUSE='OUT';
    'UPI3_TX_DN22':
      PIN_NUMBER='(0,0,0,0,0,0,0,0,0,0,0,0,0,0,0,0,0,0,0,0,0,0,0,0,CV73,0,0,0,0,~
0,0,0,0,0,0,0,0,0,0,0,0,0)';
      OUTPUT_LOAD='(1.0,-1.0)';
      PINUSE='OUT';
    'UPI3_TX_DN21':
      PIN_NUMBER='(0,0,0,0,0,0,0,0,0,0,0,0,0,0,0,0,0,0,0,0,0,0,0,0,CJ74,0,0,0,0,~
0,0,0,0,0,0,0,0,0,0,0,0,0)';
      OUTPUT_LOAD='(1.0,-1.0)';
      PINUSE='OUT';
    'UPI3_TX_DN20':
      PIN_NUMBER='(0,0,0,0,0,0,0,0,0,0,0,0,0,0,0,0,0,0,0,0,0,0,0,0,CF75,0,0,0,0,~
0,0,0,0,0,0,0,0,0,0,0,0,0)';
      OUTPUT_LOAD='(1.0,-1.0)';
      PINUSE='OUT';
    'UPI3_TX_DN19':
      PIN_NUMBER='(0,0,0,0,0,0,0,0,0,0,0,0,0,0,0,0,0,0,0,0,0,0,0,0,CG76,0,0,0,0,~
0,0,0,0,0,0,0,0,0,0,0,0,0)';
      OUTPUT_LOAD='(1.0,-1.0)';
      PINUSE='OUT';
    'UPI3_TX_DN18':
      PIN_NUMBER='(0,0,0,0,0,0,0,0,0,0,0,0,0,0,0,0,0,0,0,0,0,0,0,0,CM75,0,0,0,0,~
0,0,0,0,0,0,0,0,0,0,0,0,0)';
      OUTPUT_LOAD='(1.0,-1.0)';
      PINUSE='OUT';
    'UPI3_TX_DN17':
      PIN_NUMBER='(0,0,0,0,0,0,0,0,0,0,0,0,0,0,0,0,0,0,0,0,0,0,0,0,CH77,0,0,0,0,~
0,0,0,0,0,0,0,0,0,0,0,0,0)';
      OUTPUT_LOAD='(1.0,-1.0)';
      PINUSE='OUT';
    'UPI3_TX_DN16':
      PIN_NUMBER='(0,0,0,0,0,0,0,0,0,0,0,0,0,0,0,0,0,0,0,0,0,0,0,0,CK77,0,0,0,0,~
0,0,0,0,0,0,0,0,0,0,0,0,0)';
      OUTPUT_LOAD='(1.0,-1.0)';
      PINUSE='OUT';
    'UPI3_TX_DN15':
      PIN_NUMBER='(0,0,0,0,0,0,0,0,0,0,0,0,0,0,0,0,0,0,0,0,0,0,0,0,CR74,0,0,0,0,~
0,0,0,0,0,0,0,0,0,0,0,0,0)';
      OUTPUT_LOAD='(1.0,-1.0)';
      PINUSE='OUT';
    'UPI3_TX_DN14':
      PIN_NUMBER='(0,0,0,0,0,0,0,0,0,0,0,0,0,0,0,0,0,0,0,0,0,0,0,0,CT75,0,0,0,0,~
0,0,0,0,0,0,0,0,0,0,0,0,0)';
      OUTPUT_LOAD='(1.0,-1.0)';
      PINUSE='OUT';
    'UPI3_TX_DN13':
      PIN_NUMBER='(0,0,0,0,0,0,0,0,0,0,0,0,0,0,0,0,0,0,0,0,0,0,0,0,CU76,0,0,0,0,~
0,0,0,0,0,0,0,0,0,0,0,0,0)';
      OUTPUT_LOAD='(1.0,-1.0)';
      PINUSE='OUT';
    'UPI3_TX_DN12':
      PIN_NUMBER='(0,0,0,0,0,0,0,0,0,0,0,0,0,0,0,0,0,0,0,0,0,0,0,0,CW76,0,0,0,0,~
0,0,0,0,0,0,0,0,0,0,0,0,0)';
      OUTPUT_LOAD='(1.0,-1.0)';
      PINUSE='OUT';
    'UPI3_TX_DN11':
      PIN_NUMBER='(0,0,0,0,0,0,0,0,0,0,0,0,0,0,0,0,0,0,0,0,0,0,0,0,DL80,0,0,0,0,~
0,0,0,0,0,0,0,0,0,0,0,0,0)';
      OUTPUT_LOAD='(1.0,-1.0)';
      PINUSE='OUT';
    'UPI3_TX_DN10':
      PIN_NUMBER='(0,0,0,0,0,0,0,0,0,0,0,0,0,0,0,0,0,0,0,0,0,0,0,0,DM81,0,0,0,0,~
0,0,0,0,0,0,0,0,0,0,0,0,0)';
      OUTPUT_LOAD='(1.0,-1.0)';
      PINUSE='OUT';
    'UPI3_TX_DN9':
      PIN_NUMBER='(0,0,0,0,0,0,0,0,0,0,0,0,0,0,0,0,0,0,0,0,0,0,0,0,DN82,0,0,0,0,~
0,0,0,0,0,0,0,0,0,0,0,0,0)';
      OUTPUT_LOAD='(1.0,-1.0)';
      PINUSE='OUT';
    'UPI3_TX_DN8':
      PIN_NUMBER='(0,0,0,0,0,0,0,0,0,0,0,0,0,0,0,0,0,0,0,0,0,0,0,0,DP79,0,0,0,0,~
0,0,0,0,0,0,0,0,0,0,0,0,0)';
      OUTPUT_LOAD='(1.0,-1.0)';
      PINUSE='OUT';
    'UPI3_TX_DN7':
      PIN_NUMBER='(0,0,0,0,0,0,0,0,0,0,0,0,0,0,0,0,0,0,0,0,0,0,0,0,DR82,0,0,0,0,~
0,0,0,0,0,0,0,0,0,0,0,0,0)';
      OUTPUT_LOAD='(1.0,-1.0)';
      PINUSE='OUT';
    'UPI3_TX_DN6':
      PIN_NUMBER='(0,0,0,0,0,0,0,0,0,0,0,0,0,0,0,0,0,0,0,0,0,0,0,0,DU80,0,0,0,0,~
0,0,0,0,0,0,0,0,0,0,0,0,0)';
      OUTPUT_LOAD='(1.0,-1.0)';
      PINUSE='OUT';
    'UPI3_TX_DN5':
      PIN_NUMBER='(0,0,0,0,0,0,0,0,0,0,0,0,0,0,0,0,0,0,0,0,0,0,0,0,EK87,0,0,0,0,~
0,0,0,0,0,0,0,0,0,0,0,0,0)';
      OUTPUT_LOAD='(1.0,-1.0)';
      PINUSE='OUT';
    'UPI3_TX_DN4':
      PIN_NUMBER='(0,0,0,0,0,0,0,0,0,0,0,0,0,0,0,0,0,0,0,0,0,0,0,0,EJ86,0,0,0,0,~
0,0,0,0,0,0,0,0,0,0,0,0,0)';
      OUTPUT_LOAD='(1.0,-1.0)';
      PINUSE='OUT';
    'UPI3_TX_DN3':
      PIN_NUMBER='(0,0,0,0,0,0,0,0,0,0,0,0,0,0,0,0,0,0,0,0,0,0,0,0,EM87,0,0,0,0,~
0,0,0,0,0,0,0,0,0,0,0,0,0)';
      OUTPUT_LOAD='(1.0,-1.0)';
      PINUSE='OUT';
    'UPI3_TX_DN2':
      PIN_NUMBER='(0,0,0,0,0,0,0,0,0,0,0,0,0,0,0,0,0,0,0,0,0,0,0,0,EP85,0,0,0,0,~
0,0,0,0,0,0,0,0,0,0,0,0,0)';
      OUTPUT_LOAD='(1.0,-1.0)';
      PINUSE='OUT';
    'UPI3_TX_DN1':
      PIN_NUMBER='(0,0,0,0,0,0,0,0,0,0,0,0,0,0,0,0,0,0,0,0,0,0,0,0,EL84,0,0,0,0,~
0,0,0,0,0,0,0,0,0,0,0,0,0)';
      OUTPUT_LOAD='(1.0,-1.0)';
      PINUSE='OUT';
    'UPI3_TX_DN0':
      PIN_NUMBER='(0,0,0,0,0,0,0,0,0,0,0,0,0,0,0,0,0,0,0,0,0,0,0,0,EH85,0,0,0,0,~
0,0,0,0,0,0,0,0,0,0,0,0,0)';
      OUTPUT_LOAD='(1.0,-1.0)';
      PINUSE='OUT';
    'UPI3_TX_DP23':
      PIN_NUMBER='(0,0,0,0,0,0,0,0,0,0,0,0,0,0,0,0,0,0,0,0,0,0,0,0,CD73,0,0,0,0,~
0,0,0,0,0,0,0,0,0,0,0,0,0)';
      OUTPUT_LOAD='(1.0,-1.0)';
      PINUSE='OUT';
    'UPI3_TX_DP22':
      PIN_NUMBER='(0,0,0,0,0,0,0,0,0,0,0,0,0,0,0,0,0,0,0,0,0,0,0,0,CW74,0,0,0,0,~
0,0,0,0,0,0,0,0,0,0,0,0,0)';
      OUTPUT_LOAD='(1.0,-1.0)';
      PINUSE='OUT';
    'UPI3_TX_DP21':
      PIN_NUMBER='(0,0,0,0,0,0,0,0,0,0,0,0,0,0,0,0,0,0,0,0,0,0,0,0,CK75,0,0,0,0,~
0,0,0,0,0,0,0,0,0,0,0,0,0)';
      OUTPUT_LOAD='(1.0,-1.0)';
      PINUSE='OUT';
    'UPI3_TX_DP20':
      PIN_NUMBER='(0,0,0,0,0,0,0,0,0,0,0,0,0,0,0,0,0,0,0,0,0,0,0,0,CH75,0,0,0,0,~
0,0,0,0,0,0,0,0,0,0,0,0,0)';
      OUTPUT_LOAD='(1.0,-1.0)';
      PINUSE='OUT';
    'UPI3_TX_DP19':
      PIN_NUMBER='(0,0,0,0,0,0,0,0,0,0,0,0,0,0,0,0,0,0,0,0,0,0,0,0,CF77,0,0,0,0,~
0,0,0,0,0,0,0,0,0,0,0,0,0)';
      OUTPUT_LOAD='(1.0,-1.0)';
      PINUSE='OUT';
    'UPI3_TX_DP18':
      PIN_NUMBER='(0,0,0,0,0,0,0,0,0,0,0,0,0,0,0,0,0,0,0,0,0,0,0,0,CL76,0,0,0,0,~
0,0,0,0,0,0,0,0,0,0,0,0,0)';
      OUTPUT_LOAD='(1.0,-1.0)';
      PINUSE='OUT';
    'UPI3_TX_DP17':
      PIN_NUMBER='(0,0,0,0,0,0,0,0,0,0,0,0,0,0,0,0,0,0,0,0,0,0,0,0,CJ78,0,0,0,0,~
0,0,0,0,0,0,0,0,0,0,0,0,0)';
      OUTPUT_LOAD='(1.0,-1.0)';
      PINUSE='OUT';
    'UPI3_TX_DP16':
      PIN_NUMBER='(0,0,0,0,0,0,0,0,0,0,0,0,0,0,0,0,0,0,0,0,0,0,0,0,CM77,0,0,0,0,~
0,0,0,0,0,0,0,0,0,0,0,0,0)';
      OUTPUT_LOAD='(1.0,-1.0)';
      PINUSE='OUT';
    'UPI3_TX_DP15':
      PIN_NUMBER='(0,0,0,0,0,0,0,0,0,0,0,0,0,0,0,0,0,0,0,0,0,0,0,0,CU74,0,0,0,0,~
0,0,0,0,0,0,0,0,0,0,0,0,0)';
      OUTPUT_LOAD='(1.0,-1.0)';
      PINUSE='OUT';
    'UPI3_TX_DP14':
      PIN_NUMBER='(0,0,0,0,0,0,0,0,0,0,0,0,0,0,0,0,0,0,0,0,0,0,0,0,CR76,0,0,0,0,~
0,0,0,0,0,0,0,0,0,0,0,0,0)';
      OUTPUT_LOAD='(1.0,-1.0)';
      PINUSE='OUT';
    'UPI3_TX_DP13':
      PIN_NUMBER='(0,0,0,0,0,0,0,0,0,0,0,0,0,0,0,0,0,0,0,0,0,0,0,0,CV77,0,0,0,0,~
0,0,0,0,0,0,0,0,0,0,0,0,0)';
      OUTPUT_LOAD='(1.0,-1.0)';
      PINUSE='OUT';
    'UPI3_TX_DP12':
      PIN_NUMBER='(0,0,0,0,0,0,0,0,0,0,0,0,0,0,0,0,0,0,0,0,0,0,0,0,DA76,0,0,0,0,~
0,0,0,0,0,0,0,0,0,0,0,0,0)';
      OUTPUT_LOAD='(1.0,-1.0)';
      PINUSE='OUT';
    'UPI3_TX_DP11':
      PIN_NUMBER='(0,0,0,0,0,0,0,0,0,0,0,0,0,0,0,0,0,0,0,0,0,0,0,0,DN80,0,0,0,0,~
0,0,0,0,0,0,0,0,0,0,0,0,0)';
      OUTPUT_LOAD='(1.0,-1.0)';
      PINUSE='OUT';
    'UPI3_TX_DP10':
      PIN_NUMBER='(0,0,0,0,0,0,0,0,0,0,0,0,0,0,0,0,0,0,0,0,0,0,0,0,DL82,0,0,0,0,~
0,0,0,0,0,0,0,0,0,0,0,0,0)';
      OUTPUT_LOAD='(1.0,-1.0)';
      PINUSE='OUT';
    'UPI3_TX_DP9':
      PIN_NUMBER='(0,0,0,0,0,0,0,0,0,0,0,0,0,0,0,0,0,0,0,0,0,0,0,0,DP83,0,0,0,0,~
0,0,0,0,0,0,0,0,0,0,0,0,0)';
      OUTPUT_LOAD='(1.0,-1.0)';
      PINUSE='OUT';
    'UPI3_TX_DP8':
      PIN_NUMBER='(0,0,0,0,0,0,0,0,0,0,0,0,0,0,0,0,0,0,0,0,0,0,0,0,DR80,0,0,0,0,~
0,0,0,0,0,0,0,0,0,0,0,0,0)';
      OUTPUT_LOAD='(1.0,-1.0)';
      PINUSE='OUT';
    'UPI3_TX_DP7':
      PIN_NUMBER='(0,0,0,0,0,0,0,0,0,0,0,0,0,0,0,0,0,0,0,0,0,0,0,0,DU82,0,0,0,0,~
0,0,0,0,0,0,0,0,0,0,0,0,0)';
      OUTPUT_LOAD='(1.0,-1.0)';
      PINUSE='OUT';
    'UPI3_TX_DP6':
      PIN_NUMBER='(0,0,0,0,0,0,0,0,0,0,0,0,0,0,0,0,0,0,0,0,0,0,0,0,DT81,0,0,0,0,~
0,0,0,0,0,0,0,0,0,0,0,0,0)';
      OUTPUT_LOAD='(1.0,-1.0)';
      PINUSE='OUT';
    'UPI3_TX_DP5':
      PIN_NUMBER='(0,0,0,0,0,0,0,0,0,0,0,0,0,0,0,0,0,0,0,0,0,0,0,0,EL88,0,0,0,0,~
0,0,0,0,0,0,0,0,0,0,0,0,0)';
      OUTPUT_LOAD='(1.0,-1.0)';
      PINUSE='OUT';
    'UPI3_TX_DP4':
      PIN_NUMBER='(0,0,0,0,0,0,0,0,0,0,0,0,0,0,0,0,0,0,0,0,0,0,0,0,EH87,0,0,0,0,~
0,0,0,0,0,0,0,0,0,0,0,0,0)';
      OUTPUT_LOAD='(1.0,-1.0)';
      PINUSE='OUT';
    'UPI3_TX_DP3':
      PIN_NUMBER='(0,0,0,0,0,0,0,0,0,0,0,0,0,0,0,0,0,0,0,0,0,0,0,0,EP87,0,0,0,0,~
0,0,0,0,0,0,0,0,0,0,0,0,0)';
      OUTPUT_LOAD='(1.0,-1.0)';
      PINUSE='OUT';
    'UPI3_TX_DP2':
      PIN_NUMBER='(0,0,0,0,0,0,0,0,0,0,0,0,0,0,0,0,0,0,0,0,0,0,0,0,EN86,0,0,0,0,~
0,0,0,0,0,0,0,0,0,0,0,0,0)';
      OUTPUT_LOAD='(1.0,-1.0)';
      PINUSE='OUT';
    'UPI3_TX_DP1':
      PIN_NUMBER='(0,0,0,0,0,0,0,0,0,0,0,0,0,0,0,0,0,0,0,0,0,0,0,0,EM85,0,0,0,0,~
0,0,0,0,0,0,0,0,0,0,0,0,0)';
      OUTPUT_LOAD='(1.0,-1.0)';
      PINUSE='OUT';
    'UPI3_TX_DP0':
      PIN_NUMBER='(0,0,0,0,0,0,0,0,0,0,0,0,0,0,0,0,0,0,0,0,0,0,0,0,EK85,0,0,0,0,~
0,0,0,0,0,0,0,0,0,0,0,0,0)';
      OUTPUT_LOAD='(1.0,-1.0)';
      PINUSE='OUT';
    'VCCIN339':
      PIN_NUMBER='(0,0,0,0,0,0,0,0,0,0,0,0,0,0,0,0,0,0,0,0,0,0,0,0,0,CM89,0,0,0,~
0,0,0,0,0,0,0,0,0,0,0,0,0)';
      PINUSE='POWER';
      NO_LOAD_CHECK='Both';
      NO_IO_CHECK='Both';
      NO_ASSERT_CHECK='TRUE';
      NO_DIR_CHECK='TRUE';
      ALLOW_CONNECT='TRUE';
    'VCCIN338':
      PIN_NUMBER='(0,0,0,0,0,0,0,0,0,0,0,0,0,0,0,0,0,0,0,0,0,0,0,0,0,CP89,0,0,0,~
0,0,0,0,0,0,0,0,0,0,0,0,0)';
      PINUSE='POWER';
      NO_LOAD_CHECK='Both';
      NO_IO_CHECK='Both';
      NO_ASSERT_CHECK='TRUE';
      NO_DIR_CHECK='TRUE';
      ALLOW_CONNECT='TRUE';
    'VCCIN337':
      PIN_NUMBER='(0,0,0,0,0,0,0,0,0,0,0,0,0,0,0,0,0,0,0,0,0,0,0,0,0,CN90,0,0,0,~
0,0,0,0,0,0,0,0,0,0,0,0,0)';
      PINUSE='POWER';
      NO_LOAD_CHECK='Both';
      NO_IO_CHECK='Both';
      NO_ASSERT_CHECK='TRUE';
      NO_DIR_CHECK='TRUE';
      ALLOW_CONNECT='TRUE';
    'VCCIN336':
      PIN_NUMBER='(0,0,0,0,0,0,0,0,0,0,0,0,0,0,0,0,0,0,0,0,0,0,0,0,0,CN88,0,0,0,~
0,0,0,0,0,0,0,0,0,0,0,0,0)';
      PINUSE='POWER';
      NO_LOAD_CHECK='Both';
      NO_IO_CHECK='Both';
      NO_ASSERT_CHECK='TRUE';
      NO_DIR_CHECK='TRUE';
      ALLOW_CONNECT='TRUE';
    'VCCIN335':
      PIN_NUMBER='(0,0,0,0,0,0,0,0,0,0,0,0,0,0,0,0,0,0,0,0,0,0,0,0,0,CM91,0,0,0,~
0,0,0,0,0,0,0,0,0,0,0,0,0)';
      PINUSE='POWER';
      NO_LOAD_CHECK='Both';
      NO_IO_CHECK='Both';
      NO_ASSERT_CHECK='TRUE';
      NO_DIR_CHECK='TRUE';
      ALLOW_CONNECT='TRUE';
    'VCCIN334':
      PIN_NUMBER='(0,0,0,0,0,0,0,0,0,0,0,0,0,0,0,0,0,0,0,0,0,0,0,0,0,CM87,0,0,0,~
0,0,0,0,0,0,0,0,0,0,0,0,0)';
      PINUSE='POWER';
      NO_LOAD_CHECK='Both';
      NO_IO_CHECK='Both';
      NO_ASSERT_CHECK='TRUE';
      NO_DIR_CHECK='TRUE';
      ALLOW_CONNECT='TRUE';
    'VCCIN333':
      PIN_NUMBER='(0,0,0,0,0,0,0,0,0,0,0,0,0,0,0,0,0,0,0,0,0,0,0,0,0,CL90,0,0,0,~
0,0,0,0,0,0,0,0,0,0,0,0,0)';
      PINUSE='POWER';
      NO_LOAD_CHECK='Both';
      NO_IO_CHECK='Both';
      NO_ASSERT_CHECK='TRUE';
      NO_DIR_CHECK='TRUE';
      ALLOW_CONNECT='TRUE';
    'VCCIN332':
      PIN_NUMBER='(0,0,0,0,0,0,0,0,0,0,0,0,0,0,0,0,0,0,0,0,0,0,0,0,0,CL88,0,0,0,~
0,0,0,0,0,0,0,0,0,0,0,0,0)';
      PINUSE='POWER';
      NO_LOAD_CHECK='Both';
      NO_IO_CHECK='Both';
      NO_ASSERT_CHECK='TRUE';
      NO_DIR_CHECK='TRUE';
      ALLOW_CONNECT='TRUE';
    'VCCIN331':
      PIN_NUMBER='(0,0,0,0,0,0,0,0,0,0,0,0,0,0,0,0,0,0,0,0,0,0,0,0,0,CL86,0,0,0,~
0,0,0,0,0,0,0,0,0,0,0,0,0)';
      PINUSE='POWER';
      NO_LOAD_CHECK='Both';
      NO_IO_CHECK='Both';
      NO_ASSERT_CHECK='TRUE';
      NO_DIR_CHECK='TRUE';
      ALLOW_CONNECT='TRUE';
    'VCCIN330':
      PIN_NUMBER='(0,0,0,0,0,0,0,0,0,0,0,0,0,0,0,0,0,0,0,0,0,0,0,0,0,CL84,0,0,0,~
0,0,0,0,0,0,0,0,0,0,0,0,0)';
      PINUSE='POWER';
      NO_LOAD_CHECK='Both';
      NO_IO_CHECK='Both';
      NO_ASSERT_CHECK='TRUE';
      NO_DIR_CHECK='TRUE';
      ALLOW_CONNECT='TRUE';
    'VCCIN329':
      PIN_NUMBER='(0,0,0,0,0,0,0,0,0,0,0,0,0,0,0,0,0,0,0,0,0,0,0,0,0,CK91,0,0,0,~
0,0,0,0,0,0,0,0,0,0,0,0,0)';
      PINUSE='POWER';
      NO_LOAD_CHECK='Both';
      NO_IO_CHECK='Both';
      NO_ASSERT_CHECK='TRUE';
      NO_DIR_CHECK='TRUE';
      ALLOW_CONNECT='TRUE';
    'VCCIN328':
      PIN_NUMBER='(0,0,0,0,0,0,0,0,0,0,0,0,0,0,0,0,0,0,0,0,0,0,0,0,0,CK89,0,0,0,~
0,0,0,0,0,0,0,0,0,0,0,0,0)';
      PINUSE='POWER';
      NO_LOAD_CHECK='Both';
      NO_IO_CHECK='Both';
      NO_ASSERT_CHECK='TRUE';
      NO_DIR_CHECK='TRUE';
      ALLOW_CONNECT='TRUE';
    'VCCIN327':
      PIN_NUMBER='(0,0,0,0,0,0,0,0,0,0,0,0,0,0,0,0,0,0,0,0,0,0,0,0,0,CK87,0,0,0,~
0,0,0,0,0,0,0,0,0,0,0,0,0)';
      PINUSE='POWER';
      NO_LOAD_CHECK='Both';
      NO_IO_CHECK='Both';
      NO_ASSERT_CHECK='TRUE';
      NO_DIR_CHECK='TRUE';
      ALLOW_CONNECT='TRUE';
    'VCCIN326':
      PIN_NUMBER='(0,0,0,0,0,0,0,0,0,0,0,0,0,0,0,0,0,0,0,0,0,0,0,0,0,CK85,0,0,0,~
0,0,0,0,0,0,0,0,0,0,0,0,0)';
      PINUSE='POWER';
      NO_LOAD_CHECK='Both';
      NO_IO_CHECK='Both';
      NO_ASSERT_CHECK='TRUE';
      NO_DIR_CHECK='TRUE';
      ALLOW_CONNECT='TRUE';
    'VCCIN325':
      PIN_NUMBER='(0,0,0,0,0,0,0,0,0,0,0,0,0,0,0,0,0,0,0,0,0,0,0,0,0,CK83,0,0,0,~
0,0,0,0,0,0,0,0,0,0,0,0,0)';
      PINUSE='POWER';
      NO_LOAD_CHECK='Both';
      NO_IO_CHECK='Both';
      NO_ASSERT_CHECK='TRUE';
      NO_DIR_CHECK='TRUE';
      ALLOW_CONNECT='TRUE';
    'VCCIN324':
      PIN_NUMBER='(0,0,0,0,0,0,0,0,0,0,0,0,0,0,0,0,0,0,0,0,0,0,0,0,0,CJ90,0,0,0,~
0,0,0,0,0,0,0,0,0,0,0,0,0)';
      PINUSE='POWER';
      NO_LOAD_CHECK='Both';
      NO_IO_CHECK='Both';
      NO_ASSERT_CHECK='TRUE';
      NO_DIR_CHECK='TRUE';
      ALLOW_CONNECT='TRUE';
    'VCCIN323':
      PIN_NUMBER='(0,0,0,0,0,0,0,0,0,0,0,0,0,0,0,0,0,0,0,0,0,0,0,0,0,CJ88,0,0,0,~
0,0,0,0,0,0,0,0,0,0,0,0,0)';
      PINUSE='POWER';
      NO_LOAD_CHECK='Both';
      NO_IO_CHECK='Both';
      NO_ASSERT_CHECK='TRUE';
      NO_DIR_CHECK='TRUE';
      ALLOW_CONNECT='TRUE';
    'VCCIN322':
      PIN_NUMBER='(0,0,0,0,0,0,0,0,0,0,0,0,0,0,0,0,0,0,0,0,0,0,0,0,0,CJ86,0,0,0,~
0,0,0,0,0,0,0,0,0,0,0,0,0)';
      PINUSE='POWER';
      NO_LOAD_CHECK='Both';
      NO_IO_CHECK='Both';
      NO_ASSERT_CHECK='TRUE';
      NO_DIR_CHECK='TRUE';
      ALLOW_CONNECT='TRUE';
    'VCCIN321':
      PIN_NUMBER='(0,0,0,0,0,0,0,0,0,0,0,0,0,0,0,0,0,0,0,0,0,0,0,0,0,CJ84,0,0,0,~
0,0,0,0,0,0,0,0,0,0,0,0,0)';
      PINUSE='POWER';
      NO_LOAD_CHECK='Both';
      NO_IO_CHECK='Both';
      NO_ASSERT_CHECK='TRUE';
      NO_DIR_CHECK='TRUE';
      ALLOW_CONNECT='TRUE';
    'VCCIN320':
      PIN_NUMBER='(0,0,0,0,0,0,0,0,0,0,0,0,0,0,0,0,0,0,0,0,0,0,0,0,0,CJ82,0,0,0,~
0,0,0,0,0,0,0,0,0,0,0,0,0)';
      PINUSE='POWER';
      NO_LOAD_CHECK='Both';
      NO_IO_CHECK='Both';
      NO_ASSERT_CHECK='TRUE';
      NO_DIR_CHECK='TRUE';
      ALLOW_CONNECT='TRUE';
    'VCCIN319':
      PIN_NUMBER='(0,0,0,0,0,0,0,0,0,0,0,0,0,0,0,0,0,0,0,0,0,0,0,0,0,CH91,0,0,0,~
0,0,0,0,0,0,0,0,0,0,0,0,0)';
      PINUSE='POWER';
      NO_LOAD_CHECK='Both';
      NO_IO_CHECK='Both';
      NO_ASSERT_CHECK='TRUE';
      NO_DIR_CHECK='TRUE';
      ALLOW_CONNECT='TRUE';
    'VCCIN318':
      PIN_NUMBER='(0,0,0,0,0,0,0,0,0,0,0,0,0,0,0,0,0,0,0,0,0,0,0,0,0,CH81,0,0,0,~
0,0,0,0,0,0,0,0,0,0,0,0,0)';
      PINUSE='POWER';
      NO_LOAD_CHECK='Both';
      NO_IO_CHECK='Both';
      NO_ASSERT_CHECK='TRUE';
      NO_DIR_CHECK='TRUE';
      ALLOW_CONNECT='TRUE';
    'VCCIN317':
      PIN_NUMBER='(0,0,0,0,0,0,0,0,0,0,0,0,0,0,0,0,0,0,0,0,0,0,0,0,0,CG90,0,0,0,~
0,0,0,0,0,0,0,0,0,0,0,0,0)';
      PINUSE='POWER';
      NO_LOAD_CHECK='Both';
      NO_IO_CHECK='Both';
      NO_ASSERT_CHECK='TRUE';
      NO_DIR_CHECK='TRUE';
      ALLOW_CONNECT='TRUE';
    'VCCIN316':
      PIN_NUMBER='(0,0,0,0,0,0,0,0,0,0,0,0,0,0,0,0,0,0,0,0,0,0,0,0,0,CG88,0,0,0,~
0,0,0,0,0,0,0,0,0,0,0,0,0)';
      PINUSE='POWER';
      NO_LOAD_CHECK='Both';
      NO_IO_CHECK='Both';
      NO_ASSERT_CHECK='TRUE';
      NO_DIR_CHECK='TRUE';
      ALLOW_CONNECT='TRUE';
    'VCCIN315':
      PIN_NUMBER='(0,0,0,0,0,0,0,0,0,0,0,0,0,0,0,0,0,0,0,0,0,0,0,0,0,CG86,0,0,0,~
0,0,0,0,0,0,0,0,0,0,0,0,0)';
      PINUSE='POWER';
      NO_LOAD_CHECK='Both';
      NO_IO_CHECK='Both';
      NO_ASSERT_CHECK='TRUE';
      NO_DIR_CHECK='TRUE';
      ALLOW_CONNECT='TRUE';
    'VCCIN314':
      PIN_NUMBER='(0,0,0,0,0,0,0,0,0,0,0,0,0,0,0,0,0,0,0,0,0,0,0,0,0,CG84,0,0,0,~
0,0,0,0,0,0,0,0,0,0,0,0,0)';
      PINUSE='POWER';
      NO_LOAD_CHECK='Both';
      NO_IO_CHECK='Both';
      NO_ASSERT_CHECK='TRUE';
      NO_DIR_CHECK='TRUE';
      ALLOW_CONNECT='TRUE';
    'VCCIN313':
      PIN_NUMBER='(0,0,0,0,0,0,0,0,0,0,0,0,0,0,0,0,0,0,0,0,0,0,0,0,0,CG82,0,0,0,~
0,0,0,0,0,0,0,0,0,0,0,0,0)';
      PINUSE='POWER';
      NO_LOAD_CHECK='Both';
      NO_IO_CHECK='Both';
      NO_ASSERT_CHECK='TRUE';
      NO_DIR_CHECK='TRUE';
      ALLOW_CONNECT='TRUE';
    'VCCIN312':
      PIN_NUMBER='(0,0,0,0,0,0,0,0,0,0,0,0,0,0,0,0,0,0,0,0,0,0,0,0,0,CG80,0,0,0,~
0,0,0,0,0,0,0,0,0,0,0,0,0)';
      PINUSE='POWER';
      NO_LOAD_CHECK='Both';
      NO_IO_CHECK='Both';
      NO_ASSERT_CHECK='TRUE';
      NO_DIR_CHECK='TRUE';
      ALLOW_CONNECT='TRUE';
    'VCCIN311':
      PIN_NUMBER='(0,0,0,0,0,0,0,0,0,0,0,0,0,0,0,0,0,0,0,0,0,0,0,0,0,CF91,0,0,0,~
0,0,0,0,0,0,0,0,0,0,0,0,0)';
      PINUSE='POWER';
      NO_LOAD_CHECK='Both';
      NO_IO_CHECK='Both';
      NO_ASSERT_CHECK='TRUE';
      NO_DIR_CHECK='TRUE';
      ALLOW_CONNECT='TRUE';
    'VCCIN310':
      PIN_NUMBER='(0,0,0,0,0,0,0,0,0,0,0,0,0,0,0,0,0,0,0,0,0,0,0,0,0,CF89,0,0,0,~
0,0,0,0,0,0,0,0,0,0,0,0,0)';
      PINUSE='POWER';
      NO_LOAD_CHECK='Both';
      NO_IO_CHECK='Both';
      NO_ASSERT_CHECK='TRUE';
      NO_DIR_CHECK='TRUE';
      ALLOW_CONNECT='TRUE';
    'VCCIN309':
      PIN_NUMBER='(0,0,0,0,0,0,0,0,0,0,0,0,0,0,0,0,0,0,0,0,0,0,0,0,0,CF87,0,0,0,~
0,0,0,0,0,0,0,0,0,0,0,0,0)';
      PINUSE='POWER';
      NO_LOAD_CHECK='Both';
      NO_IO_CHECK='Both';
      NO_ASSERT_CHECK='TRUE';
      NO_DIR_CHECK='TRUE';
      ALLOW_CONNECT='TRUE';
    'VCCIN308':
      PIN_NUMBER='(0,0,0,0,0,0,0,0,0,0,0,0,0,0,0,0,0,0,0,0,0,0,0,0,0,CF85,0,0,0,~
0,0,0,0,0,0,0,0,0,0,0,0,0)';
      PINUSE='POWER';
      NO_LOAD_CHECK='Both';
      NO_IO_CHECK='Both';
      NO_ASSERT_CHECK='TRUE';
      NO_DIR_CHECK='TRUE';
      ALLOW_CONNECT='TRUE';
    'VCCIN307':
      PIN_NUMBER='(0,0,0,0,0,0,0,0,0,0,0,0,0,0,0,0,0,0,0,0,0,0,0,0,0,CF83,0,0,0,~
0,0,0,0,0,0,0,0,0,0,0,0,0)';
      PINUSE='POWER';
      NO_LOAD_CHECK='Both';
      NO_IO_CHECK='Both';
      NO_ASSERT_CHECK='TRUE';
      NO_DIR_CHECK='TRUE';
      ALLOW_CONNECT='TRUE';
    'VCCIN306':
      PIN_NUMBER='(0,0,0,0,0,0,0,0,0,0,0,0,0,0,0,0,0,0,0,0,0,0,0,0,0,CF81,0,0,0,~
0,0,0,0,0,0,0,0,0,0,0,0,0)';
      PINUSE='POWER';
      NO_LOAD_CHECK='Both';
      NO_IO_CHECK='Both';
      NO_ASSERT_CHECK='TRUE';
      NO_DIR_CHECK='TRUE';
      ALLOW_CONNECT='TRUE';
    'VCCIN305':
      PIN_NUMBER='(0,0,0,0,0,0,0,0,0,0,0,0,0,0,0,0,0,0,0,0,0,0,0,0,0,CF79,0,0,0,~
0,0,0,0,0,0,0,0,0,0,0,0,0)';
      PINUSE='POWER';
      NO_LOAD_CHECK='Both';
      NO_IO_CHECK='Both';
      NO_ASSERT_CHECK='TRUE';
      NO_DIR_CHECK='TRUE';
      ALLOW_CONNECT='TRUE';
    'VCCIN304':
      PIN_NUMBER='(0,0,0,0,0,0,0,0,0,0,0,0,0,0,0,0,0,0,0,0,0,0,0,0,0,CE90,0,0,0,~
0,0,0,0,0,0,0,0,0,0,0,0,0)';
      PINUSE='POWER';
      NO_LOAD_CHECK='Both';
      NO_IO_CHECK='Both';
      NO_ASSERT_CHECK='TRUE';
      NO_DIR_CHECK='TRUE';
      ALLOW_CONNECT='TRUE';
    'VCCIN303':
      PIN_NUMBER='(0,0,0,0,0,0,0,0,0,0,0,0,0,0,0,0,0,0,0,0,0,0,0,0,0,CE88,0,0,0,~
0,0,0,0,0,0,0,0,0,0,0,0,0)';
      PINUSE='POWER';
      NO_LOAD_CHECK='Both';
      NO_IO_CHECK='Both';
      NO_ASSERT_CHECK='TRUE';
      NO_DIR_CHECK='TRUE';
      ALLOW_CONNECT='TRUE';
    'VCCIN302':
      PIN_NUMBER='(0,0,0,0,0,0,0,0,0,0,0,0,0,0,0,0,0,0,0,0,0,0,0,0,0,CE86,0,0,0,~
0,0,0,0,0,0,0,0,0,0,0,0,0)';
      PINUSE='POWER';
      NO_LOAD_CHECK='Both';
      NO_IO_CHECK='Both';
      NO_ASSERT_CHECK='TRUE';
      NO_DIR_CHECK='TRUE';
      ALLOW_CONNECT='TRUE';
    'VCCIN301':
      PIN_NUMBER='(0,0,0,0,0,0,0,0,0,0,0,0,0,0,0,0,0,0,0,0,0,0,0,0,0,CE84,0,0,0,~
0,0,0,0,0,0,0,0,0,0,0,0,0)';
      PINUSE='POWER';
      NO_LOAD_CHECK='Both';
      NO_IO_CHECK='Both';
      NO_ASSERT_CHECK='TRUE';
      NO_DIR_CHECK='TRUE';
      ALLOW_CONNECT='TRUE';
    'VCCIN300':
      PIN_NUMBER='(0,0,0,0,0,0,0,0,0,0,0,0,0,0,0,0,0,0,0,0,0,0,0,0,0,CE82,0,0,0,~
0,0,0,0,0,0,0,0,0,0,0,0,0)';
      PINUSE='POWER';
      NO_LOAD_CHECK='Both';
      NO_IO_CHECK='Both';
      NO_ASSERT_CHECK='TRUE';
      NO_DIR_CHECK='TRUE';
      ALLOW_CONNECT='TRUE';
    'VCCIN299':
      PIN_NUMBER='(0,0,0,0,0,0,0,0,0,0,0,0,0,0,0,0,0,0,0,0,0,0,0,0,0,CE80,0,0,0,~
0,0,0,0,0,0,0,0,0,0,0,0,0)';
      PINUSE='POWER';
      NO_LOAD_CHECK='Both';
      NO_IO_CHECK='Both';
      NO_ASSERT_CHECK='TRUE';
      NO_DIR_CHECK='TRUE';
      ALLOW_CONNECT='TRUE';
    'VCCIN298':
      PIN_NUMBER='(0,0,0,0,0,0,0,0,0,0,0,0,0,0,0,0,0,0,0,0,0,0,0,0,0,CD89,0,0,0,~
0,0,0,0,0,0,0,0,0,0,0,0,0)';
      PINUSE='POWER';
      NO_LOAD_CHECK='Both';
      NO_IO_CHECK='Both';
      NO_ASSERT_CHECK='TRUE';
      NO_DIR_CHECK='TRUE';
      ALLOW_CONNECT='TRUE';
    'VCCIN297':
      PIN_NUMBER='(0,0,0,0,0,0,0,0,0,0,0,0,0,0,0,0,0,0,0,0,0,0,0,0,0,CD87,0,0,0,~
0,0,0,0,0,0,0,0,0,0,0,0,0)';
      PINUSE='POWER';
      NO_LOAD_CHECK='Both';
      NO_IO_CHECK='Both';
      NO_ASSERT_CHECK='TRUE';
      NO_DIR_CHECK='TRUE';
      ALLOW_CONNECT='TRUE';
    'VCCIN296':
      PIN_NUMBER='(0,0,0,0,0,0,0,0,0,0,0,0,0,0,0,0,0,0,0,0,0,0,0,0,0,CD85,0,0,0,~
0,0,0,0,0,0,0,0,0,0,0,0,0)';
      PINUSE='POWER';
      NO_LOAD_CHECK='Both';
      NO_IO_CHECK='Both';
      NO_ASSERT_CHECK='TRUE';
      NO_DIR_CHECK='TRUE';
      ALLOW_CONNECT='TRUE';
    'VCCIN295':
      PIN_NUMBER='(0,0,0,0,0,0,0,0,0,0,0,0,0,0,0,0,0,0,0,0,0,0,0,0,0,CD83,0,0,0,~
0,0,0,0,0,0,0,0,0,0,0,0,0)';
      PINUSE='POWER';
      NO_LOAD_CHECK='Both';
      NO_IO_CHECK='Both';
      NO_ASSERT_CHECK='TRUE';
      NO_DIR_CHECK='TRUE';
      ALLOW_CONNECT='TRUE';
    'VCCIN294':
      PIN_NUMBER='(0,0,0,0,0,0,0,0,0,0,0,0,0,0,0,0,0,0,0,0,0,0,0,0,0,CD81,0,0,0,~
0,0,0,0,0,0,0,0,0,0,0,0,0)';
      PINUSE='POWER';
      NO_LOAD_CHECK='Both';
      NO_IO_CHECK='Both';
      NO_ASSERT_CHECK='TRUE';
      NO_DIR_CHECK='TRUE';
      ALLOW_CONNECT='TRUE';
    'VCCIN293':
      PIN_NUMBER='(0,0,0,0,0,0,0,0,0,0,0,0,0,0,0,0,0,0,0,0,0,0,0,0,0,CD79,0,0,0,~
0,0,0,0,0,0,0,0,0,0,0,0,0)';
      PINUSE='POWER';
      NO_LOAD_CHECK='Both';
      NO_IO_CHECK='Both';
      NO_ASSERT_CHECK='TRUE';
      NO_DIR_CHECK='TRUE';
      ALLOW_CONNECT='TRUE';
    'VCCIN292':
      PIN_NUMBER='(0,0,0,0,0,0,0,0,0,0,0,0,0,0,0,0,0,0,0,0,0,0,0,0,0,CD59,0,0,0,~
0,0,0,0,0,0,0,0,0,0,0,0,0)';
      PINUSE='POWER';
      NO_LOAD_CHECK='Both';
      NO_IO_CHECK='Both';
      NO_ASSERT_CHECK='TRUE';
      NO_DIR_CHECK='TRUE';
      ALLOW_CONNECT='TRUE';
    'VCCIN291':
      PIN_NUMBER='(0,0,0,0,0,0,0,0,0,0,0,0,0,0,0,0,0,0,0,0,0,0,0,0,0,CD57,0,0,0,~
0,0,0,0,0,0,0,0,0,0,0,0,0)';
      PINUSE='POWER';
      NO_LOAD_CHECK='Both';
      NO_IO_CHECK='Both';
      NO_ASSERT_CHECK='TRUE';
      NO_DIR_CHECK='TRUE';
      ALLOW_CONNECT='TRUE';
    'VCCIN290':
      PIN_NUMBER='(0,0,0,0,0,0,0,0,0,0,0,0,0,0,0,0,0,0,0,0,0,0,0,0,0,CD55,0,0,0,~
0,0,0,0,0,0,0,0,0,0,0,0,0)';
      PINUSE='POWER';
      NO_LOAD_CHECK='Both';
      NO_IO_CHECK='Both';
      NO_ASSERT_CHECK='TRUE';
      NO_DIR_CHECK='TRUE';
      ALLOW_CONNECT='TRUE';
    'VCCIN289':
      PIN_NUMBER='(0,0,0,0,0,0,0,0,0,0,0,0,0,0,0,0,0,0,0,0,0,0,0,0,0,CD53,0,0,0,~
0,0,0,0,0,0,0,0,0,0,0,0,0)';
      PINUSE='POWER';
      NO_LOAD_CHECK='Both';
      NO_IO_CHECK='Both';
      NO_ASSERT_CHECK='TRUE';
      NO_DIR_CHECK='TRUE';
      ALLOW_CONNECT='TRUE';
    'VCCIN288':
      PIN_NUMBER='(0,0,0,0,0,0,0,0,0,0,0,0,0,0,0,0,0,0,0,0,0,0,0,0,0,CD51,0,0,0,~
0,0,0,0,0,0,0,0,0,0,0,0,0)';
      PINUSE='POWER';
      NO_LOAD_CHECK='Both';
      NO_IO_CHECK='Both';
      NO_ASSERT_CHECK='TRUE';
      NO_DIR_CHECK='TRUE';
      ALLOW_CONNECT='TRUE';
    'VCCIN287':
      PIN_NUMBER='(0,0,0,0,0,0,0,0,0,0,0,0,0,0,0,0,0,0,0,0,0,0,0,0,0,CD49,0,0,0,~
0,0,0,0,0,0,0,0,0,0,0,0,0)';
      PINUSE='POWER';
      NO_LOAD_CHECK='Both';
      NO_IO_CHECK='Both';
      NO_ASSERT_CHECK='TRUE';
      NO_DIR_CHECK='TRUE';
      ALLOW_CONNECT='TRUE';
    'VCCIN286':
      PIN_NUMBER='(0,0,0,0,0,0,0,0,0,0,0,0,0,0,0,0,0,0,0,0,0,0,0,0,0,CD47,0,0,0,~
0,0,0,0,0,0,0,0,0,0,0,0,0)';
      PINUSE='POWER';
      NO_LOAD_CHECK='Both';
      NO_IO_CHECK='Both';
      NO_ASSERT_CHECK='TRUE';
      NO_DIR_CHECK='TRUE';
      ALLOW_CONNECT='TRUE';
    'VCCIN285':
      PIN_NUMBER='(0,0,0,0,0,0,0,0,0,0,0,0,0,0,0,0,0,0,0,0,0,0,0,0,0,CD44,0,0,0,~
0,0,0,0,0,0,0,0,0,0,0,0,0)';
      PINUSE='POWER';
      NO_LOAD_CHECK='Both';
      NO_IO_CHECK='Both';
      NO_ASSERT_CHECK='TRUE';
      NO_DIR_CHECK='TRUE';
      ALLOW_CONNECT='TRUE';
    'VCCIN284':
      PIN_NUMBER='(0,0,0,0,0,0,0,0,0,0,0,0,0,0,0,0,0,0,0,0,0,0,0,0,0,CD42,0,0,0,~
0,0,0,0,0,0,0,0,0,0,0,0,0)';
      PINUSE='POWER';
      NO_LOAD_CHECK='Both';
      NO_IO_CHECK='Both';
      NO_ASSERT_CHECK='TRUE';
      NO_DIR_CHECK='TRUE';
      ALLOW_CONNECT='TRUE';
    'VCCIN283':
      PIN_NUMBER='(0,0,0,0,0,0,0,0,0,0,0,0,0,0,0,0,0,0,0,0,0,0,0,0,0,CD40,0,0,0,~
0,0,0,0,0,0,0,0,0,0,0,0,0)';
      PINUSE='POWER';
      NO_LOAD_CHECK='Both';
      NO_IO_CHECK='Both';
      NO_ASSERT_CHECK='TRUE';
      NO_DIR_CHECK='TRUE';
      ALLOW_CONNECT='TRUE';
    'VCCIN282':
      PIN_NUMBER='(0,0,0,0,0,0,0,0,0,0,0,0,0,0,0,0,0,0,0,0,0,0,0,0,0,CD38,0,0,0,~
0,0,0,0,0,0,0,0,0,0,0,0,0)';
      PINUSE='POWER';
      NO_LOAD_CHECK='Both';
      NO_IO_CHECK='Both';
      NO_ASSERT_CHECK='TRUE';
      NO_DIR_CHECK='TRUE';
      ALLOW_CONNECT='TRUE';
    'VCCIN281':
      PIN_NUMBER='(0,0,0,0,0,0,0,0,0,0,0,0,0,0,0,0,0,0,0,0,0,0,0,0,0,CD36,0,0,0,~
0,0,0,0,0,0,0,0,0,0,0,0,0)';
      PINUSE='POWER';
      NO_LOAD_CHECK='Both';
      NO_IO_CHECK='Both';
      NO_ASSERT_CHECK='TRUE';
      NO_DIR_CHECK='TRUE';
      ALLOW_CONNECT='TRUE';
    'VCCIN280':
      PIN_NUMBER='(0,0,0,0,0,0,0,0,0,0,0,0,0,0,0,0,0,0,0,0,0,0,0,0,0,CD34,0,0,0,~
0,0,0,0,0,0,0,0,0,0,0,0,0)';
      PINUSE='POWER';
      NO_LOAD_CHECK='Both';
      NO_IO_CHECK='Both';
      NO_ASSERT_CHECK='TRUE';
      NO_DIR_CHECK='TRUE';
      ALLOW_CONNECT='TRUE';
    'VCCIN279':
      PIN_NUMBER='(0,0,0,0,0,0,0,0,0,0,0,0,0,0,0,0,0,0,0,0,0,0,0,0,0,CD32,0,0,0,~
0,0,0,0,0,0,0,0,0,0,0,0,0)';
      PINUSE='POWER';
      NO_LOAD_CHECK='Both';
      NO_IO_CHECK='Both';
      NO_ASSERT_CHECK='TRUE';
      NO_DIR_CHECK='TRUE';
      ALLOW_CONNECT='TRUE';
    'VCCIN278':
      PIN_NUMBER='(0,0,0,0,0,0,0,0,0,0,0,0,0,0,0,0,0,0,0,0,0,0,0,0,0,CC90,0,0,0,~
0,0,0,0,0,0,0,0,0,0,0,0,0)';
      PINUSE='POWER';
      NO_LOAD_CHECK='Both';
      NO_IO_CHECK='Both';
      NO_ASSERT_CHECK='TRUE';
      NO_DIR_CHECK='TRUE';
      ALLOW_CONNECT='TRUE';
    'VCCIN277':
      PIN_NUMBER='(0,0,0,0,0,0,0,0,0,0,0,0,0,0,0,0,0,0,0,0,0,0,0,0,0,CC88,0,0,0,~
0,0,0,0,0,0,0,0,0,0,0,0,0)';
      PINUSE='POWER';
      NO_LOAD_CHECK='Both';
      NO_IO_CHECK='Both';
      NO_ASSERT_CHECK='TRUE';
      NO_DIR_CHECK='TRUE';
      ALLOW_CONNECT='TRUE';
    'VCCIN276':
      PIN_NUMBER='(0,0,0,0,0,0,0,0,0,0,0,0,0,0,0,0,0,0,0,0,0,0,0,0,0,CC86,0,0,0,~
0,0,0,0,0,0,0,0,0,0,0,0,0)';
      PINUSE='POWER';
      NO_LOAD_CHECK='Both';
      NO_IO_CHECK='Both';
      NO_ASSERT_CHECK='TRUE';
      NO_DIR_CHECK='TRUE';
      ALLOW_CONNECT='TRUE';
    'VCCIN275':
      PIN_NUMBER='(0,0,0,0,0,0,0,0,0,0,0,0,0,0,0,0,0,0,0,0,0,0,0,0,0,CC84,0,0,0,~
0,0,0,0,0,0,0,0,0,0,0,0,0)';
      PINUSE='POWER';
      NO_LOAD_CHECK='Both';
      NO_IO_CHECK='Both';
      NO_ASSERT_CHECK='TRUE';
      NO_DIR_CHECK='TRUE';
      ALLOW_CONNECT='TRUE';
    'VCCIN274':
      PIN_NUMBER='(0,0,0,0,0,0,0,0,0,0,0,0,0,0,0,0,0,0,0,0,0,0,0,0,0,CC82,0,0,0,~
0,0,0,0,0,0,0,0,0,0,0,0,0)';
      PINUSE='POWER';
      NO_LOAD_CHECK='Both';
      NO_IO_CHECK='Both';
      NO_ASSERT_CHECK='TRUE';
      NO_DIR_CHECK='TRUE';
      ALLOW_CONNECT='TRUE';
    'VCCIN273':
      PIN_NUMBER='(0,0,0,0,0,0,0,0,0,0,0,0,0,0,0,0,0,0,0,0,0,0,0,0,0,CC80,0,0,0,~
0,0,0,0,0,0,0,0,0,0,0,0,0)';
      PINUSE='POWER';
      NO_LOAD_CHECK='Both';
      NO_IO_CHECK='Both';
      NO_ASSERT_CHECK='TRUE';
      NO_DIR_CHECK='TRUE';
      ALLOW_CONNECT='TRUE';
    'VCCIN272':
      PIN_NUMBER='(0,0,0,0,0,0,0,0,0,0,0,0,0,0,0,0,0,0,0,0,0,0,0,0,0,CC78,0,0,0,~
0,0,0,0,0,0,0,0,0,0,0,0,0)';
      PINUSE='POWER';
      NO_LOAD_CHECK='Both';
      NO_IO_CHECK='Both';
      NO_ASSERT_CHECK='TRUE';
      NO_DIR_CHECK='TRUE';
      ALLOW_CONNECT='TRUE';
    'VCCIN271':
      PIN_NUMBER='(0,0,0,0,0,0,0,0,0,0,0,0,0,0,0,0,0,0,0,0,0,0,0,0,0,CC76,0,0,0,~
0,0,0,0,0,0,0,0,0,0,0,0,0)';
      PINUSE='POWER';
      NO_LOAD_CHECK='Both';
      NO_IO_CHECK='Both';
      NO_ASSERT_CHECK='TRUE';
      NO_DIR_CHECK='TRUE';
      ALLOW_CONNECT='TRUE';
    'VCCIN270':
      PIN_NUMBER='(0,0,0,0,0,0,0,0,0,0,0,0,0,0,0,0,0,0,0,0,0,0,0,0,0,CC60,0,0,0,~
0,0,0,0,0,0,0,0,0,0,0,0,0)';
      PINUSE='POWER';
      NO_LOAD_CHECK='Both';
      NO_IO_CHECK='Both';
      NO_ASSERT_CHECK='TRUE';
      NO_DIR_CHECK='TRUE';
      ALLOW_CONNECT='TRUE';
    'VCCIN269':
      PIN_NUMBER='(0,0,0,0,0,0,0,0,0,0,0,0,0,0,0,0,0,0,0,0,0,0,0,0,0,CC58,0,0,0,~
0,0,0,0,0,0,0,0,0,0,0,0,0)';
      PINUSE='POWER';
      NO_LOAD_CHECK='Both';
      NO_IO_CHECK='Both';
      NO_ASSERT_CHECK='TRUE';
      NO_DIR_CHECK='TRUE';
      ALLOW_CONNECT='TRUE';
    'VCCIN268':
      PIN_NUMBER='(0,0,0,0,0,0,0,0,0,0,0,0,0,0,0,0,0,0,0,0,0,0,0,0,0,CC56,0,0,0,~
0,0,0,0,0,0,0,0,0,0,0,0,0)';
      PINUSE='POWER';
      NO_LOAD_CHECK='Both';
      NO_IO_CHECK='Both';
      NO_ASSERT_CHECK='TRUE';
      NO_DIR_CHECK='TRUE';
      ALLOW_CONNECT='TRUE';
    'VCCIN267':
      PIN_NUMBER='(0,0,0,0,0,0,0,0,0,0,0,0,0,0,0,0,0,0,0,0,0,0,0,0,0,CC54,0,0,0,~
0,0,0,0,0,0,0,0,0,0,0,0,0)';
      PINUSE='POWER';
      NO_LOAD_CHECK='Both';
      NO_IO_CHECK='Both';
      NO_ASSERT_CHECK='TRUE';
      NO_DIR_CHECK='TRUE';
      ALLOW_CONNECT='TRUE';
    'VCCIN266':
      PIN_NUMBER='(0,0,0,0,0,0,0,0,0,0,0,0,0,0,0,0,0,0,0,0,0,0,0,0,0,CC52,0,0,0,~
0,0,0,0,0,0,0,0,0,0,0,0,0)';
      PINUSE='POWER';
      NO_LOAD_CHECK='Both';
      NO_IO_CHECK='Both';
      NO_ASSERT_CHECK='TRUE';
      NO_DIR_CHECK='TRUE';
      ALLOW_CONNECT='TRUE';
    'VCCIN265':
      PIN_NUMBER='(0,0,0,0,0,0,0,0,0,0,0,0,0,0,0,0,0,0,0,0,0,0,0,0,0,CC50,0,0,0,~
0,0,0,0,0,0,0,0,0,0,0,0,0)';
      PINUSE='POWER';
      NO_LOAD_CHECK='Both';
      NO_IO_CHECK='Both';
      NO_ASSERT_CHECK='TRUE';
      NO_DIR_CHECK='TRUE';
      ALLOW_CONNECT='TRUE';
    'VCCIN264':
      PIN_NUMBER='(0,0,0,0,0,0,0,0,0,0,0,0,0,0,0,0,0,0,0,0,0,0,0,0,0,CC48,0,0,0,~
0,0,0,0,0,0,0,0,0,0,0,0,0)';
      PINUSE='POWER';
      NO_LOAD_CHECK='Both';
      NO_IO_CHECK='Both';
      NO_ASSERT_CHECK='TRUE';
      NO_DIR_CHECK='TRUE';
      ALLOW_CONNECT='TRUE';
    'VCCIN263':
      PIN_NUMBER='(0,0,0,0,0,0,0,0,0,0,0,0,0,0,0,0,0,0,0,0,0,0,0,0,0,CC45,0,0,0,~
0,0,0,0,0,0,0,0,0,0,0,0,0)';
      PINUSE='POWER';
      NO_LOAD_CHECK='Both';
      NO_IO_CHECK='Both';
      NO_ASSERT_CHECK='TRUE';
      NO_DIR_CHECK='TRUE';
      ALLOW_CONNECT='TRUE';
    'VCCIN262':
      PIN_NUMBER='(0,0,0,0,0,0,0,0,0,0,0,0,0,0,0,0,0,0,0,0,0,0,0,0,0,CC43,0,0,0,~
0,0,0,0,0,0,0,0,0,0,0,0,0)';
      PINUSE='POWER';
      NO_LOAD_CHECK='Both';
      NO_IO_CHECK='Both';
      NO_ASSERT_CHECK='TRUE';
      NO_DIR_CHECK='TRUE';
      ALLOW_CONNECT='TRUE';
    'VCCIN261':
      PIN_NUMBER='(0,0,0,0,0,0,0,0,0,0,0,0,0,0,0,0,0,0,0,0,0,0,0,0,0,CC41,0,0,0,~
0,0,0,0,0,0,0,0,0,0,0,0,0)';
      PINUSE='POWER';
      NO_LOAD_CHECK='Both';
      NO_IO_CHECK='Both';
      NO_ASSERT_CHECK='TRUE';
      NO_DIR_CHECK='TRUE';
      ALLOW_CONNECT='TRUE';
    'VCCIN260':
      PIN_NUMBER='(0,0,0,0,0,0,0,0,0,0,0,0,0,0,0,0,0,0,0,0,0,0,0,0,0,CC39,0,0,0,~
0,0,0,0,0,0,0,0,0,0,0,0,0)';
      PINUSE='POWER';
      NO_LOAD_CHECK='Both';
      NO_IO_CHECK='Both';
      NO_ASSERT_CHECK='TRUE';
      NO_DIR_CHECK='TRUE';
      ALLOW_CONNECT='TRUE';
    'VCCIN259':
      PIN_NUMBER='(0,0,0,0,0,0,0,0,0,0,0,0,0,0,0,0,0,0,0,0,0,0,0,0,0,CC37,0,0,0,~
0,0,0,0,0,0,0,0,0,0,0,0,0)';
      PINUSE='POWER';
      NO_LOAD_CHECK='Both';
      NO_IO_CHECK='Both';
      NO_ASSERT_CHECK='TRUE';
      NO_DIR_CHECK='TRUE';
      ALLOW_CONNECT='TRUE';
    'VCCIN258':
      PIN_NUMBER='(0,0,0,0,0,0,0,0,0,0,0,0,0,0,0,0,0,0,0,0,0,0,0,0,0,CC35,0,0,0,~
0,0,0,0,0,0,0,0,0,0,0,0,0)';
      PINUSE='POWER';
      NO_LOAD_CHECK='Both';
      NO_IO_CHECK='Both';
      NO_ASSERT_CHECK='TRUE';
      NO_DIR_CHECK='TRUE';
      ALLOW_CONNECT='TRUE';
    'VCCIN257':
      PIN_NUMBER='(0,0,0,0,0,0,0,0,0,0,0,0,0,0,0,0,0,0,0,0,0,0,0,0,0,CC33,0,0,0,~
0,0,0,0,0,0,0,0,0,0,0,0,0)';
      PINUSE='POWER';
      NO_LOAD_CHECK='Both';
      NO_IO_CHECK='Both';
      NO_ASSERT_CHECK='TRUE';
      NO_DIR_CHECK='TRUE';
      ALLOW_CONNECT='TRUE';
    'VCCIN256':
      PIN_NUMBER='(0,0,0,0,0,0,0,0,0,0,0,0,0,0,0,0,0,0,0,0,0,0,0,0,0,CB77,0,0,0,~
0,0,0,0,0,0,0,0,0,0,0,0,0)';
      PINUSE='POWER';
      NO_LOAD_CHECK='Both';
      NO_IO_CHECK='Both';
      NO_ASSERT_CHECK='TRUE';
      NO_DIR_CHECK='TRUE';
      ALLOW_CONNECT='TRUE';
    'VCCIN255':
      PIN_NUMBER='(0,0,0,0,0,0,0,0,0,0,0,0,0,0,0,0,0,0,0,0,0,0,0,0,0,CB75,0,0,0,~
0,0,0,0,0,0,0,0,0,0,0,0,0)';
      PINUSE='POWER';
      NO_LOAD_CHECK='Both';
      NO_IO_CHECK='Both';
      NO_ASSERT_CHECK='TRUE';
      NO_DIR_CHECK='TRUE';
      ALLOW_CONNECT='TRUE';
    'VCCIN254':
      PIN_NUMBER='(0,0,0,0,0,0,0,0,0,0,0,0,0,0,0,0,0,0,0,0,0,0,0,0,0,CB61,0,0,0,~
0,0,0,0,0,0,0,0,0,0,0,0,0)';
      PINUSE='POWER';
      NO_LOAD_CHECK='Both';
      NO_IO_CHECK='Both';
      NO_ASSERT_CHECK='TRUE';
      NO_DIR_CHECK='TRUE';
      ALLOW_CONNECT='TRUE';
    'VCCIN253':
      PIN_NUMBER='(0,0,0,0,0,0,0,0,0,0,0,0,0,0,0,0,0,0,0,0,0,0,0,0,0,CA90,0,0,0,~
0,0,0,0,0,0,0,0,0,0,0,0,0)';
      PINUSE='POWER';
      NO_LOAD_CHECK='Both';
      NO_IO_CHECK='Both';
      NO_ASSERT_CHECK='TRUE';
      NO_DIR_CHECK='TRUE';
      ALLOW_CONNECT='TRUE';
    'VCCIN252':
      PIN_NUMBER='(0,0,0,0,0,0,0,0,0,0,0,0,0,0,0,0,0,0,0,0,0,0,0,0,0,CA88,0,0,0,~
0,0,0,0,0,0,0,0,0,0,0,0,0)';
      PINUSE='POWER';
      NO_LOAD_CHECK='Both';
      NO_IO_CHECK='Both';
      NO_ASSERT_CHECK='TRUE';
      NO_DIR_CHECK='TRUE';
      ALLOW_CONNECT='TRUE';
    'VCCIN251':
      PIN_NUMBER='(0,0,0,0,0,0,0,0,0,0,0,0,0,0,0,0,0,0,0,0,0,0,0,0,0,CA86,0,0,0,~
0,0,0,0,0,0,0,0,0,0,0,0,0)';
      PINUSE='POWER';
      NO_LOAD_CHECK='Both';
      NO_IO_CHECK='Both';
      NO_ASSERT_CHECK='TRUE';
      NO_DIR_CHECK='TRUE';
      ALLOW_CONNECT='TRUE';
    'VCCIN250':
      PIN_NUMBER='(0,0,0,0,0,0,0,0,0,0,0,0,0,0,0,0,0,0,0,0,0,0,0,0,0,CA84,0,0,0,~
0,0,0,0,0,0,0,0,0,0,0,0,0)';
      PINUSE='POWER';
      NO_LOAD_CHECK='Both';
      NO_IO_CHECK='Both';
      NO_ASSERT_CHECK='TRUE';
      NO_DIR_CHECK='TRUE';
      ALLOW_CONNECT='TRUE';
    'VCCIN249':
      PIN_NUMBER='(0,0,0,0,0,0,0,0,0,0,0,0,0,0,0,0,0,0,0,0,0,0,0,0,0,CA82,0,0,0,~
0,0,0,0,0,0,0,0,0,0,0,0,0)';
      PINUSE='POWER';
      NO_LOAD_CHECK='Both';
      NO_IO_CHECK='Both';
      NO_ASSERT_CHECK='TRUE';
      NO_DIR_CHECK='TRUE';
      ALLOW_CONNECT='TRUE';
    'VCCIN248':
      PIN_NUMBER='(0,0,0,0,0,0,0,0,0,0,0,0,0,0,0,0,0,0,0,0,0,0,0,0,0,CA80,0,0,0,~
0,0,0,0,0,0,0,0,0,0,0,0,0)';
      PINUSE='POWER';
      NO_LOAD_CHECK='Both';
      NO_IO_CHECK='Both';
      NO_ASSERT_CHECK='TRUE';
      NO_DIR_CHECK='TRUE';
      ALLOW_CONNECT='TRUE';
    'VCCIN247':
      PIN_NUMBER='(0,0,0,0,0,0,0,0,0,0,0,0,0,0,0,0,0,0,0,0,0,0,0,0,0,CA78,0,0,0,~
0,0,0,0,0,0,0,0,0,0,0,0,0)';
      PINUSE='POWER';
      NO_LOAD_CHECK='Both';
      NO_IO_CHECK='Both';
      NO_ASSERT_CHECK='TRUE';
      NO_DIR_CHECK='TRUE';
      ALLOW_CONNECT='TRUE';
    'VCCIN246':
      PIN_NUMBER='(0,0,0,0,0,0,0,0,0,0,0,0,0,0,0,0,0,0,0,0,0,0,0,0,0,CA76,0,0,0,~
0,0,0,0,0,0,0,0,0,0,0,0,0)';
      PINUSE='POWER';
      NO_LOAD_CHECK='Both';
      NO_IO_CHECK='Both';
      NO_ASSERT_CHECK='TRUE';
      NO_DIR_CHECK='TRUE';
      ALLOW_CONNECT='TRUE';
    'VCCIN245':
      PIN_NUMBER='(0,0,0,0,0,0,0,0,0,0,0,0,0,0,0,0,0,0,0,0,0,0,0,0,0,CA74,0,0,0,~
0,0,0,0,0,0,0,0,0,0,0,0,0)';
      PINUSE='POWER';
      NO_LOAD_CHECK='Both';
      NO_IO_CHECK='Both';
      NO_ASSERT_CHECK='TRUE';
      NO_DIR_CHECK='TRUE';
      ALLOW_CONNECT='TRUE';
    'VCCIN244':
      PIN_NUMBER='(0,0,0,0,0,0,0,0,0,0,0,0,0,0,0,0,0,0,0,0,0,0,0,0,0,CA72,0,0,0,~
0,0,0,0,0,0,0,0,0,0,0,0,0)';
      PINUSE='POWER';
      NO_LOAD_CHECK='Both';
      NO_IO_CHECK='Both';
      NO_ASSERT_CHECK='TRUE';
      NO_DIR_CHECK='TRUE';
      ALLOW_CONNECT='TRUE';
    'VCCIN243':
      PIN_NUMBER='(0,0,0,0,0,0,0,0,0,0,0,0,0,0,0,0,0,0,0,0,0,0,0,0,0,CA70,0,0,0,~
0,0,0,0,0,0,0,0,0,0,0,0,0)';
      PINUSE='POWER';
      NO_LOAD_CHECK='Both';
      NO_IO_CHECK='Both';
      NO_ASSERT_CHECK='TRUE';
      NO_DIR_CHECK='TRUE';
      ALLOW_CONNECT='TRUE';
    'VCCIN242':
      PIN_NUMBER='(0,0,0,0,0,0,0,0,0,0,0,0,0,0,0,0,0,0,0,0,0,0,0,0,0,CA68,0,0,0,~
0,0,0,0,0,0,0,0,0,0,0,0,0)';
      PINUSE='POWER';
      NO_LOAD_CHECK='Both';
      NO_IO_CHECK='Both';
      NO_ASSERT_CHECK='TRUE';
      NO_DIR_CHECK='TRUE';
      ALLOW_CONNECT='TRUE';
    'VCCIN241':
      PIN_NUMBER='(0,0,0,0,0,0,0,0,0,0,0,0,0,0,0,0,0,0,0,0,0,0,0,0,0,CA66,0,0,0,~
0,0,0,0,0,0,0,0,0,0,0,0,0)';
      PINUSE='POWER';
      NO_LOAD_CHECK='Both';
      NO_IO_CHECK='Both';
      NO_ASSERT_CHECK='TRUE';
      NO_DIR_CHECK='TRUE';
      ALLOW_CONNECT='TRUE';
    'VCCIN240':
      PIN_NUMBER='(0,0,0,0,0,0,0,0,0,0,0,0,0,0,0,0,0,0,0,0,0,0,0,0,0,CA64,0,0,0,~
0,0,0,0,0,0,0,0,0,0,0,0,0)';
      PINUSE='POWER';
      NO_LOAD_CHECK='Both';
      NO_IO_CHECK='Both';
      NO_ASSERT_CHECK='TRUE';
      NO_DIR_CHECK='TRUE';
      ALLOW_CONNECT='TRUE';
    'VCCIN239':
      PIN_NUMBER='(0,0,0,0,0,0,0,0,0,0,0,0,0,0,0,0,0,0,0,0,0,0,0,0,0,CA62,0,0,0,~
0,0,0,0,0,0,0,0,0,0,0,0,0)';
      PINUSE='POWER';
      NO_LOAD_CHECK='Both';
      NO_IO_CHECK='Both';
      NO_ASSERT_CHECK='TRUE';
      NO_DIR_CHECK='TRUE';
      ALLOW_CONNECT='TRUE';
    'VCCIN238':
      PIN_NUMBER='(0,0,0,0,0,0,0,0,0,0,0,0,0,0,0,0,0,0,0,0,0,0,0,0,0,CA60,0,0,0,~
0,0,0,0,0,0,0,0,0,0,0,0,0)';
      PINUSE='POWER';
      NO_LOAD_CHECK='Both';
      NO_IO_CHECK='Both';
      NO_ASSERT_CHECK='TRUE';
      NO_DIR_CHECK='TRUE';
      ALLOW_CONNECT='TRUE';
    'VCCIN237':
      PIN_NUMBER='(0,0,0,0,0,0,0,0,0,0,0,0,0,0,0,0,0,0,0,0,0,0,0,0,0,CA58,0,0,0,~
0,0,0,0,0,0,0,0,0,0,0,0,0)';
      PINUSE='POWER';
      NO_LOAD_CHECK='Both';
      NO_IO_CHECK='Both';
      NO_ASSERT_CHECK='TRUE';
      NO_DIR_CHECK='TRUE';
      ALLOW_CONNECT='TRUE';
    'VCCIN236':
      PIN_NUMBER='(0,0,0,0,0,0,0,0,0,0,0,0,0,0,0,0,0,0,0,0,0,0,0,0,0,CA56,0,0,0,~
0,0,0,0,0,0,0,0,0,0,0,0,0)';
      PINUSE='POWER';
      NO_LOAD_CHECK='Both';
      NO_IO_CHECK='Both';
      NO_ASSERT_CHECK='TRUE';
      NO_DIR_CHECK='TRUE';
      ALLOW_CONNECT='TRUE';
    'VCCIN235':
      PIN_NUMBER='(0,0,0,0,0,0,0,0,0,0,0,0,0,0,0,0,0,0,0,0,0,0,0,0,0,CA54,0,0,0,~
0,0,0,0,0,0,0,0,0,0,0,0,0)';
      PINUSE='POWER';
      NO_LOAD_CHECK='Both';
      NO_IO_CHECK='Both';
      NO_ASSERT_CHECK='TRUE';
      NO_DIR_CHECK='TRUE';
      ALLOW_CONNECT='TRUE';
    'VCCIN234':
      PIN_NUMBER='(0,0,0,0,0,0,0,0,0,0,0,0,0,0,0,0,0,0,0,0,0,0,0,0,0,CA52,0,0,0,~
0,0,0,0,0,0,0,0,0,0,0,0,0)';
      PINUSE='POWER';
      NO_LOAD_CHECK='Both';
      NO_IO_CHECK='Both';
      NO_ASSERT_CHECK='TRUE';
      NO_DIR_CHECK='TRUE';
      ALLOW_CONNECT='TRUE';
    'VCCIN233':
      PIN_NUMBER='(0,0,0,0,0,0,0,0,0,0,0,0,0,0,0,0,0,0,0,0,0,0,0,0,0,CA50,0,0,0,~
0,0,0,0,0,0,0,0,0,0,0,0,0)';
      PINUSE='POWER';
      NO_LOAD_CHECK='Both';
      NO_IO_CHECK='Both';
      NO_ASSERT_CHECK='TRUE';
      NO_DIR_CHECK='TRUE';
      ALLOW_CONNECT='TRUE';
    'VCCIN232':
      PIN_NUMBER='(0,0,0,0,0,0,0,0,0,0,0,0,0,0,0,0,0,0,0,0,0,0,0,0,0,CA48,0,0,0,~
0,0,0,0,0,0,0,0,0,0,0,0,0)';
      PINUSE='POWER';
      NO_LOAD_CHECK='Both';
      NO_IO_CHECK='Both';
      NO_ASSERT_CHECK='TRUE';
      NO_DIR_CHECK='TRUE';
      ALLOW_CONNECT='TRUE';
    'VCCIN231':
      PIN_NUMBER='(0,0,0,0,0,0,0,0,0,0,0,0,0,0,0,0,0,0,0,0,0,0,0,0,0,CA45,0,0,0,~
0,0,0,0,0,0,0,0,0,0,0,0,0)';
      PINUSE='POWER';
      NO_LOAD_CHECK='Both';
      NO_IO_CHECK='Both';
      NO_ASSERT_CHECK='TRUE';
      NO_DIR_CHECK='TRUE';
      ALLOW_CONNECT='TRUE';
    'VCCIN230':
      PIN_NUMBER='(0,0,0,0,0,0,0,0,0,0,0,0,0,0,0,0,0,0,0,0,0,0,0,0,0,CA43,0,0,0,~
0,0,0,0,0,0,0,0,0,0,0,0,0)';
      PINUSE='POWER';
      NO_LOAD_CHECK='Both';
      NO_IO_CHECK='Both';
      NO_ASSERT_CHECK='TRUE';
      NO_DIR_CHECK='TRUE';
      ALLOW_CONNECT='TRUE';
    'VCCIN229':
      PIN_NUMBER='(0,0,0,0,0,0,0,0,0,0,0,0,0,0,0,0,0,0,0,0,0,0,0,0,0,CA41,0,0,0,~
0,0,0,0,0,0,0,0,0,0,0,0,0)';
      PINUSE='POWER';
      NO_LOAD_CHECK='Both';
      NO_IO_CHECK='Both';
      NO_ASSERT_CHECK='TRUE';
      NO_DIR_CHECK='TRUE';
      ALLOW_CONNECT='TRUE';
    'VCCIN228':
      PIN_NUMBER='(0,0,0,0,0,0,0,0,0,0,0,0,0,0,0,0,0,0,0,0,0,0,0,0,0,CA39,0,0,0,~
0,0,0,0,0,0,0,0,0,0,0,0,0)';
      PINUSE='POWER';
      NO_LOAD_CHECK='Both';
      NO_IO_CHECK='Both';
      NO_ASSERT_CHECK='TRUE';
      NO_DIR_CHECK='TRUE';
      ALLOW_CONNECT='TRUE';
    'VCCIN227':
      PIN_NUMBER='(0,0,0,0,0,0,0,0,0,0,0,0,0,0,0,0,0,0,0,0,0,0,0,0,0,CA37,0,0,0,~
0,0,0,0,0,0,0,0,0,0,0,0,0)';
      PINUSE='POWER';
      NO_LOAD_CHECK='Both';
      NO_IO_CHECK='Both';
      NO_ASSERT_CHECK='TRUE';
      NO_DIR_CHECK='TRUE';
      ALLOW_CONNECT='TRUE';
    'VCCIN226':
      PIN_NUMBER='(0,0,0,0,0,0,0,0,0,0,0,0,0,0,0,0,0,0,0,0,0,0,0,0,0,CA35,0,0,0,~
0,0,0,0,0,0,0,0,0,0,0,0,0)';
      PINUSE='POWER';
      NO_LOAD_CHECK='Both';
      NO_IO_CHECK='Both';
      NO_ASSERT_CHECK='TRUE';
      NO_DIR_CHECK='TRUE';
      ALLOW_CONNECT='TRUE';
    'VCCIN225':
      PIN_NUMBER='(0,0,0,0,0,0,0,0,0,0,0,0,0,0,0,0,0,0,0,0,0,0,0,0,0,CA33,0,0,0,~
0,0,0,0,0,0,0,0,0,0,0,0,0)';
      PINUSE='POWER';
      NO_LOAD_CHECK='Both';
      NO_IO_CHECK='Both';
      NO_ASSERT_CHECK='TRUE';
      NO_DIR_CHECK='TRUE';
      ALLOW_CONNECT='TRUE';
    'VCCIN224':
      PIN_NUMBER='(0,0,0,0,0,0,0,0,0,0,0,0,0,0,0,0,0,0,0,0,0,0,0,0,0,BY89,0,0,0,~
0,0,0,0,0,0,0,0,0,0,0,0,0)';
      PINUSE='POWER';
      NO_LOAD_CHECK='Both';
      NO_IO_CHECK='Both';
      NO_ASSERT_CHECK='TRUE';
      NO_DIR_CHECK='TRUE';
      ALLOW_CONNECT='TRUE';
    'VCCIN223':
      PIN_NUMBER='(0,0,0,0,0,0,0,0,0,0,0,0,0,0,0,0,0,0,0,0,0,0,0,0,0,BY87,0,0,0,~
0,0,0,0,0,0,0,0,0,0,0,0,0)';
      PINUSE='POWER';
      NO_LOAD_CHECK='Both';
      NO_IO_CHECK='Both';
      NO_ASSERT_CHECK='TRUE';
      NO_DIR_CHECK='TRUE';
      ALLOW_CONNECT='TRUE';
    'VCCIN222':
      PIN_NUMBER='(0,0,0,0,0,0,0,0,0,0,0,0,0,0,0,0,0,0,0,0,0,0,0,0,0,BY85,0,0,0,~
0,0,0,0,0,0,0,0,0,0,0,0,0)';
      PINUSE='POWER';
      NO_LOAD_CHECK='Both';
      NO_IO_CHECK='Both';
      NO_ASSERT_CHECK='TRUE';
      NO_DIR_CHECK='TRUE';
      ALLOW_CONNECT='TRUE';
    'VCCIN221':
      PIN_NUMBER='(0,0,0,0,0,0,0,0,0,0,0,0,0,0,0,0,0,0,0,0,0,0,0,0,0,BY83,0,0,0,~
0,0,0,0,0,0,0,0,0,0,0,0,0)';
      PINUSE='POWER';
      NO_LOAD_CHECK='Both';
      NO_IO_CHECK='Both';
      NO_ASSERT_CHECK='TRUE';
      NO_DIR_CHECK='TRUE';
      ALLOW_CONNECT='TRUE';
    'VCCIN220':
      PIN_NUMBER='(0,0,0,0,0,0,0,0,0,0,0,0,0,0,0,0,0,0,0,0,0,0,0,0,0,BY81,0,0,0,~
0,0,0,0,0,0,0,0,0,0,0,0,0)';
      PINUSE='POWER';
      NO_LOAD_CHECK='Both';
      NO_IO_CHECK='Both';
      NO_ASSERT_CHECK='TRUE';
      NO_DIR_CHECK='TRUE';
      ALLOW_CONNECT='TRUE';
    'VCCIN219':
      PIN_NUMBER='(0,0,0,0,0,0,0,0,0,0,0,0,0,0,0,0,0,0,0,0,0,0,0,0,0,BY79,0,0,0,~
0,0,0,0,0,0,0,0,0,0,0,0,0)';
      PINUSE='POWER';
      NO_LOAD_CHECK='Both';
      NO_IO_CHECK='Both';
      NO_ASSERT_CHECK='TRUE';
      NO_DIR_CHECK='TRUE';
      ALLOW_CONNECT='TRUE';
    'VCCIN218':
      PIN_NUMBER='(0,0,0,0,0,0,0,0,0,0,0,0,0,0,0,0,0,0,0,0,0,0,0,0,0,BY77,0,0,0,~
0,0,0,0,0,0,0,0,0,0,0,0,0)';
      PINUSE='POWER';
      NO_LOAD_CHECK='Both';
      NO_IO_CHECK='Both';
      NO_ASSERT_CHECK='TRUE';
      NO_DIR_CHECK='TRUE';
      ALLOW_CONNECT='TRUE';
    'VCCIN217':
      PIN_NUMBER='(0,0,0,0,0,0,0,0,0,0,0,0,0,0,0,0,0,0,0,0,0,0,0,0,0,BY75,0,0,0,~
0,0,0,0,0,0,0,0,0,0,0,0,0)';
      PINUSE='POWER';
      NO_LOAD_CHECK='Both';
      NO_IO_CHECK='Both';
      NO_ASSERT_CHECK='TRUE';
      NO_DIR_CHECK='TRUE';
      ALLOW_CONNECT='TRUE';
    'VCCIN216':
      PIN_NUMBER='(0,0,0,0,0,0,0,0,0,0,0,0,0,0,0,0,0,0,0,0,0,0,0,0,0,BY73,0,0,0,~
0,0,0,0,0,0,0,0,0,0,0,0,0)';
      PINUSE='POWER';
      NO_LOAD_CHECK='Both';
      NO_IO_CHECK='Both';
      NO_ASSERT_CHECK='TRUE';
      NO_DIR_CHECK='TRUE';
      ALLOW_CONNECT='TRUE';
    'VCCIN215':
      PIN_NUMBER='(0,0,0,0,0,0,0,0,0,0,0,0,0,0,0,0,0,0,0,0,0,0,0,0,0,BY71,0,0,0,~
0,0,0,0,0,0,0,0,0,0,0,0,0)';
      PINUSE='POWER';
      NO_LOAD_CHECK='Both';
      NO_IO_CHECK='Both';
      NO_ASSERT_CHECK='TRUE';
      NO_DIR_CHECK='TRUE';
      ALLOW_CONNECT='TRUE';
    'VCCIN214':
      PIN_NUMBER='(0,0,0,0,0,0,0,0,0,0,0,0,0,0,0,0,0,0,0,0,0,0,0,0,0,BY69,0,0,0,~
0,0,0,0,0,0,0,0,0,0,0,0,0)';
      PINUSE='POWER';
      NO_LOAD_CHECK='Both';
      NO_IO_CHECK='Both';
      NO_ASSERT_CHECK='TRUE';
      NO_DIR_CHECK='TRUE';
      ALLOW_CONNECT='TRUE';
    'VCCIN213':
      PIN_NUMBER='(0,0,0,0,0,0,0,0,0,0,0,0,0,0,0,0,0,0,0,0,0,0,0,0,0,BY67,0,0,0,~
0,0,0,0,0,0,0,0,0,0,0,0,0)';
      PINUSE='POWER';
      NO_LOAD_CHECK='Both';
      NO_IO_CHECK='Both';
      NO_ASSERT_CHECK='TRUE';
      NO_DIR_CHECK='TRUE';
      ALLOW_CONNECT='TRUE';
    'VCCIN212':
      PIN_NUMBER='(0,0,0,0,0,0,0,0,0,0,0,0,0,0,0,0,0,0,0,0,0,0,0,0,0,BY65,0,0,0,~
0,0,0,0,0,0,0,0,0,0,0,0,0)';
      PINUSE='POWER';
      NO_LOAD_CHECK='Both';
      NO_IO_CHECK='Both';
      NO_ASSERT_CHECK='TRUE';
      NO_DIR_CHECK='TRUE';
      ALLOW_CONNECT='TRUE';
    'VCCIN211':
      PIN_NUMBER='(0,0,0,0,0,0,0,0,0,0,0,0,0,0,0,0,0,0,0,0,0,0,0,0,0,BY63,0,0,0,~
0,0,0,0,0,0,0,0,0,0,0,0,0)';
      PINUSE='POWER';
      NO_LOAD_CHECK='Both';
      NO_IO_CHECK='Both';
      NO_ASSERT_CHECK='TRUE';
      NO_DIR_CHECK='TRUE';
      ALLOW_CONNECT='TRUE';
    'VCCIN210':
      PIN_NUMBER='(0,0,0,0,0,0,0,0,0,0,0,0,0,0,0,0,0,0,0,0,0,0,0,0,0,BY61,0,0,0,~
0,0,0,0,0,0,0,0,0,0,0,0,0)';
      PINUSE='POWER';
      NO_LOAD_CHECK='Both';
      NO_IO_CHECK='Both';
      NO_ASSERT_CHECK='TRUE';
      NO_DIR_CHECK='TRUE';
      ALLOW_CONNECT='TRUE';
    'VCCIN209':
      PIN_NUMBER='(0,0,0,0,0,0,0,0,0,0,0,0,0,0,0,0,0,0,0,0,0,0,0,0,0,BY59,0,0,0,~
0,0,0,0,0,0,0,0,0,0,0,0,0)';
      PINUSE='POWER';
      NO_LOAD_CHECK='Both';
      NO_IO_CHECK='Both';
      NO_ASSERT_CHECK='TRUE';
      NO_DIR_CHECK='TRUE';
      ALLOW_CONNECT='TRUE';
    'VCCIN208':
      PIN_NUMBER='(0,0,0,0,0,0,0,0,0,0,0,0,0,0,0,0,0,0,0,0,0,0,0,0,0,BY57,0,0,0,~
0,0,0,0,0,0,0,0,0,0,0,0,0)';
      PINUSE='POWER';
      NO_LOAD_CHECK='Both';
      NO_IO_CHECK='Both';
      NO_ASSERT_CHECK='TRUE';
      NO_DIR_CHECK='TRUE';
      ALLOW_CONNECT='TRUE';
    'VCCIN207':
      PIN_NUMBER='(0,0,0,0,0,0,0,0,0,0,0,0,0,0,0,0,0,0,0,0,0,0,0,0,0,BY55,0,0,0,~
0,0,0,0,0,0,0,0,0,0,0,0,0)';
      PINUSE='POWER';
      NO_LOAD_CHECK='Both';
      NO_IO_CHECK='Both';
      NO_ASSERT_CHECK='TRUE';
      NO_DIR_CHECK='TRUE';
      ALLOW_CONNECT='TRUE';
    'VCCIN206':
      PIN_NUMBER='(0,0,0,0,0,0,0,0,0,0,0,0,0,0,0,0,0,0,0,0,0,0,0,0,0,BY53,0,0,0,~
0,0,0,0,0,0,0,0,0,0,0,0,0)';
      PINUSE='POWER';
      NO_LOAD_CHECK='Both';
      NO_IO_CHECK='Both';
      NO_ASSERT_CHECK='TRUE';
      NO_DIR_CHECK='TRUE';
      ALLOW_CONNECT='TRUE';
    'VCCIN205':
      PIN_NUMBER='(0,0,0,0,0,0,0,0,0,0,0,0,0,0,0,0,0,0,0,0,0,0,0,0,0,BY51,0,0,0,~
0,0,0,0,0,0,0,0,0,0,0,0,0)';
      PINUSE='POWER';
      NO_LOAD_CHECK='Both';
      NO_IO_CHECK='Both';
      NO_ASSERT_CHECK='TRUE';
      NO_DIR_CHECK='TRUE';
      ALLOW_CONNECT='TRUE';
    'VCCIN204':
      PIN_NUMBER='(0,0,0,0,0,0,0,0,0,0,0,0,0,0,0,0,0,0,0,0,0,0,0,0,0,BY49,0,0,0,~
0,0,0,0,0,0,0,0,0,0,0,0,0)';
      PINUSE='POWER';
      NO_LOAD_CHECK='Both';
      NO_IO_CHECK='Both';
      NO_ASSERT_CHECK='TRUE';
      NO_DIR_CHECK='TRUE';
      ALLOW_CONNECT='TRUE';
    'VCCIN203':
      PIN_NUMBER='(0,0,0,0,0,0,0,0,0,0,0,0,0,0,0,0,0,0,0,0,0,0,0,0,0,BY47,0,0,0,~
0,0,0,0,0,0,0,0,0,0,0,0,0)';
      PINUSE='POWER';
      NO_LOAD_CHECK='Both';
      NO_IO_CHECK='Both';
      NO_ASSERT_CHECK='TRUE';
      NO_DIR_CHECK='TRUE';
      ALLOW_CONNECT='TRUE';
    'VCCIN202':
      PIN_NUMBER='(0,0,0,0,0,0,0,0,0,0,0,0,0,0,0,0,0,0,0,0,0,0,0,0,0,BY44,0,0,0,~
0,0,0,0,0,0,0,0,0,0,0,0,0)';
      PINUSE='POWER';
      NO_LOAD_CHECK='Both';
      NO_IO_CHECK='Both';
      NO_ASSERT_CHECK='TRUE';
      NO_DIR_CHECK='TRUE';
      ALLOW_CONNECT='TRUE';
    'VCCIN201':
      PIN_NUMBER='(0,0,0,0,0,0,0,0,0,0,0,0,0,0,0,0,0,0,0,0,0,0,0,0,0,BY42,0,0,0,~
0,0,0,0,0,0,0,0,0,0,0,0,0)';
      PINUSE='POWER';
      NO_LOAD_CHECK='Both';
      NO_IO_CHECK='Both';
      NO_ASSERT_CHECK='TRUE';
      NO_DIR_CHECK='TRUE';
      ALLOW_CONNECT='TRUE';
    'VCCIN200':
      PIN_NUMBER='(0,0,0,0,0,0,0,0,0,0,0,0,0,0,0,0,0,0,0,0,0,0,0,0,0,BY40,0,0,0,~
0,0,0,0,0,0,0,0,0,0,0,0,0)';
      PINUSE='POWER';
      NO_LOAD_CHECK='Both';
      NO_IO_CHECK='Both';
      NO_ASSERT_CHECK='TRUE';
      NO_DIR_CHECK='TRUE';
      ALLOW_CONNECT='TRUE';
    'VCCIN199':
      PIN_NUMBER='(0,0,0,0,0,0,0,0,0,0,0,0,0,0,0,0,0,0,0,0,0,0,0,0,0,BY38,0,0,0,~
0,0,0,0,0,0,0,0,0,0,0,0,0)';
      PINUSE='POWER';
      NO_LOAD_CHECK='Both';
      NO_IO_CHECK='Both';
      NO_ASSERT_CHECK='TRUE';
      NO_DIR_CHECK='TRUE';
      ALLOW_CONNECT='TRUE';
    'VCCIN198':
      PIN_NUMBER='(0,0,0,0,0,0,0,0,0,0,0,0,0,0,0,0,0,0,0,0,0,0,0,0,0,BY36,0,0,0,~
0,0,0,0,0,0,0,0,0,0,0,0,0)';
      PINUSE='POWER';
      NO_LOAD_CHECK='Both';
      NO_IO_CHECK='Both';
      NO_ASSERT_CHECK='TRUE';
      NO_DIR_CHECK='TRUE';
      ALLOW_CONNECT='TRUE';
    'VCCIN197':
      PIN_NUMBER='(0,0,0,0,0,0,0,0,0,0,0,0,0,0,0,0,0,0,0,0,0,0,0,0,0,BY34,0,0,0,~
0,0,0,0,0,0,0,0,0,0,0,0,0)';
      PINUSE='POWER';
      NO_LOAD_CHECK='Both';
      NO_IO_CHECK='Both';
      NO_ASSERT_CHECK='TRUE';
      NO_DIR_CHECK='TRUE';
      ALLOW_CONNECT='TRUE';
    'VCCIN196':
      PIN_NUMBER='(0,0,0,0,0,0,0,0,0,0,0,0,0,0,0,0,0,0,0,0,0,0,0,0,0,BY32,0,0,0,~
0,0,0,0,0,0,0,0,0,0,0,0,0)';
      PINUSE='POWER';
      NO_LOAD_CHECK='Both';
      NO_IO_CHECK='Both';
      NO_ASSERT_CHECK='TRUE';
      NO_DIR_CHECK='TRUE';
      ALLOW_CONNECT='TRUE';
    'VCCIN195':
      PIN_NUMBER='(0,0,0,0,0,0,0,0,0,0,0,0,0,0,0,0,0,0,0,0,0,0,0,0,0,BW90,0,0,0,~
0,0,0,0,0,0,0,0,0,0,0,0,0)';
      PINUSE='POWER';
      NO_LOAD_CHECK='Both';
      NO_IO_CHECK='Both';
      NO_ASSERT_CHECK='TRUE';
      NO_DIR_CHECK='TRUE';
      ALLOW_CONNECT='TRUE';
    'VCCIN194':
      PIN_NUMBER='(0,0,0,0,0,0,0,0,0,0,0,0,0,0,0,0,0,0,0,0,0,0,0,0,0,BW88,0,0,0,~
0,0,0,0,0,0,0,0,0,0,0,0,0)';
      PINUSE='POWER';
      NO_LOAD_CHECK='Both';
      NO_IO_CHECK='Both';
      NO_ASSERT_CHECK='TRUE';
      NO_DIR_CHECK='TRUE';
      ALLOW_CONNECT='TRUE';
    'VCCIN193':
      PIN_NUMBER='(0,0,0,0,0,0,0,0,0,0,0,0,0,0,0,0,0,0,0,0,0,0,0,0,0,BW86,0,0,0,~
0,0,0,0,0,0,0,0,0,0,0,0,0)';
      PINUSE='POWER';
      NO_LOAD_CHECK='Both';
      NO_IO_CHECK='Both';
      NO_ASSERT_CHECK='TRUE';
      NO_DIR_CHECK='TRUE';
      ALLOW_CONNECT='TRUE';
    'VCCIN192':
      PIN_NUMBER='(0,0,0,0,0,0,0,0,0,0,0,0,0,0,0,0,0,0,0,0,0,0,0,0,0,BW84,0,0,0,~
0,0,0,0,0,0,0,0,0,0,0,0,0)';
      PINUSE='POWER';
      NO_LOAD_CHECK='Both';
      NO_IO_CHECK='Both';
      NO_ASSERT_CHECK='TRUE';
      NO_DIR_CHECK='TRUE';
      ALLOW_CONNECT='TRUE';
    'VCCIN191':
      PIN_NUMBER='(0,0,0,0,0,0,0,0,0,0,0,0,0,0,0,0,0,0,0,0,0,0,0,0,0,BW82,0,0,0,~
0,0,0,0,0,0,0,0,0,0,0,0,0)';
      PINUSE='POWER';
      NO_LOAD_CHECK='Both';
      NO_IO_CHECK='Both';
      NO_ASSERT_CHECK='TRUE';
      NO_DIR_CHECK='TRUE';
      ALLOW_CONNECT='TRUE';
    'VCCIN190':
      PIN_NUMBER='(0,0,0,0,0,0,0,0,0,0,0,0,0,0,0,0,0,0,0,0,0,0,0,0,0,BW80,0,0,0,~
0,0,0,0,0,0,0,0,0,0,0,0,0)';
      PINUSE='POWER';
      NO_LOAD_CHECK='Both';
      NO_IO_CHECK='Both';
      NO_ASSERT_CHECK='TRUE';
      NO_DIR_CHECK='TRUE';
      ALLOW_CONNECT='TRUE';
    'VCCIN189':
      PIN_NUMBER='(0,0,0,0,0,0,0,0,0,0,0,0,0,0,0,0,0,0,0,0,0,0,0,0,0,0,BW78,0,0,~
0,0,0,0,0,0,0,0,0,0,0,0,0)';
      PINUSE='POWER';
      NO_LOAD_CHECK='Both';
      NO_IO_CHECK='Both';
      NO_ASSERT_CHECK='TRUE';
      NO_DIR_CHECK='TRUE';
      ALLOW_CONNECT='TRUE';
    'VCCIN188':
      PIN_NUMBER='(0,0,0,0,0,0,0,0,0,0,0,0,0,0,0,0,0,0,0,0,0,0,0,0,0,0,BW76,0,0,~
0,0,0,0,0,0,0,0,0,0,0,0,0)';
      PINUSE='POWER';
      NO_LOAD_CHECK='Both';
      NO_IO_CHECK='Both';
      NO_ASSERT_CHECK='TRUE';
      NO_DIR_CHECK='TRUE';
      ALLOW_CONNECT='TRUE';
    'VCCIN187':
      PIN_NUMBER='(0,0,0,0,0,0,0,0,0,0,0,0,0,0,0,0,0,0,0,0,0,0,0,0,0,0,BW74,0,0,~
0,0,0,0,0,0,0,0,0,0,0,0,0)';
      PINUSE='POWER';
      NO_LOAD_CHECK='Both';
      NO_IO_CHECK='Both';
      NO_ASSERT_CHECK='TRUE';
      NO_DIR_CHECK='TRUE';
      ALLOW_CONNECT='TRUE';
    'VCCIN186':
      PIN_NUMBER='(0,0,0,0,0,0,0,0,0,0,0,0,0,0,0,0,0,0,0,0,0,0,0,0,0,0,BW72,0,0,~
0,0,0,0,0,0,0,0,0,0,0,0,0)';
      PINUSE='POWER';
      NO_LOAD_CHECK='Both';
      NO_IO_CHECK='Both';
      NO_ASSERT_CHECK='TRUE';
      NO_DIR_CHECK='TRUE';
      ALLOW_CONNECT='TRUE';
    'VCCIN185':
      PIN_NUMBER='(0,0,0,0,0,0,0,0,0,0,0,0,0,0,0,0,0,0,0,0,0,0,0,0,0,0,BW70,0,0,~
0,0,0,0,0,0,0,0,0,0,0,0,0)';
      PINUSE='POWER';
      NO_LOAD_CHECK='Both';
      NO_IO_CHECK='Both';
      NO_ASSERT_CHECK='TRUE';
      NO_DIR_CHECK='TRUE';
      ALLOW_CONNECT='TRUE';
    'VCCIN184':
      PIN_NUMBER='(0,0,0,0,0,0,0,0,0,0,0,0,0,0,0,0,0,0,0,0,0,0,0,0,0,0,BW68,0,0,~
0,0,0,0,0,0,0,0,0,0,0,0,0)';
      PINUSE='POWER';
      NO_LOAD_CHECK='Both';
      NO_IO_CHECK='Both';
      NO_ASSERT_CHECK='TRUE';
      NO_DIR_CHECK='TRUE';
      ALLOW_CONNECT='TRUE';
    'VCCIN183':
      PIN_NUMBER='(0,0,0,0,0,0,0,0,0,0,0,0,0,0,0,0,0,0,0,0,0,0,0,0,0,0,BW66,0,0,~
0,0,0,0,0,0,0,0,0,0,0,0,0)';
      PINUSE='POWER';
      NO_LOAD_CHECK='Both';
      NO_IO_CHECK='Both';
      NO_ASSERT_CHECK='TRUE';
      NO_DIR_CHECK='TRUE';
      ALLOW_CONNECT='TRUE';
    'VCCIN182':
      PIN_NUMBER='(0,0,0,0,0,0,0,0,0,0,0,0,0,0,0,0,0,0,0,0,0,0,0,0,0,0,BW64,0,0,~
0,0,0,0,0,0,0,0,0,0,0,0,0)';
      PINUSE='POWER';
      NO_LOAD_CHECK='Both';
      NO_IO_CHECK='Both';
      NO_ASSERT_CHECK='TRUE';
      NO_DIR_CHECK='TRUE';
      ALLOW_CONNECT='TRUE';
    'VCCIN181':
      PIN_NUMBER='(0,0,0,0,0,0,0,0,0,0,0,0,0,0,0,0,0,0,0,0,0,0,0,0,0,0,BW62,0,0,~
0,0,0,0,0,0,0,0,0,0,0,0,0)';
      PINUSE='POWER';
      NO_LOAD_CHECK='Both';
      NO_IO_CHECK='Both';
      NO_ASSERT_CHECK='TRUE';
      NO_DIR_CHECK='TRUE';
      ALLOW_CONNECT='TRUE';
    'VCCIN180':
      PIN_NUMBER='(0,0,0,0,0,0,0,0,0,0,0,0,0,0,0,0,0,0,0,0,0,0,0,0,0,0,BW60,0,0,~
0,0,0,0,0,0,0,0,0,0,0,0,0)';
      PINUSE='POWER';
      NO_LOAD_CHECK='Both';
      NO_IO_CHECK='Both';
      NO_ASSERT_CHECK='TRUE';
      NO_DIR_CHECK='TRUE';
      ALLOW_CONNECT='TRUE';
    'VCCIN179':
      PIN_NUMBER='(0,0,0,0,0,0,0,0,0,0,0,0,0,0,0,0,0,0,0,0,0,0,0,0,0,0,BW58,0,0,~
0,0,0,0,0,0,0,0,0,0,0,0,0)';
      PINUSE='POWER';
      NO_LOAD_CHECK='Both';
      NO_IO_CHECK='Both';
      NO_ASSERT_CHECK='TRUE';
      NO_DIR_CHECK='TRUE';
      ALLOW_CONNECT='TRUE';
    'VCCIN178':
      PIN_NUMBER='(0,0,0,0,0,0,0,0,0,0,0,0,0,0,0,0,0,0,0,0,0,0,0,0,0,0,BW56,0,0,~
0,0,0,0,0,0,0,0,0,0,0,0,0)';
      PINUSE='POWER';
      NO_LOAD_CHECK='Both';
      NO_IO_CHECK='Both';
      NO_ASSERT_CHECK='TRUE';
      NO_DIR_CHECK='TRUE';
      ALLOW_CONNECT='TRUE';
    'VCCIN177':
      PIN_NUMBER='(0,0,0,0,0,0,0,0,0,0,0,0,0,0,0,0,0,0,0,0,0,0,0,0,0,0,BW54,0,0,~
0,0,0,0,0,0,0,0,0,0,0,0,0)';
      PINUSE='POWER';
      NO_LOAD_CHECK='Both';
      NO_IO_CHECK='Both';
      NO_ASSERT_CHECK='TRUE';
      NO_DIR_CHECK='TRUE';
      ALLOW_CONNECT='TRUE';
    'VCCIN176':
      PIN_NUMBER='(0,0,0,0,0,0,0,0,0,0,0,0,0,0,0,0,0,0,0,0,0,0,0,0,0,0,BW52,0,0,~
0,0,0,0,0,0,0,0,0,0,0,0,0)';
      PINUSE='POWER';
      NO_LOAD_CHECK='Both';
      NO_IO_CHECK='Both';
      NO_ASSERT_CHECK='TRUE';
      NO_DIR_CHECK='TRUE';
      ALLOW_CONNECT='TRUE';
    'VCCIN175':
      PIN_NUMBER='(0,0,0,0,0,0,0,0,0,0,0,0,0,0,0,0,0,0,0,0,0,0,0,0,0,0,BW50,0,0,~
0,0,0,0,0,0,0,0,0,0,0,0,0)';
      PINUSE='POWER';
      NO_LOAD_CHECK='Both';
      NO_IO_CHECK='Both';
      NO_ASSERT_CHECK='TRUE';
      NO_DIR_CHECK='TRUE';
      ALLOW_CONNECT='TRUE';
    'VCCIN174':
      PIN_NUMBER='(0,0,0,0,0,0,0,0,0,0,0,0,0,0,0,0,0,0,0,0,0,0,0,0,0,0,BW48,0,0,~
0,0,0,0,0,0,0,0,0,0,0,0,0)';
      PINUSE='POWER';
      NO_LOAD_CHECK='Both';
      NO_IO_CHECK='Both';
      NO_ASSERT_CHECK='TRUE';
      NO_DIR_CHECK='TRUE';
      ALLOW_CONNECT='TRUE';
    'VCCIN173':
      PIN_NUMBER='(0,0,0,0,0,0,0,0,0,0,0,0,0,0,0,0,0,0,0,0,0,0,0,0,0,0,BW45,0,0,~
0,0,0,0,0,0,0,0,0,0,0,0,0)';
      PINUSE='POWER';
      NO_LOAD_CHECK='Both';
      NO_IO_CHECK='Both';
      NO_ASSERT_CHECK='TRUE';
      NO_DIR_CHECK='TRUE';
      ALLOW_CONNECT='TRUE';
    'VCCIN172':
      PIN_NUMBER='(0,0,0,0,0,0,0,0,0,0,0,0,0,0,0,0,0,0,0,0,0,0,0,0,0,0,BW43,0,0,~
0,0,0,0,0,0,0,0,0,0,0,0,0)';
      PINUSE='POWER';
      NO_LOAD_CHECK='Both';
      NO_IO_CHECK='Both';
      NO_ASSERT_CHECK='TRUE';
      NO_DIR_CHECK='TRUE';
      ALLOW_CONNECT='TRUE';
    'VCCIN171':
      PIN_NUMBER='(0,0,0,0,0,0,0,0,0,0,0,0,0,0,0,0,0,0,0,0,0,0,0,0,0,0,BW41,0,0,~
0,0,0,0,0,0,0,0,0,0,0,0,0)';
      PINUSE='POWER';
      NO_LOAD_CHECK='Both';
      NO_IO_CHECK='Both';
      NO_ASSERT_CHECK='TRUE';
      NO_DIR_CHECK='TRUE';
      ALLOW_CONNECT='TRUE';
    'VCCIN170':
      PIN_NUMBER='(0,0,0,0,0,0,0,0,0,0,0,0,0,0,0,0,0,0,0,0,0,0,0,0,0,0,BW39,0,0,~
0,0,0,0,0,0,0,0,0,0,0,0,0)';
      PINUSE='POWER';
      NO_LOAD_CHECK='Both';
      NO_IO_CHECK='Both';
      NO_ASSERT_CHECK='TRUE';
      NO_DIR_CHECK='TRUE';
      ALLOW_CONNECT='TRUE';
    'VCCIN169':
      PIN_NUMBER='(0,0,0,0,0,0,0,0,0,0,0,0,0,0,0,0,0,0,0,0,0,0,0,0,0,0,BW37,0,0,~
0,0,0,0,0,0,0,0,0,0,0,0,0)';
      PINUSE='POWER';
      NO_LOAD_CHECK='Both';
      NO_IO_CHECK='Both';
      NO_ASSERT_CHECK='TRUE';
      NO_DIR_CHECK='TRUE';
      ALLOW_CONNECT='TRUE';
    'VCCIN168':
      PIN_NUMBER='(0,0,0,0,0,0,0,0,0,0,0,0,0,0,0,0,0,0,0,0,0,0,0,0,0,0,BW35,0,0,~
0,0,0,0,0,0,0,0,0,0,0,0,0)';
      PINUSE='POWER';
      NO_LOAD_CHECK='Both';
      NO_IO_CHECK='Both';
      NO_ASSERT_CHECK='TRUE';
      NO_DIR_CHECK='TRUE';
      ALLOW_CONNECT='TRUE';
    'VCCIN167':
      PIN_NUMBER='(0,0,0,0,0,0,0,0,0,0,0,0,0,0,0,0,0,0,0,0,0,0,0,0,0,0,BW33,0,0,~
0,0,0,0,0,0,0,0,0,0,0,0,0)';
      PINUSE='POWER';
      NO_LOAD_CHECK='Both';
      NO_IO_CHECK='Both';
      NO_ASSERT_CHECK='TRUE';
      NO_DIR_CHECK='TRUE';
      ALLOW_CONNECT='TRUE';
    'VCCIN166':
      PIN_NUMBER='(0,0,0,0,0,0,0,0,0,0,0,0,0,0,0,0,0,0,0,0,0,0,0,0,0,0,BV89,0,0,~
0,0,0,0,0,0,0,0,0,0,0,0,0)';
      PINUSE='POWER';
      NO_LOAD_CHECK='Both';
      NO_IO_CHECK='Both';
      NO_ASSERT_CHECK='TRUE';
      NO_DIR_CHECK='TRUE';
      ALLOW_CONNECT='TRUE';
    'VCCIN165':
      PIN_NUMBER='(0,0,0,0,0,0,0,0,0,0,0,0,0,0,0,0,0,0,0,0,0,0,0,0,0,0,BV87,0,0,~
0,0,0,0,0,0,0,0,0,0,0,0,0)';
      PINUSE='POWER';
      NO_LOAD_CHECK='Both';
      NO_IO_CHECK='Both';
      NO_ASSERT_CHECK='TRUE';
      NO_DIR_CHECK='TRUE';
      ALLOW_CONNECT='TRUE';
    'VCCIN164':
      PIN_NUMBER='(0,0,0,0,0,0,0,0,0,0,0,0,0,0,0,0,0,0,0,0,0,0,0,0,0,0,BV85,0,0,~
0,0,0,0,0,0,0,0,0,0,0,0,0)';
      PINUSE='POWER';
      NO_LOAD_CHECK='Both';
      NO_IO_CHECK='Both';
      NO_ASSERT_CHECK='TRUE';
      NO_DIR_CHECK='TRUE';
      ALLOW_CONNECT='TRUE';
    'VCCIN163':
      PIN_NUMBER='(0,0,0,0,0,0,0,0,0,0,0,0,0,0,0,0,0,0,0,0,0,0,0,0,0,0,BV83,0,0,~
0,0,0,0,0,0,0,0,0,0,0,0,0)';
      PINUSE='POWER';
      NO_LOAD_CHECK='Both';
      NO_IO_CHECK='Both';
      NO_ASSERT_CHECK='TRUE';
      NO_DIR_CHECK='TRUE';
      ALLOW_CONNECT='TRUE';
    'VCCIN162':
      PIN_NUMBER='(0,0,0,0,0,0,0,0,0,0,0,0,0,0,0,0,0,0,0,0,0,0,0,0,0,0,BV81,0,0,~
0,0,0,0,0,0,0,0,0,0,0,0,0)';
      PINUSE='POWER';
      NO_LOAD_CHECK='Both';
      NO_IO_CHECK='Both';
      NO_ASSERT_CHECK='TRUE';
      NO_DIR_CHECK='TRUE';
      ALLOW_CONNECT='TRUE';
    'VCCIN161':
      PIN_NUMBER='(0,0,0,0,0,0,0,0,0,0,0,0,0,0,0,0,0,0,0,0,0,0,0,0,0,0,BV79,0,0,~
0,0,0,0,0,0,0,0,0,0,0,0,0)';
      PINUSE='POWER';
      NO_LOAD_CHECK='Both';
      NO_IO_CHECK='Both';
      NO_ASSERT_CHECK='TRUE';
      NO_DIR_CHECK='TRUE';
      ALLOW_CONNECT='TRUE';
    'VCCIN160':
      PIN_NUMBER='(0,0,0,0,0,0,0,0,0,0,0,0,0,0,0,0,0,0,0,0,0,0,0,0,0,0,BV77,0,0,~
0,0,0,0,0,0,0,0,0,0,0,0,0)';
      PINUSE='POWER';
      NO_LOAD_CHECK='Both';
      NO_IO_CHECK='Both';
      NO_ASSERT_CHECK='TRUE';
      NO_DIR_CHECK='TRUE';
      ALLOW_CONNECT='TRUE';
    'VCCIN159':
      PIN_NUMBER='(0,0,0,0,0,0,0,0,0,0,0,0,0,0,0,0,0,0,0,0,0,0,0,0,0,0,BV75,0,0,~
0,0,0,0,0,0,0,0,0,0,0,0,0)';
      PINUSE='POWER';
      NO_LOAD_CHECK='Both';
      NO_IO_CHECK='Both';
      NO_ASSERT_CHECK='TRUE';
      NO_DIR_CHECK='TRUE';
      ALLOW_CONNECT='TRUE';
    'VCCIN158':
      PIN_NUMBER='(0,0,0,0,0,0,0,0,0,0,0,0,0,0,0,0,0,0,0,0,0,0,0,0,0,0,BV73,0,0,~
0,0,0,0,0,0,0,0,0,0,0,0,0)';
      PINUSE='POWER';
      NO_LOAD_CHECK='Both';
      NO_IO_CHECK='Both';
      NO_ASSERT_CHECK='TRUE';
      NO_DIR_CHECK='TRUE';
      ALLOW_CONNECT='TRUE';
    'VCCIN157':
      PIN_NUMBER='(0,0,0,0,0,0,0,0,0,0,0,0,0,0,0,0,0,0,0,0,0,0,0,0,0,0,BV71,0,0,~
0,0,0,0,0,0,0,0,0,0,0,0,0)';
      PINUSE='POWER';
      NO_LOAD_CHECK='Both';
      NO_IO_CHECK='Both';
      NO_ASSERT_CHECK='TRUE';
      NO_DIR_CHECK='TRUE';
      ALLOW_CONNECT='TRUE';
    'VCCIN156':
      PIN_NUMBER='(0,0,0,0,0,0,0,0,0,0,0,0,0,0,0,0,0,0,0,0,0,0,0,0,0,0,BV69,0,0,~
0,0,0,0,0,0,0,0,0,0,0,0,0)';
      PINUSE='POWER';
      NO_LOAD_CHECK='Both';
      NO_IO_CHECK='Both';
      NO_ASSERT_CHECK='TRUE';
      NO_DIR_CHECK='TRUE';
      ALLOW_CONNECT='TRUE';
    'VCCIN155':
      PIN_NUMBER='(0,0,0,0,0,0,0,0,0,0,0,0,0,0,0,0,0,0,0,0,0,0,0,0,0,0,BV67,0,0,~
0,0,0,0,0,0,0,0,0,0,0,0,0)';
      PINUSE='POWER';
      NO_LOAD_CHECK='Both';
      NO_IO_CHECK='Both';
      NO_ASSERT_CHECK='TRUE';
      NO_DIR_CHECK='TRUE';
      ALLOW_CONNECT='TRUE';
    'VCCIN154':
      PIN_NUMBER='(0,0,0,0,0,0,0,0,0,0,0,0,0,0,0,0,0,0,0,0,0,0,0,0,0,0,BV65,0,0,~
0,0,0,0,0,0,0,0,0,0,0,0,0)';
      PINUSE='POWER';
      NO_LOAD_CHECK='Both';
      NO_IO_CHECK='Both';
      NO_ASSERT_CHECK='TRUE';
      NO_DIR_CHECK='TRUE';
      ALLOW_CONNECT='TRUE';
    'VCCIN153':
      PIN_NUMBER='(0,0,0,0,0,0,0,0,0,0,0,0,0,0,0,0,0,0,0,0,0,0,0,0,0,0,BV63,0,0,~
0,0,0,0,0,0,0,0,0,0,0,0,0)';
      PINUSE='POWER';
      NO_LOAD_CHECK='Both';
      NO_IO_CHECK='Both';
      NO_ASSERT_CHECK='TRUE';
      NO_DIR_CHECK='TRUE';
      ALLOW_CONNECT='TRUE';
    'VCCIN152':
      PIN_NUMBER='(0,0,0,0,0,0,0,0,0,0,0,0,0,0,0,0,0,0,0,0,0,0,0,0,0,0,BV61,0,0,~
0,0,0,0,0,0,0,0,0,0,0,0,0)';
      PINUSE='POWER';
      NO_LOAD_CHECK='Both';
      NO_IO_CHECK='Both';
      NO_ASSERT_CHECK='TRUE';
      NO_DIR_CHECK='TRUE';
      ALLOW_CONNECT='TRUE';
    'VCCIN151':
      PIN_NUMBER='(0,0,0,0,0,0,0,0,0,0,0,0,0,0,0,0,0,0,0,0,0,0,0,0,0,0,BV59,0,0,~
0,0,0,0,0,0,0,0,0,0,0,0,0)';
      PINUSE='POWER';
      NO_LOAD_CHECK='Both';
      NO_IO_CHECK='Both';
      NO_ASSERT_CHECK='TRUE';
      NO_DIR_CHECK='TRUE';
      ALLOW_CONNECT='TRUE';
    'VCCIN150':
      PIN_NUMBER='(0,0,0,0,0,0,0,0,0,0,0,0,0,0,0,0,0,0,0,0,0,0,0,0,0,0,BV57,0,0,~
0,0,0,0,0,0,0,0,0,0,0,0,0)';
      PINUSE='POWER';
      NO_LOAD_CHECK='Both';
      NO_IO_CHECK='Both';
      NO_ASSERT_CHECK='TRUE';
      NO_DIR_CHECK='TRUE';
      ALLOW_CONNECT='TRUE';
    'VCCIN149':
      PIN_NUMBER='(0,0,0,0,0,0,0,0,0,0,0,0,0,0,0,0,0,0,0,0,0,0,0,0,0,0,BV55,0,0,~
0,0,0,0,0,0,0,0,0,0,0,0,0)';
      PINUSE='POWER';
      NO_LOAD_CHECK='Both';
      NO_IO_CHECK='Both';
      NO_ASSERT_CHECK='TRUE';
      NO_DIR_CHECK='TRUE';
      ALLOW_CONNECT='TRUE';
    'VCCIN148':
      PIN_NUMBER='(0,0,0,0,0,0,0,0,0,0,0,0,0,0,0,0,0,0,0,0,0,0,0,0,0,0,BV53,0,0,~
0,0,0,0,0,0,0,0,0,0,0,0,0)';
      PINUSE='POWER';
      NO_LOAD_CHECK='Both';
      NO_IO_CHECK='Both';
      NO_ASSERT_CHECK='TRUE';
      NO_DIR_CHECK='TRUE';
      ALLOW_CONNECT='TRUE';
    'VCCIN147':
      PIN_NUMBER='(0,0,0,0,0,0,0,0,0,0,0,0,0,0,0,0,0,0,0,0,0,0,0,0,0,0,BV51,0,0,~
0,0,0,0,0,0,0,0,0,0,0,0,0)';
      PINUSE='POWER';
      NO_LOAD_CHECK='Both';
      NO_IO_CHECK='Both';
      NO_ASSERT_CHECK='TRUE';
      NO_DIR_CHECK='TRUE';
      ALLOW_CONNECT='TRUE';
    'VCCIN146':
      PIN_NUMBER='(0,0,0,0,0,0,0,0,0,0,0,0,0,0,0,0,0,0,0,0,0,0,0,0,0,0,BV49,0,0,~
0,0,0,0,0,0,0,0,0,0,0,0,0)';
      PINUSE='POWER';
      NO_LOAD_CHECK='Both';
      NO_IO_CHECK='Both';
      NO_ASSERT_CHECK='TRUE';
      NO_DIR_CHECK='TRUE';
      ALLOW_CONNECT='TRUE';
    'VCCIN145':
      PIN_NUMBER='(0,0,0,0,0,0,0,0,0,0,0,0,0,0,0,0,0,0,0,0,0,0,0,0,0,0,BV47,0,0,~
0,0,0,0,0,0,0,0,0,0,0,0,0)';
      PINUSE='POWER';
      NO_LOAD_CHECK='Both';
      NO_IO_CHECK='Both';
      NO_ASSERT_CHECK='TRUE';
      NO_DIR_CHECK='TRUE';
      ALLOW_CONNECT='TRUE';
    'VCCIN144':
      PIN_NUMBER='(0,0,0,0,0,0,0,0,0,0,0,0,0,0,0,0,0,0,0,0,0,0,0,0,0,0,BV44,0,0,~
0,0,0,0,0,0,0,0,0,0,0,0,0)';
      PINUSE='POWER';
      NO_LOAD_CHECK='Both';
      NO_IO_CHECK='Both';
      NO_ASSERT_CHECK='TRUE';
      NO_DIR_CHECK='TRUE';
      ALLOW_CONNECT='TRUE';
    'VCCIN143':
      PIN_NUMBER='(0,0,0,0,0,0,0,0,0,0,0,0,0,0,0,0,0,0,0,0,0,0,0,0,0,0,BV42,0,0,~
0,0,0,0,0,0,0,0,0,0,0,0,0)';
      PINUSE='POWER';
      NO_LOAD_CHECK='Both';
      NO_IO_CHECK='Both';
      NO_ASSERT_CHECK='TRUE';
      NO_DIR_CHECK='TRUE';
      ALLOW_CONNECT='TRUE';
    'VCCIN142':
      PIN_NUMBER='(0,0,0,0,0,0,0,0,0,0,0,0,0,0,0,0,0,0,0,0,0,0,0,0,0,0,BV40,0,0,~
0,0,0,0,0,0,0,0,0,0,0,0,0)';
      PINUSE='POWER';
      NO_LOAD_CHECK='Both';
      NO_IO_CHECK='Both';
      NO_ASSERT_CHECK='TRUE';
      NO_DIR_CHECK='TRUE';
      ALLOW_CONNECT='TRUE';
    'VCCIN141':
      PIN_NUMBER='(0,0,0,0,0,0,0,0,0,0,0,0,0,0,0,0,0,0,0,0,0,0,0,0,0,0,BV38,0,0,~
0,0,0,0,0,0,0,0,0,0,0,0,0)';
      PINUSE='POWER';
      NO_LOAD_CHECK='Both';
      NO_IO_CHECK='Both';
      NO_ASSERT_CHECK='TRUE';
      NO_DIR_CHECK='TRUE';
      ALLOW_CONNECT='TRUE';
    'VCCIN140':
      PIN_NUMBER='(0,0,0,0,0,0,0,0,0,0,0,0,0,0,0,0,0,0,0,0,0,0,0,0,0,0,BV36,0,0,~
0,0,0,0,0,0,0,0,0,0,0,0,0)';
      PINUSE='POWER';
      NO_LOAD_CHECK='Both';
      NO_IO_CHECK='Both';
      NO_ASSERT_CHECK='TRUE';
      NO_DIR_CHECK='TRUE';
      ALLOW_CONNECT='TRUE';
    'VCCIN139':
      PIN_NUMBER='(0,0,0,0,0,0,0,0,0,0,0,0,0,0,0,0,0,0,0,0,0,0,0,0,0,0,BV34,0,0,~
0,0,0,0,0,0,0,0,0,0,0,0,0)';
      PINUSE='POWER';
      NO_LOAD_CHECK='Both';
      NO_IO_CHECK='Both';
      NO_ASSERT_CHECK='TRUE';
      NO_DIR_CHECK='TRUE';
      ALLOW_CONNECT='TRUE';
    'VCCIN138':
      PIN_NUMBER='(0,0,0,0,0,0,0,0,0,0,0,0,0,0,0,0,0,0,0,0,0,0,0,0,0,0,BV32,0,0,~
0,0,0,0,0,0,0,0,0,0,0,0,0)';
      PINUSE='POWER';
      NO_LOAD_CHECK='Both';
      NO_IO_CHECK='Both';
      NO_ASSERT_CHECK='TRUE';
      NO_DIR_CHECK='TRUE';
      ALLOW_CONNECT='TRUE';
    'VCCIN137':
      PIN_NUMBER='(0,0,0,0,0,0,0,0,0,0,0,0,0,0,0,0,0,0,0,0,0,0,0,0,0,0,BU90,0,0,~
0,0,0,0,0,0,0,0,0,0,0,0,0)';
      PINUSE='POWER';
      NO_LOAD_CHECK='Both';
      NO_IO_CHECK='Both';
      NO_ASSERT_CHECK='TRUE';
      NO_DIR_CHECK='TRUE';
      ALLOW_CONNECT='TRUE';
    'VCCIN136':
      PIN_NUMBER='(0,0,0,0,0,0,0,0,0,0,0,0,0,0,0,0,0,0,0,0,0,0,0,0,0,0,BU88,0,0,~
0,0,0,0,0,0,0,0,0,0,0,0,0)';
      PINUSE='POWER';
      NO_LOAD_CHECK='Both';
      NO_IO_CHECK='Both';
      NO_ASSERT_CHECK='TRUE';
      NO_DIR_CHECK='TRUE';
      ALLOW_CONNECT='TRUE';
    'VCCIN135':
      PIN_NUMBER='(0,0,0,0,0,0,0,0,0,0,0,0,0,0,0,0,0,0,0,0,0,0,0,0,0,0,BU86,0,0,~
0,0,0,0,0,0,0,0,0,0,0,0,0)';
      PINUSE='POWER';
      NO_LOAD_CHECK='Both';
      NO_IO_CHECK='Both';
      NO_ASSERT_CHECK='TRUE';
      NO_DIR_CHECK='TRUE';
      ALLOW_CONNECT='TRUE';
    'VCCIN134':
      PIN_NUMBER='(0,0,0,0,0,0,0,0,0,0,0,0,0,0,0,0,0,0,0,0,0,0,0,0,0,0,BU84,0,0,~
0,0,0,0,0,0,0,0,0,0,0,0,0)';
      PINUSE='POWER';
      NO_LOAD_CHECK='Both';
      NO_IO_CHECK='Both';
      NO_ASSERT_CHECK='TRUE';
      NO_DIR_CHECK='TRUE';
      ALLOW_CONNECT='TRUE';
    'VCCIN133':
      PIN_NUMBER='(0,0,0,0,0,0,0,0,0,0,0,0,0,0,0,0,0,0,0,0,0,0,0,0,0,0,BU82,0,0,~
0,0,0,0,0,0,0,0,0,0,0,0,0)';
      PINUSE='POWER';
      NO_LOAD_CHECK='Both';
      NO_IO_CHECK='Both';
      NO_ASSERT_CHECK='TRUE';
      NO_DIR_CHECK='TRUE';
      ALLOW_CONNECT='TRUE';
    'VCCIN132':
      PIN_NUMBER='(0,0,0,0,0,0,0,0,0,0,0,0,0,0,0,0,0,0,0,0,0,0,0,0,0,0,BU80,0,0,~
0,0,0,0,0,0,0,0,0,0,0,0,0)';
      PINUSE='POWER';
      NO_LOAD_CHECK='Both';
      NO_IO_CHECK='Both';
      NO_ASSERT_CHECK='TRUE';
      NO_DIR_CHECK='TRUE';
      ALLOW_CONNECT='TRUE';
    'VCCIN131':
      PIN_NUMBER='(0,0,0,0,0,0,0,0,0,0,0,0,0,0,0,0,0,0,0,0,0,0,0,0,0,0,BU78,0,0,~
0,0,0,0,0,0,0,0,0,0,0,0,0)';
      PINUSE='POWER';
      NO_LOAD_CHECK='Both';
      NO_IO_CHECK='Both';
      NO_ASSERT_CHECK='TRUE';
      NO_DIR_CHECK='TRUE';
      ALLOW_CONNECT='TRUE';
    'VCCIN130':
      PIN_NUMBER='(0,0,0,0,0,0,0,0,0,0,0,0,0,0,0,0,0,0,0,0,0,0,0,0,0,0,BU76,0,0,~
0,0,0,0,0,0,0,0,0,0,0,0,0)';
      PINUSE='POWER';
      NO_LOAD_CHECK='Both';
      NO_IO_CHECK='Both';
      NO_ASSERT_CHECK='TRUE';
      NO_DIR_CHECK='TRUE';
      ALLOW_CONNECT='TRUE';
    'VCCIN129':
      PIN_NUMBER='(0,0,0,0,0,0,0,0,0,0,0,0,0,0,0,0,0,0,0,0,0,0,0,0,0,0,BU74,0,0,~
0,0,0,0,0,0,0,0,0,0,0,0,0)';
      PINUSE='POWER';
      NO_LOAD_CHECK='Both';
      NO_IO_CHECK='Both';
      NO_ASSERT_CHECK='TRUE';
      NO_DIR_CHECK='TRUE';
      ALLOW_CONNECT='TRUE';
    'VCCIN128':
      PIN_NUMBER='(0,0,0,0,0,0,0,0,0,0,0,0,0,0,0,0,0,0,0,0,0,0,0,0,0,0,BU72,0,0,~
0,0,0,0,0,0,0,0,0,0,0,0,0)';
      PINUSE='POWER';
      NO_LOAD_CHECK='Both';
      NO_IO_CHECK='Both';
      NO_ASSERT_CHECK='TRUE';
      NO_DIR_CHECK='TRUE';
      ALLOW_CONNECT='TRUE';
    'VCCIN127':
      PIN_NUMBER='(0,0,0,0,0,0,0,0,0,0,0,0,0,0,0,0,0,0,0,0,0,0,0,0,0,0,BU70,0,0,~
0,0,0,0,0,0,0,0,0,0,0,0,0)';
      PINUSE='POWER';
      NO_LOAD_CHECK='Both';
      NO_IO_CHECK='Both';
      NO_ASSERT_CHECK='TRUE';
      NO_DIR_CHECK='TRUE';
      ALLOW_CONNECT='TRUE';
    'VCCIN126':
      PIN_NUMBER='(0,0,0,0,0,0,0,0,0,0,0,0,0,0,0,0,0,0,0,0,0,0,0,0,0,0,BU68,0,0,~
0,0,0,0,0,0,0,0,0,0,0,0,0)';
      PINUSE='POWER';
      NO_LOAD_CHECK='Both';
      NO_IO_CHECK='Both';
      NO_ASSERT_CHECK='TRUE';
      NO_DIR_CHECK='TRUE';
      ALLOW_CONNECT='TRUE';
    'VCCIN125':
      PIN_NUMBER='(0,0,0,0,0,0,0,0,0,0,0,0,0,0,0,0,0,0,0,0,0,0,0,0,0,0,BU66,0,0,~
0,0,0,0,0,0,0,0,0,0,0,0,0)';
      PINUSE='POWER';
      NO_LOAD_CHECK='Both';
      NO_IO_CHECK='Both';
      NO_ASSERT_CHECK='TRUE';
      NO_DIR_CHECK='TRUE';
      ALLOW_CONNECT='TRUE';
    'VCCIN124':
      PIN_NUMBER='(0,0,0,0,0,0,0,0,0,0,0,0,0,0,0,0,0,0,0,0,0,0,0,0,0,0,BU64,0,0,~
0,0,0,0,0,0,0,0,0,0,0,0,0)';
      PINUSE='POWER';
      NO_LOAD_CHECK='Both';
      NO_IO_CHECK='Both';
      NO_ASSERT_CHECK='TRUE';
      NO_DIR_CHECK='TRUE';
      ALLOW_CONNECT='TRUE';
    'VCCIN123':
      PIN_NUMBER='(0,0,0,0,0,0,0,0,0,0,0,0,0,0,0,0,0,0,0,0,0,0,0,0,0,0,BU62,0,0,~
0,0,0,0,0,0,0,0,0,0,0,0,0)';
      PINUSE='POWER';
      NO_LOAD_CHECK='Both';
      NO_IO_CHECK='Both';
      NO_ASSERT_CHECK='TRUE';
      NO_DIR_CHECK='TRUE';
      ALLOW_CONNECT='TRUE';
    'VCCIN122':
      PIN_NUMBER='(0,0,0,0,0,0,0,0,0,0,0,0,0,0,0,0,0,0,0,0,0,0,0,0,0,0,BU60,0,0,~
0,0,0,0,0,0,0,0,0,0,0,0,0)';
      PINUSE='POWER';
      NO_LOAD_CHECK='Both';
      NO_IO_CHECK='Both';
      NO_ASSERT_CHECK='TRUE';
      NO_DIR_CHECK='TRUE';
      ALLOW_CONNECT='TRUE';
    'VCCIN121':
      PIN_NUMBER='(0,0,0,0,0,0,0,0,0,0,0,0,0,0,0,0,0,0,0,0,0,0,0,0,0,0,BU58,0,0,~
0,0,0,0,0,0,0,0,0,0,0,0,0)';
      PINUSE='POWER';
      NO_LOAD_CHECK='Both';
      NO_IO_CHECK='Both';
      NO_ASSERT_CHECK='TRUE';
      NO_DIR_CHECK='TRUE';
      ALLOW_CONNECT='TRUE';
    'VCCIN120':
      PIN_NUMBER='(0,0,0,0,0,0,0,0,0,0,0,0,0,0,0,0,0,0,0,0,0,0,0,0,0,0,BU56,0,0,~
0,0,0,0,0,0,0,0,0,0,0,0,0)';
      PINUSE='POWER';
      NO_LOAD_CHECK='Both';
      NO_IO_CHECK='Both';
      NO_ASSERT_CHECK='TRUE';
      NO_DIR_CHECK='TRUE';
      ALLOW_CONNECT='TRUE';
    'VCCIN119':
      PIN_NUMBER='(0,0,0,0,0,0,0,0,0,0,0,0,0,0,0,0,0,0,0,0,0,0,0,0,0,0,BU54,0,0,~
0,0,0,0,0,0,0,0,0,0,0,0,0)';
      PINUSE='POWER';
      NO_LOAD_CHECK='Both';
      NO_IO_CHECK='Both';
      NO_ASSERT_CHECK='TRUE';
      NO_DIR_CHECK='TRUE';
      ALLOW_CONNECT='TRUE';
    'VCCIN118':
      PIN_NUMBER='(0,0,0,0,0,0,0,0,0,0,0,0,0,0,0,0,0,0,0,0,0,0,0,0,0,0,BU52,0,0,~
0,0,0,0,0,0,0,0,0,0,0,0,0)';
      PINUSE='POWER';
      NO_LOAD_CHECK='Both';
      NO_IO_CHECK='Both';
      NO_ASSERT_CHECK='TRUE';
      NO_DIR_CHECK='TRUE';
      ALLOW_CONNECT='TRUE';
    'VCCIN117':
      PIN_NUMBER='(0,0,0,0,0,0,0,0,0,0,0,0,0,0,0,0,0,0,0,0,0,0,0,0,0,0,BU50,0,0,~
0,0,0,0,0,0,0,0,0,0,0,0,0)';
      PINUSE='POWER';
      NO_LOAD_CHECK='Both';
      NO_IO_CHECK='Both';
      NO_ASSERT_CHECK='TRUE';
      NO_DIR_CHECK='TRUE';
      ALLOW_CONNECT='TRUE';
    'VCCIN116':
      PIN_NUMBER='(0,0,0,0,0,0,0,0,0,0,0,0,0,0,0,0,0,0,0,0,0,0,0,0,0,0,BU48,0,0,~
0,0,0,0,0,0,0,0,0,0,0,0,0)';
      PINUSE='POWER';
      NO_LOAD_CHECK='Both';
      NO_IO_CHECK='Both';
      NO_ASSERT_CHECK='TRUE';
      NO_DIR_CHECK='TRUE';
      ALLOW_CONNECT='TRUE';
    'VCCIN115':
      PIN_NUMBER='(0,0,0,0,0,0,0,0,0,0,0,0,0,0,0,0,0,0,0,0,0,0,0,0,0,0,BU45,0,0,~
0,0,0,0,0,0,0,0,0,0,0,0,0)';
      PINUSE='POWER';
      NO_LOAD_CHECK='Both';
      NO_IO_CHECK='Both';
      NO_ASSERT_CHECK='TRUE';
      NO_DIR_CHECK='TRUE';
      ALLOW_CONNECT='TRUE';
    'VCCIN114':
      PIN_NUMBER='(0,0,0,0,0,0,0,0,0,0,0,0,0,0,0,0,0,0,0,0,0,0,0,0,0,0,BU43,0,0,~
0,0,0,0,0,0,0,0,0,0,0,0,0)';
      PINUSE='POWER';
      NO_LOAD_CHECK='Both';
      NO_IO_CHECK='Both';
      NO_ASSERT_CHECK='TRUE';
      NO_DIR_CHECK='TRUE';
      ALLOW_CONNECT='TRUE';
    'VCCIN113':
      PIN_NUMBER='(0,0,0,0,0,0,0,0,0,0,0,0,0,0,0,0,0,0,0,0,0,0,0,0,0,0,BU41,0,0,~
0,0,0,0,0,0,0,0,0,0,0,0,0)';
      PINUSE='POWER';
      NO_LOAD_CHECK='Both';
      NO_IO_CHECK='Both';
      NO_ASSERT_CHECK='TRUE';
      NO_DIR_CHECK='TRUE';
      ALLOW_CONNECT='TRUE';
    'VCCIN112':
      PIN_NUMBER='(0,0,0,0,0,0,0,0,0,0,0,0,0,0,0,0,0,0,0,0,0,0,0,0,0,0,BU39,0,0,~
0,0,0,0,0,0,0,0,0,0,0,0,0)';
      PINUSE='POWER';
      NO_LOAD_CHECK='Both';
      NO_IO_CHECK='Both';
      NO_ASSERT_CHECK='TRUE';
      NO_DIR_CHECK='TRUE';
      ALLOW_CONNECT='TRUE';
    'VCCIN111':
      PIN_NUMBER='(0,0,0,0,0,0,0,0,0,0,0,0,0,0,0,0,0,0,0,0,0,0,0,0,0,0,BU37,0,0,~
0,0,0,0,0,0,0,0,0,0,0,0,0)';
      PINUSE='POWER';
      NO_LOAD_CHECK='Both';
      NO_IO_CHECK='Both';
      NO_ASSERT_CHECK='TRUE';
      NO_DIR_CHECK='TRUE';
      ALLOW_CONNECT='TRUE';
    'VCCIN110':
      PIN_NUMBER='(0,0,0,0,0,0,0,0,0,0,0,0,0,0,0,0,0,0,0,0,0,0,0,0,0,0,BU35,0,0,~
0,0,0,0,0,0,0,0,0,0,0,0,0)';
      PINUSE='POWER';
      NO_LOAD_CHECK='Both';
      NO_IO_CHECK='Both';
      NO_ASSERT_CHECK='TRUE';
      NO_DIR_CHECK='TRUE';
      ALLOW_CONNECT='TRUE';
    'VCCIN109':
      PIN_NUMBER='(0,0,0,0,0,0,0,0,0,0,0,0,0,0,0,0,0,0,0,0,0,0,0,0,0,0,BU33,0,0,~
0,0,0,0,0,0,0,0,0,0,0,0,0)';
      PINUSE='POWER';
      NO_LOAD_CHECK='Both';
      NO_IO_CHECK='Both';
      NO_ASSERT_CHECK='TRUE';
      NO_DIR_CHECK='TRUE';
      ALLOW_CONNECT='TRUE';
    'VCCIN108':
      PIN_NUMBER='(0,0,0,0,0,0,0,0,0,0,0,0,0,0,0,0,0,0,0,0,0,0,0,0,0,0,BT89,0,0,~
0,0,0,0,0,0,0,0,0,0,0,0,0)';
      PINUSE='POWER';
      NO_LOAD_CHECK='Both';
      NO_IO_CHECK='Both';
      NO_ASSERT_CHECK='TRUE';
      NO_DIR_CHECK='TRUE';
      ALLOW_CONNECT='TRUE';
    'VCCIN107':
      PIN_NUMBER='(0,0,0,0,0,0,0,0,0,0,0,0,0,0,0,0,0,0,0,0,0,0,0,0,0,0,BT87,0,0,~
0,0,0,0,0,0,0,0,0,0,0,0,0)';
      PINUSE='POWER';
      NO_LOAD_CHECK='Both';
      NO_IO_CHECK='Both';
      NO_ASSERT_CHECK='TRUE';
      NO_DIR_CHECK='TRUE';
      ALLOW_CONNECT='TRUE';
    'VCCIN106':
      PIN_NUMBER='(0,0,0,0,0,0,0,0,0,0,0,0,0,0,0,0,0,0,0,0,0,0,0,0,0,0,BT85,0,0,~
0,0,0,0,0,0,0,0,0,0,0,0,0)';
      PINUSE='POWER';
      NO_LOAD_CHECK='Both';
      NO_IO_CHECK='Both';
      NO_ASSERT_CHECK='TRUE';
      NO_DIR_CHECK='TRUE';
      ALLOW_CONNECT='TRUE';
    'VCCIN105':
      PIN_NUMBER='(0,0,0,0,0,0,0,0,0,0,0,0,0,0,0,0,0,0,0,0,0,0,0,0,0,0,BT83,0,0,~
0,0,0,0,0,0,0,0,0,0,0,0,0)';
      PINUSE='POWER';
      NO_LOAD_CHECK='Both';
      NO_IO_CHECK='Both';
      NO_ASSERT_CHECK='TRUE';
      NO_DIR_CHECK='TRUE';
      ALLOW_CONNECT='TRUE';
    'VCCIN104':
      PIN_NUMBER='(0,0,0,0,0,0,0,0,0,0,0,0,0,0,0,0,0,0,0,0,0,0,0,0,0,0,BT81,0,0,~
0,0,0,0,0,0,0,0,0,0,0,0,0)';
      PINUSE='POWER';
      NO_LOAD_CHECK='Both';
      NO_IO_CHECK='Both';
      NO_ASSERT_CHECK='TRUE';
      NO_DIR_CHECK='TRUE';
      ALLOW_CONNECT='TRUE';
    'VCCIN103':
      PIN_NUMBER='(0,0,0,0,0,0,0,0,0,0,0,0,0,0,0,0,0,0,0,0,0,0,0,0,0,0,BT79,0,0,~
0,0,0,0,0,0,0,0,0,0,0,0,0)';
      PINUSE='POWER';
      NO_LOAD_CHECK='Both';
      NO_IO_CHECK='Both';
      NO_ASSERT_CHECK='TRUE';
      NO_DIR_CHECK='TRUE';
      ALLOW_CONNECT='TRUE';
    'VCCIN102':
      PIN_NUMBER='(0,0,0,0,0,0,0,0,0,0,0,0,0,0,0,0,0,0,0,0,0,0,0,0,0,0,BT77,0,0,~
0,0,0,0,0,0,0,0,0,0,0,0,0)';
      PINUSE='POWER';
      NO_LOAD_CHECK='Both';
      NO_IO_CHECK='Both';
      NO_ASSERT_CHECK='TRUE';
      NO_DIR_CHECK='TRUE';
      ALLOW_CONNECT='TRUE';
    'VCCIN101':
      PIN_NUMBER='(0,0,0,0,0,0,0,0,0,0,0,0,0,0,0,0,0,0,0,0,0,0,0,0,0,0,BT75,0,0,~
0,0,0,0,0,0,0,0,0,0,0,0,0)';
      PINUSE='POWER';
      NO_LOAD_CHECK='Both';
      NO_IO_CHECK='Both';
      NO_ASSERT_CHECK='TRUE';
      NO_DIR_CHECK='TRUE';
      ALLOW_CONNECT='TRUE';
    'VCCIN100':
      PIN_NUMBER='(0,0,0,0,0,0,0,0,0,0,0,0,0,0,0,0,0,0,0,0,0,0,0,0,0,0,BT73,0,0,~
0,0,0,0,0,0,0,0,0,0,0,0,0)';
      PINUSE='POWER';
      NO_LOAD_CHECK='Both';
      NO_IO_CHECK='Both';
      NO_ASSERT_CHECK='TRUE';
      NO_DIR_CHECK='TRUE';
      ALLOW_CONNECT='TRUE';
    'VCCIN99':
      PIN_NUMBER='(0,0,0,0,0,0,0,0,0,0,0,0,0,0,0,0,0,0,0,0,0,0,0,0,0,0,BT71,0,0,~
0,0,0,0,0,0,0,0,0,0,0,0,0)';
      PINUSE='POWER';
      NO_LOAD_CHECK='Both';
      NO_IO_CHECK='Both';
      NO_ASSERT_CHECK='TRUE';
      NO_DIR_CHECK='TRUE';
      ALLOW_CONNECT='TRUE';
    'VCCIN98':
      PIN_NUMBER='(0,0,0,0,0,0,0,0,0,0,0,0,0,0,0,0,0,0,0,0,0,0,0,0,0,0,BT69,0,0,~
0,0,0,0,0,0,0,0,0,0,0,0,0)';
      PINUSE='POWER';
      NO_LOAD_CHECK='Both';
      NO_IO_CHECK='Both';
      NO_ASSERT_CHECK='TRUE';
      NO_DIR_CHECK='TRUE';
      ALLOW_CONNECT='TRUE';
    'VCCIN97':
      PIN_NUMBER='(0,0,0,0,0,0,0,0,0,0,0,0,0,0,0,0,0,0,0,0,0,0,0,0,0,0,BT67,0,0,~
0,0,0,0,0,0,0,0,0,0,0,0,0)';
      PINUSE='POWER';
      NO_LOAD_CHECK='Both';
      NO_IO_CHECK='Both';
      NO_ASSERT_CHECK='TRUE';
      NO_DIR_CHECK='TRUE';
      ALLOW_CONNECT='TRUE';
    'VCCIN96':
      PIN_NUMBER='(0,0,0,0,0,0,0,0,0,0,0,0,0,0,0,0,0,0,0,0,0,0,0,0,0,0,BT65,0,0,~
0,0,0,0,0,0,0,0,0,0,0,0,0)';
      PINUSE='POWER';
      NO_LOAD_CHECK='Both';
      NO_IO_CHECK='Both';
      NO_ASSERT_CHECK='TRUE';
      NO_DIR_CHECK='TRUE';
      ALLOW_CONNECT='TRUE';
    'VCCIN95':
      PIN_NUMBER='(0,0,0,0,0,0,0,0,0,0,0,0,0,0,0,0,0,0,0,0,0,0,0,0,0,0,BT63,0,0,~
0,0,0,0,0,0,0,0,0,0,0,0,0)';
      PINUSE='POWER';
      NO_LOAD_CHECK='Both';
      NO_IO_CHECK='Both';
      NO_ASSERT_CHECK='TRUE';
      NO_DIR_CHECK='TRUE';
      ALLOW_CONNECT='TRUE';
    'VCCIN94':
      PIN_NUMBER='(0,0,0,0,0,0,0,0,0,0,0,0,0,0,0,0,0,0,0,0,0,0,0,0,0,0,BT61,0,0,~
0,0,0,0,0,0,0,0,0,0,0,0,0)';
      PINUSE='POWER';
      NO_LOAD_CHECK='Both';
      NO_IO_CHECK='Both';
      NO_ASSERT_CHECK='TRUE';
      NO_DIR_CHECK='TRUE';
      ALLOW_CONNECT='TRUE';
    'VCCIN93':
      PIN_NUMBER='(0,0,0,0,0,0,0,0,0,0,0,0,0,0,0,0,0,0,0,0,0,0,0,0,0,0,BT59,0,0,~
0,0,0,0,0,0,0,0,0,0,0,0,0)';
      PINUSE='POWER';
      NO_LOAD_CHECK='Both';
      NO_IO_CHECK='Both';
      NO_ASSERT_CHECK='TRUE';
      NO_DIR_CHECK='TRUE';
      ALLOW_CONNECT='TRUE';
    'VCCIN92':
      PIN_NUMBER='(0,0,0,0,0,0,0,0,0,0,0,0,0,0,0,0,0,0,0,0,0,0,0,0,0,0,BT57,0,0,~
0,0,0,0,0,0,0,0,0,0,0,0,0)';
      PINUSE='POWER';
      NO_LOAD_CHECK='Both';
      NO_IO_CHECK='Both';
      NO_ASSERT_CHECK='TRUE';
      NO_DIR_CHECK='TRUE';
      ALLOW_CONNECT='TRUE';
    'VCCIN91':
      PIN_NUMBER='(0,0,0,0,0,0,0,0,0,0,0,0,0,0,0,0,0,0,0,0,0,0,0,0,0,0,BT55,0,0,~
0,0,0,0,0,0,0,0,0,0,0,0,0)';
      PINUSE='POWER';
      NO_LOAD_CHECK='Both';
      NO_IO_CHECK='Both';
      NO_ASSERT_CHECK='TRUE';
      NO_DIR_CHECK='TRUE';
      ALLOW_CONNECT='TRUE';
    'VCCIN90':
      PIN_NUMBER='(0,0,0,0,0,0,0,0,0,0,0,0,0,0,0,0,0,0,0,0,0,0,0,0,0,0,BT53,0,0,~
0,0,0,0,0,0,0,0,0,0,0,0,0)';
      PINUSE='POWER';
      NO_LOAD_CHECK='Both';
      NO_IO_CHECK='Both';
      NO_ASSERT_CHECK='TRUE';
      NO_DIR_CHECK='TRUE';
      ALLOW_CONNECT='TRUE';
    'VCCIN89':
      PIN_NUMBER='(0,0,0,0,0,0,0,0,0,0,0,0,0,0,0,0,0,0,0,0,0,0,0,0,0,0,BT51,0,0,~
0,0,0,0,0,0,0,0,0,0,0,0,0)';
      PINUSE='POWER';
      NO_LOAD_CHECK='Both';
      NO_IO_CHECK='Both';
      NO_ASSERT_CHECK='TRUE';
      NO_DIR_CHECK='TRUE';
      ALLOW_CONNECT='TRUE';
    'VCCIN88':
      PIN_NUMBER='(0,0,0,0,0,0,0,0,0,0,0,0,0,0,0,0,0,0,0,0,0,0,0,0,0,0,BT49,0,0,~
0,0,0,0,0,0,0,0,0,0,0,0,0)';
      PINUSE='POWER';
      NO_LOAD_CHECK='Both';
      NO_IO_CHECK='Both';
      NO_ASSERT_CHECK='TRUE';
      NO_DIR_CHECK='TRUE';
      ALLOW_CONNECT='TRUE';
    'VCCIN87':
      PIN_NUMBER='(0,0,0,0,0,0,0,0,0,0,0,0,0,0,0,0,0,0,0,0,0,0,0,0,0,0,BT47,0,0,~
0,0,0,0,0,0,0,0,0,0,0,0,0)';
      PINUSE='POWER';
      NO_LOAD_CHECK='Both';
      NO_IO_CHECK='Both';
      NO_ASSERT_CHECK='TRUE';
      NO_DIR_CHECK='TRUE';
      ALLOW_CONNECT='TRUE';
    'VCCIN86':
      PIN_NUMBER='(0,0,0,0,0,0,0,0,0,0,0,0,0,0,0,0,0,0,0,0,0,0,0,0,0,0,BT44,0,0,~
0,0,0,0,0,0,0,0,0,0,0,0,0)';
      PINUSE='POWER';
      NO_LOAD_CHECK='Both';
      NO_IO_CHECK='Both';
      NO_ASSERT_CHECK='TRUE';
      NO_DIR_CHECK='TRUE';
      ALLOW_CONNECT='TRUE';
    'VCCIN85':
      PIN_NUMBER='(0,0,0,0,0,0,0,0,0,0,0,0,0,0,0,0,0,0,0,0,0,0,0,0,0,0,BT42,0,0,~
0,0,0,0,0,0,0,0,0,0,0,0,0)';
      PINUSE='POWER';
      NO_LOAD_CHECK='Both';
      NO_IO_CHECK='Both';
      NO_ASSERT_CHECK='TRUE';
      NO_DIR_CHECK='TRUE';
      ALLOW_CONNECT='TRUE';
    'VCCIN84':
      PIN_NUMBER='(0,0,0,0,0,0,0,0,0,0,0,0,0,0,0,0,0,0,0,0,0,0,0,0,0,0,BT40,0,0,~
0,0,0,0,0,0,0,0,0,0,0,0,0)';
      PINUSE='POWER';
      NO_LOAD_CHECK='Both';
      NO_IO_CHECK='Both';
      NO_ASSERT_CHECK='TRUE';
      NO_DIR_CHECK='TRUE';
      ALLOW_CONNECT='TRUE';
    'VCCIN83':
      PIN_NUMBER='(0,0,0,0,0,0,0,0,0,0,0,0,0,0,0,0,0,0,0,0,0,0,0,0,0,0,BT38,0,0,~
0,0,0,0,0,0,0,0,0,0,0,0,0)';
      PINUSE='POWER';
      NO_LOAD_CHECK='Both';
      NO_IO_CHECK='Both';
      NO_ASSERT_CHECK='TRUE';
      NO_DIR_CHECK='TRUE';
      ALLOW_CONNECT='TRUE';
    'VCCIN82':
      PIN_NUMBER='(0,0,0,0,0,0,0,0,0,0,0,0,0,0,0,0,0,0,0,0,0,0,0,0,0,0,BT36,0,0,~
0,0,0,0,0,0,0,0,0,0,0,0,0)';
      PINUSE='POWER';
      NO_LOAD_CHECK='Both';
      NO_IO_CHECK='Both';
      NO_ASSERT_CHECK='TRUE';
      NO_DIR_CHECK='TRUE';
      ALLOW_CONNECT='TRUE';
    'VCCIN81':
      PIN_NUMBER='(0,0,0,0,0,0,0,0,0,0,0,0,0,0,0,0,0,0,0,0,0,0,0,0,0,0,BT34,0,0,~
0,0,0,0,0,0,0,0,0,0,0,0,0)';
      PINUSE='POWER';
      NO_LOAD_CHECK='Both';
      NO_IO_CHECK='Both';
      NO_ASSERT_CHECK='TRUE';
      NO_DIR_CHECK='TRUE';
      ALLOW_CONNECT='TRUE';
    'VCCIN80':
      PIN_NUMBER='(0,0,0,0,0,0,0,0,0,0,0,0,0,0,0,0,0,0,0,0,0,0,0,0,0,0,BT32,0,0,~
0,0,0,0,0,0,0,0,0,0,0,0,0)';
      PINUSE='POWER';
      NO_LOAD_CHECK='Both';
      NO_IO_CHECK='Both';
      NO_ASSERT_CHECK='TRUE';
      NO_DIR_CHECK='TRUE';
      ALLOW_CONNECT='TRUE';
    'VCCIN79':
      PIN_NUMBER='(0,0,0,0,0,0,0,0,0,0,0,0,0,0,0,0,0,0,0,0,0,0,0,0,0,0,BR78,0,0,~
0,0,0,0,0,0,0,0,0,0,0,0,0)';
      PINUSE='POWER';
      NO_LOAD_CHECK='Both';
      NO_IO_CHECK='Both';
      NO_ASSERT_CHECK='TRUE';
      NO_DIR_CHECK='TRUE';
      ALLOW_CONNECT='TRUE';
    'VCCIN78':
      PIN_NUMBER='(0,0,0,0,0,0,0,0,0,0,0,0,0,0,0,0,0,0,0,0,0,0,0,0,0,0,BR62,0,0,~
0,0,0,0,0,0,0,0,0,0,0,0,0)';
      PINUSE='POWER';
      NO_LOAD_CHECK='Both';
      NO_IO_CHECK='Both';
      NO_ASSERT_CHECK='TRUE';
      NO_DIR_CHECK='TRUE';
      ALLOW_CONNECT='TRUE';
    'VCCIN77':
      PIN_NUMBER='(0,0,0,0,0,0,0,0,0,0,0,0,0,0,0,0,0,0,0,0,0,0,0,0,0,0,BR60,0,0,~
0,0,0,0,0,0,0,0,0,0,0,0,0)';
      PINUSE='POWER';
      NO_LOAD_CHECK='Both';
      NO_IO_CHECK='Both';
      NO_ASSERT_CHECK='TRUE';
      NO_DIR_CHECK='TRUE';
      ALLOW_CONNECT='TRUE';
    'VCCIN76':
      PIN_NUMBER='(0,0,0,0,0,0,0,0,0,0,0,0,0,0,0,0,0,0,0,0,0,0,0,0,0,0,BP89,0,0,~
0,0,0,0,0,0,0,0,0,0,0,0,0)';
      PINUSE='POWER';
      NO_LOAD_CHECK='Both';
      NO_IO_CHECK='Both';
      NO_ASSERT_CHECK='TRUE';
      NO_DIR_CHECK='TRUE';
      ALLOW_CONNECT='TRUE';
    'VCCIN75':
      PIN_NUMBER='(0,0,0,0,0,0,0,0,0,0,0,0,0,0,0,0,0,0,0,0,0,0,0,0,0,0,BP87,0,0,~
0,0,0,0,0,0,0,0,0,0,0,0,0)';
      PINUSE='POWER';
      NO_LOAD_CHECK='Both';
      NO_IO_CHECK='Both';
      NO_ASSERT_CHECK='TRUE';
      NO_DIR_CHECK='TRUE';
      ALLOW_CONNECT='TRUE';
    'VCCIN74':
      PIN_NUMBER='(0,0,0,0,0,0,0,0,0,0,0,0,0,0,0,0,0,0,0,0,0,0,0,0,0,0,BP85,0,0,~
0,0,0,0,0,0,0,0,0,0,0,0,0)';
      PINUSE='POWER';
      NO_LOAD_CHECK='Both';
      NO_IO_CHECK='Both';
      NO_ASSERT_CHECK='TRUE';
      NO_DIR_CHECK='TRUE';
      ALLOW_CONNECT='TRUE';
    'VCCIN73':
      PIN_NUMBER='(0,0,0,0,0,0,0,0,0,0,0,0,0,0,0,0,0,0,0,0,0,0,0,0,0,0,BP83,0,0,~
0,0,0,0,0,0,0,0,0,0,0,0,0)';
      PINUSE='POWER';
      NO_LOAD_CHECK='Both';
      NO_IO_CHECK='Both';
      NO_ASSERT_CHECK='TRUE';
      NO_DIR_CHECK='TRUE';
      ALLOW_CONNECT='TRUE';
    'VCCIN72':
      PIN_NUMBER='(0,0,0,0,0,0,0,0,0,0,0,0,0,0,0,0,0,0,0,0,0,0,0,0,0,0,BP81,0,0,~
0,0,0,0,0,0,0,0,0,0,0,0,0)';
      PINUSE='POWER';
      NO_LOAD_CHECK='Both';
      NO_IO_CHECK='Both';
      NO_ASSERT_CHECK='TRUE';
      NO_DIR_CHECK='TRUE';
      ALLOW_CONNECT='TRUE';
    'VCCIN71':
      PIN_NUMBER='(0,0,0,0,0,0,0,0,0,0,0,0,0,0,0,0,0,0,0,0,0,0,0,0,0,0,BP79,0,0,~
0,0,0,0,0,0,0,0,0,0,0,0,0)';
      PINUSE='POWER';
      NO_LOAD_CHECK='Both';
      NO_IO_CHECK='Both';
      NO_ASSERT_CHECK='TRUE';
      NO_DIR_CHECK='TRUE';
      ALLOW_CONNECT='TRUE';
    'VCCIN70':
      PIN_NUMBER='(0,0,0,0,0,0,0,0,0,0,0,0,0,0,0,0,0,0,0,0,0,0,0,0,0,0,BP61,0,0,~
0,0,0,0,0,0,0,0,0,0,0,0,0)';
      PINUSE='POWER';
      NO_LOAD_CHECK='Both';
      NO_IO_CHECK='Both';
      NO_ASSERT_CHECK='TRUE';
      NO_DIR_CHECK='TRUE';
      ALLOW_CONNECT='TRUE';
    'VCCIN69':
      PIN_NUMBER='(0,0,0,0,0,0,0,0,0,0,0,0,0,0,0,0,0,0,0,0,0,0,0,0,0,0,BP59,0,0,~
0,0,0,0,0,0,0,0,0,0,0,0,0)';
      PINUSE='POWER';
      NO_LOAD_CHECK='Both';
      NO_IO_CHECK='Both';
      NO_ASSERT_CHECK='TRUE';
      NO_DIR_CHECK='TRUE';
      ALLOW_CONNECT='TRUE';
    'VCCIN68':
      PIN_NUMBER='(0,0,0,0,0,0,0,0,0,0,0,0,0,0,0,0,0,0,0,0,0,0,0,0,0,0,BP57,0,0,~
0,0,0,0,0,0,0,0,0,0,0,0,0)';
      PINUSE='POWER';
      NO_LOAD_CHECK='Both';
      NO_IO_CHECK='Both';
      NO_ASSERT_CHECK='TRUE';
      NO_DIR_CHECK='TRUE';
      ALLOW_CONNECT='TRUE';
    'VCCIN67':
      PIN_NUMBER='(0,0,0,0,0,0,0,0,0,0,0,0,0,0,0,0,0,0,0,0,0,0,0,0,0,0,BP55,0,0,~
0,0,0,0,0,0,0,0,0,0,0,0,0)';
      PINUSE='POWER';
      NO_LOAD_CHECK='Both';
      NO_IO_CHECK='Both';
      NO_ASSERT_CHECK='TRUE';
      NO_DIR_CHECK='TRUE';
      ALLOW_CONNECT='TRUE';
    'VCCIN66':
      PIN_NUMBER='(0,0,0,0,0,0,0,0,0,0,0,0,0,0,0,0,0,0,0,0,0,0,0,0,0,0,BP53,0,0,~
0,0,0,0,0,0,0,0,0,0,0,0,0)';
      PINUSE='POWER';
      NO_LOAD_CHECK='Both';
      NO_IO_CHECK='Both';
      NO_ASSERT_CHECK='TRUE';
      NO_DIR_CHECK='TRUE';
      ALLOW_CONNECT='TRUE';
    'VCCIN65':
      PIN_NUMBER='(0,0,0,0,0,0,0,0,0,0,0,0,0,0,0,0,0,0,0,0,0,0,0,0,0,0,BP51,0,0,~
0,0,0,0,0,0,0,0,0,0,0,0,0)';
      PINUSE='POWER';
      NO_LOAD_CHECK='Both';
      NO_IO_CHECK='Both';
      NO_ASSERT_CHECK='TRUE';
      NO_DIR_CHECK='TRUE';
      ALLOW_CONNECT='TRUE';
    'VCCIN64':
      PIN_NUMBER='(0,0,0,0,0,0,0,0,0,0,0,0,0,0,0,0,0,0,0,0,0,0,0,0,0,0,BP49,0,0,~
0,0,0,0,0,0,0,0,0,0,0,0,0)';
      PINUSE='POWER';
      NO_LOAD_CHECK='Both';
      NO_IO_CHECK='Both';
      NO_ASSERT_CHECK='TRUE';
      NO_DIR_CHECK='TRUE';
      ALLOW_CONNECT='TRUE';
    'VCCIN63':
      PIN_NUMBER='(0,0,0,0,0,0,0,0,0,0,0,0,0,0,0,0,0,0,0,0,0,0,0,0,0,0,BP47,0,0,~
0,0,0,0,0,0,0,0,0,0,0,0,0)';
      PINUSE='POWER';
      NO_LOAD_CHECK='Both';
      NO_IO_CHECK='Both';
      NO_ASSERT_CHECK='TRUE';
      NO_DIR_CHECK='TRUE';
      ALLOW_CONNECT='TRUE';
    'VCCIN62':
      PIN_NUMBER='(0,0,0,0,0,0,0,0,0,0,0,0,0,0,0,0,0,0,0,0,0,0,0,0,0,0,BP44,0,0,~
0,0,0,0,0,0,0,0,0,0,0,0,0)';
      PINUSE='POWER';
      NO_LOAD_CHECK='Both';
      NO_IO_CHECK='Both';
      NO_ASSERT_CHECK='TRUE';
      NO_DIR_CHECK='TRUE';
      ALLOW_CONNECT='TRUE';
    'VCCIN61':
      PIN_NUMBER='(0,0,0,0,0,0,0,0,0,0,0,0,0,0,0,0,0,0,0,0,0,0,0,0,0,0,BP42,0,0,~
0,0,0,0,0,0,0,0,0,0,0,0,0)';
      PINUSE='POWER';
      NO_LOAD_CHECK='Both';
      NO_IO_CHECK='Both';
      NO_ASSERT_CHECK='TRUE';
      NO_DIR_CHECK='TRUE';
      ALLOW_CONNECT='TRUE';
    'VCCIN60':
      PIN_NUMBER='(0,0,0,0,0,0,0,0,0,0,0,0,0,0,0,0,0,0,0,0,0,0,0,0,0,0,BP40,0,0,~
0,0,0,0,0,0,0,0,0,0,0,0,0)';
      PINUSE='POWER';
      NO_LOAD_CHECK='Both';
      NO_IO_CHECK='Both';
      NO_ASSERT_CHECK='TRUE';
      NO_DIR_CHECK='TRUE';
      ALLOW_CONNECT='TRUE';
    'VCCIN59':
      PIN_NUMBER='(0,0,0,0,0,0,0,0,0,0,0,0,0,0,0,0,0,0,0,0,0,0,0,0,0,0,BP38,0,0,~
0,0,0,0,0,0,0,0,0,0,0,0,0)';
      PINUSE='POWER';
      NO_LOAD_CHECK='Both';
      NO_IO_CHECK='Both';
      NO_ASSERT_CHECK='TRUE';
      NO_DIR_CHECK='TRUE';
      ALLOW_CONNECT='TRUE';
    'VCCIN58':
      PIN_NUMBER='(0,0,0,0,0,0,0,0,0,0,0,0,0,0,0,0,0,0,0,0,0,0,0,0,0,0,BP36,0,0,~
0,0,0,0,0,0,0,0,0,0,0,0,0)';
      PINUSE='POWER';
      NO_LOAD_CHECK='Both';
      NO_IO_CHECK='Both';
      NO_ASSERT_CHECK='TRUE';
      NO_DIR_CHECK='TRUE';
      ALLOW_CONNECT='TRUE';
    'VCCIN57':
      PIN_NUMBER='(0,0,0,0,0,0,0,0,0,0,0,0,0,0,0,0,0,0,0,0,0,0,0,0,0,0,BP34,0,0,~
0,0,0,0,0,0,0,0,0,0,0,0,0)';
      PINUSE='POWER';
      NO_LOAD_CHECK='Both';
      NO_IO_CHECK='Both';
      NO_ASSERT_CHECK='TRUE';
      NO_DIR_CHECK='TRUE';
      ALLOW_CONNECT='TRUE';
    'VCCIN56':
      PIN_NUMBER='(0,0,0,0,0,0,0,0,0,0,0,0,0,0,0,0,0,0,0,0,0,0,0,0,0,0,BP32,0,0,~
0,0,0,0,0,0,0,0,0,0,0,0,0)';
      PINUSE='POWER';
      NO_LOAD_CHECK='Both';
      NO_IO_CHECK='Both';
      NO_ASSERT_CHECK='TRUE';
      NO_DIR_CHECK='TRUE';
      ALLOW_CONNECT='TRUE';
    'VCCIN55':
      PIN_NUMBER='(0,0,0,0,0,0,0,0,0,0,0,0,0,0,0,0,0,0,0,0,0,0,0,0,0,0,BN90,0,0,~
0,0,0,0,0,0,0,0,0,0,0,0,0)';
      PINUSE='POWER';
      NO_LOAD_CHECK='Both';
      NO_IO_CHECK='Both';
      NO_ASSERT_CHECK='TRUE';
      NO_DIR_CHECK='TRUE';
      ALLOW_CONNECT='TRUE';
    'VCCIN54':
      PIN_NUMBER='(0,0,0,0,0,0,0,0,0,0,0,0,0,0,0,0,0,0,0,0,0,0,0,0,0,0,BN88,0,0,~
0,0,0,0,0,0,0,0,0,0,0,0,0)';
      PINUSE='POWER';
      NO_LOAD_CHECK='Both';
      NO_IO_CHECK='Both';
      NO_ASSERT_CHECK='TRUE';
      NO_DIR_CHECK='TRUE';
      ALLOW_CONNECT='TRUE';
    'VCCIN53':
      PIN_NUMBER='(0,0,0,0,0,0,0,0,0,0,0,0,0,0,0,0,0,0,0,0,0,0,0,0,0,0,BN86,0,0,~
0,0,0,0,0,0,0,0,0,0,0,0,0)';
      PINUSE='POWER';
      NO_LOAD_CHECK='Both';
      NO_IO_CHECK='Both';
      NO_ASSERT_CHECK='TRUE';
      NO_DIR_CHECK='TRUE';
      ALLOW_CONNECT='TRUE';
    'VCCIN52':
      PIN_NUMBER='(0,0,0,0,0,0,0,0,0,0,0,0,0,0,0,0,0,0,0,0,0,0,0,0,0,0,BN84,0,0,~
0,0,0,0,0,0,0,0,0,0,0,0,0)';
      PINUSE='POWER';
      NO_LOAD_CHECK='Both';
      NO_IO_CHECK='Both';
      NO_ASSERT_CHECK='TRUE';
      NO_DIR_CHECK='TRUE';
      ALLOW_CONNECT='TRUE';
    'VCCIN51':
      PIN_NUMBER='(0,0,0,0,0,0,0,0,0,0,0,0,0,0,0,0,0,0,0,0,0,0,0,0,0,0,BN82,0,0,~
0,0,0,0,0,0,0,0,0,0,0,0,0)';
      PINUSE='POWER';
      NO_LOAD_CHECK='Both';
      NO_IO_CHECK='Both';
      NO_ASSERT_CHECK='TRUE';
      NO_DIR_CHECK='TRUE';
      ALLOW_CONNECT='TRUE';
    'VCCIN50':
      PIN_NUMBER='(0,0,0,0,0,0,0,0,0,0,0,0,0,0,0,0,0,0,0,0,0,0,0,0,0,0,BN80,0,0,~
0,0,0,0,0,0,0,0,0,0,0,0,0)';
      PINUSE='POWER';
      NO_LOAD_CHECK='Both';
      NO_IO_CHECK='Both';
      NO_ASSERT_CHECK='TRUE';
      NO_DIR_CHECK='TRUE';
      ALLOW_CONNECT='TRUE';
    'VCCIN49':
      PIN_NUMBER='(0,0,0,0,0,0,0,0,0,0,0,0,0,0,0,0,0,0,0,0,0,0,0,0,0,0,BN78,0,0,~
0,0,0,0,0,0,0,0,0,0,0,0,0)';
      PINUSE='POWER';
      NO_LOAD_CHECK='Both';
      NO_IO_CHECK='Both';
      NO_ASSERT_CHECK='TRUE';
      NO_DIR_CHECK='TRUE';
      ALLOW_CONNECT='TRUE';
    'VCCIN48':
      PIN_NUMBER='(0,0,0,0,0,0,0,0,0,0,0,0,0,0,0,0,0,0,0,0,0,0,0,0,0,0,BN60,0,0,~
0,0,0,0,0,0,0,0,0,0,0,0,0)';
      PINUSE='POWER';
      NO_LOAD_CHECK='Both';
      NO_IO_CHECK='Both';
      NO_ASSERT_CHECK='TRUE';
      NO_DIR_CHECK='TRUE';
      ALLOW_CONNECT='TRUE';
    'VCCIN47':
      PIN_NUMBER='(0,0,0,0,0,0,0,0,0,0,0,0,0,0,0,0,0,0,0,0,0,0,0,0,0,0,BN58,0,0,~
0,0,0,0,0,0,0,0,0,0,0,0,0)';
      PINUSE='POWER';
      NO_LOAD_CHECK='Both';
      NO_IO_CHECK='Both';
      NO_ASSERT_CHECK='TRUE';
      NO_DIR_CHECK='TRUE';
      ALLOW_CONNECT='TRUE';
    'VCCIN46':
      PIN_NUMBER='(0,0,0,0,0,0,0,0,0,0,0,0,0,0,0,0,0,0,0,0,0,0,0,0,0,0,BN56,0,0,~
0,0,0,0,0,0,0,0,0,0,0,0,0)';
      PINUSE='POWER';
      NO_LOAD_CHECK='Both';
      NO_IO_CHECK='Both';
      NO_ASSERT_CHECK='TRUE';
      NO_DIR_CHECK='TRUE';
      ALLOW_CONNECT='TRUE';
    'VCCIN45':
      PIN_NUMBER='(0,0,0,0,0,0,0,0,0,0,0,0,0,0,0,0,0,0,0,0,0,0,0,0,0,0,BN54,0,0,~
0,0,0,0,0,0,0,0,0,0,0,0,0)';
      PINUSE='POWER';
      NO_LOAD_CHECK='Both';
      NO_IO_CHECK='Both';
      NO_ASSERT_CHECK='TRUE';
      NO_DIR_CHECK='TRUE';
      ALLOW_CONNECT='TRUE';
    'VCCIN44':
      PIN_NUMBER='(0,0,0,0,0,0,0,0,0,0,0,0,0,0,0,0,0,0,0,0,0,0,0,0,0,0,BN52,0,0,~
0,0,0,0,0,0,0,0,0,0,0,0,0)';
      PINUSE='POWER';
      NO_LOAD_CHECK='Both';
      NO_IO_CHECK='Both';
      NO_ASSERT_CHECK='TRUE';
      NO_DIR_CHECK='TRUE';
      ALLOW_CONNECT='TRUE';
    'VCCIN43':
      PIN_NUMBER='(0,0,0,0,0,0,0,0,0,0,0,0,0,0,0,0,0,0,0,0,0,0,0,0,0,0,BN50,0,0,~
0,0,0,0,0,0,0,0,0,0,0,0,0)';
      PINUSE='POWER';
      NO_LOAD_CHECK='Both';
      NO_IO_CHECK='Both';
      NO_ASSERT_CHECK='TRUE';
      NO_DIR_CHECK='TRUE';
      ALLOW_CONNECT='TRUE';
    'VCCIN42':
      PIN_NUMBER='(0,0,0,0,0,0,0,0,0,0,0,0,0,0,0,0,0,0,0,0,0,0,0,0,0,0,BN48,0,0,~
0,0,0,0,0,0,0,0,0,0,0,0,0)';
      PINUSE='POWER';
      NO_LOAD_CHECK='Both';
      NO_IO_CHECK='Both';
      NO_ASSERT_CHECK='TRUE';
      NO_DIR_CHECK='TRUE';
      ALLOW_CONNECT='TRUE';
    'VCCIN41':
      PIN_NUMBER='(0,0,0,0,0,0,0,0,0,0,0,0,0,0,0,0,0,0,0,0,0,0,0,0,0,0,BN45,0,0,~
0,0,0,0,0,0,0,0,0,0,0,0,0)';
      PINUSE='POWER';
      NO_LOAD_CHECK='Both';
      NO_IO_CHECK='Both';
      NO_ASSERT_CHECK='TRUE';
      NO_DIR_CHECK='TRUE';
      ALLOW_CONNECT='TRUE';
    'VCCIN40':
      PIN_NUMBER='(0,0,0,0,0,0,0,0,0,0,0,0,0,0,0,0,0,0,0,0,0,0,0,0,0,0,BN43,0,0,~
0,0,0,0,0,0,0,0,0,0,0,0,0)';
      PINUSE='POWER';
      NO_LOAD_CHECK='Both';
      NO_IO_CHECK='Both';
      NO_ASSERT_CHECK='TRUE';
      NO_DIR_CHECK='TRUE';
      ALLOW_CONNECT='TRUE';
    'VCCIN39':
      PIN_NUMBER='(0,0,0,0,0,0,0,0,0,0,0,0,0,0,0,0,0,0,0,0,0,0,0,0,0,0,0,BN41,0,~
0,0,0,0,0,0,0,0,0,0,0,0,0)';
      PINUSE='POWER';
      NO_LOAD_CHECK='Both';
      NO_IO_CHECK='Both';
      NO_ASSERT_CHECK='TRUE';
      NO_DIR_CHECK='TRUE';
      ALLOW_CONNECT='TRUE';
    'VCCIN38':
      PIN_NUMBER='(0,0,0,0,0,0,0,0,0,0,0,0,0,0,0,0,0,0,0,0,0,0,0,0,0,0,0,BN39,0,~
0,0,0,0,0,0,0,0,0,0,0,0,0)';
      PINUSE='POWER';
      NO_LOAD_CHECK='Both';
      NO_IO_CHECK='Both';
      NO_ASSERT_CHECK='TRUE';
      NO_DIR_CHECK='TRUE';
      ALLOW_CONNECT='TRUE';
    'VCCIN37':
      PIN_NUMBER='(0,0,0,0,0,0,0,0,0,0,0,0,0,0,0,0,0,0,0,0,0,0,0,0,0,0,0,BN37,0,~
0,0,0,0,0,0,0,0,0,0,0,0,0)';
      PINUSE='POWER';
      NO_LOAD_CHECK='Both';
      NO_IO_CHECK='Both';
      NO_ASSERT_CHECK='TRUE';
      NO_DIR_CHECK='TRUE';
      ALLOW_CONNECT='TRUE';
    'VCCIN36':
      PIN_NUMBER='(0,0,0,0,0,0,0,0,0,0,0,0,0,0,0,0,0,0,0,0,0,0,0,0,0,0,0,BN35,0,~
0,0,0,0,0,0,0,0,0,0,0,0,0)';
      PINUSE='POWER';
      NO_LOAD_CHECK='Both';
      NO_IO_CHECK='Both';
      NO_ASSERT_CHECK='TRUE';
      NO_DIR_CHECK='TRUE';
      ALLOW_CONNECT='TRUE';
    'VCCIN35':
      PIN_NUMBER='(0,0,0,0,0,0,0,0,0,0,0,0,0,0,0,0,0,0,0,0,0,0,0,0,0,0,0,BN33,0,~
0,0,0,0,0,0,0,0,0,0,0,0,0)';
      PINUSE='POWER';
      NO_LOAD_CHECK='Both';
      NO_IO_CHECK='Both';
      NO_ASSERT_CHECK='TRUE';
      NO_DIR_CHECK='TRUE';
      ALLOW_CONNECT='TRUE';
    'VCCIN34':
      PIN_NUMBER='(0,0,0,0,0,0,0,0,0,0,0,0,0,0,0,0,0,0,0,0,0,0,0,0,0,0,0,BM91,0,~
0,0,0,0,0,0,0,0,0,0,0,0,0)';
      PINUSE='POWER';
      NO_LOAD_CHECK='Both';
      NO_IO_CHECK='Both';
      NO_ASSERT_CHECK='TRUE';
      NO_DIR_CHECK='TRUE';
      ALLOW_CONNECT='TRUE';
    'VCCIN33':
      PIN_NUMBER='(0,0,0,0,0,0,0,0,0,0,0,0,0,0,0,0,0,0,0,0,0,0,0,0,0,0,0,BM89,0,~
0,0,0,0,0,0,0,0,0,0,0,0,0)';
      PINUSE='POWER';
      NO_LOAD_CHECK='Both';
      NO_IO_CHECK='Both';
      NO_ASSERT_CHECK='TRUE';
      NO_DIR_CHECK='TRUE';
      ALLOW_CONNECT='TRUE';
    'VCCIN32':
      PIN_NUMBER='(0,0,0,0,0,0,0,0,0,0,0,0,0,0,0,0,0,0,0,0,0,0,0,0,0,0,0,BM87,0,~
0,0,0,0,0,0,0,0,0,0,0,0,0)';
      PINUSE='POWER';
      NO_LOAD_CHECK='Both';
      NO_IO_CHECK='Both';
      NO_ASSERT_CHECK='TRUE';
      NO_DIR_CHECK='TRUE';
      ALLOW_CONNECT='TRUE';
    'VCCIN31':
      PIN_NUMBER='(0,0,0,0,0,0,0,0,0,0,0,0,0,0,0,0,0,0,0,0,0,0,0,0,0,0,0,BM85,0,~
0,0,0,0,0,0,0,0,0,0,0,0,0)';
      PINUSE='POWER';
      NO_LOAD_CHECK='Both';
      NO_IO_CHECK='Both';
      NO_ASSERT_CHECK='TRUE';
      NO_DIR_CHECK='TRUE';
      ALLOW_CONNECT='TRUE';
    'VCCIN30':
      PIN_NUMBER='(0,0,0,0,0,0,0,0,0,0,0,0,0,0,0,0,0,0,0,0,0,0,0,0,0,0,0,BM83,0,~
0,0,0,0,0,0,0,0,0,0,0,0,0)';
      PINUSE='POWER';
      NO_LOAD_CHECK='Both';
      NO_IO_CHECK='Both';
      NO_ASSERT_CHECK='TRUE';
      NO_DIR_CHECK='TRUE';
      ALLOW_CONNECT='TRUE';
    'VCCIN29':
      PIN_NUMBER='(0,0,0,0,0,0,0,0,0,0,0,0,0,0,0,0,0,0,0,0,0,0,0,0,0,0,0,BM81,0,~
0,0,0,0,0,0,0,0,0,0,0,0,0)';
      PINUSE='POWER';
      NO_LOAD_CHECK='Both';
      NO_IO_CHECK='Both';
      NO_ASSERT_CHECK='TRUE';
      NO_DIR_CHECK='TRUE';
      ALLOW_CONNECT='TRUE';
    'VCCIN28':
      PIN_NUMBER='(0,0,0,0,0,0,0,0,0,0,0,0,0,0,0,0,0,0,0,0,0,0,0,0,0,0,0,BM79,0,~
0,0,0,0,0,0,0,0,0,0,0,0,0)';
      PINUSE='POWER';
      NO_LOAD_CHECK='Both';
      NO_IO_CHECK='Both';
      NO_ASSERT_CHECK='TRUE';
      NO_DIR_CHECK='TRUE';
      ALLOW_CONNECT='TRUE';
    'VCCIN27':
      PIN_NUMBER='(0,0,0,0,0,0,0,0,0,0,0,0,0,0,0,0,0,0,0,0,0,0,0,0,0,0,0,BL90,0,~
0,0,0,0,0,0,0,0,0,0,0,0,0)';
      PINUSE='POWER';
      NO_LOAD_CHECK='Both';
      NO_IO_CHECK='Both';
      NO_ASSERT_CHECK='TRUE';
      NO_DIR_CHECK='TRUE';
      ALLOW_CONNECT='TRUE';
    'VCCIN26':
      PIN_NUMBER='(0,0,0,0,0,0,0,0,0,0,0,0,0,0,0,0,0,0,0,0,0,0,0,0,0,0,0,BL88,0,~
0,0,0,0,0,0,0,0,0,0,0,0,0)';
      PINUSE='POWER';
      NO_LOAD_CHECK='Both';
      NO_IO_CHECK='Both';
      NO_ASSERT_CHECK='TRUE';
      NO_DIR_CHECK='TRUE';
      ALLOW_CONNECT='TRUE';
    'VCCIN25':
      PIN_NUMBER='(0,0,0,0,0,0,0,0,0,0,0,0,0,0,0,0,0,0,0,0,0,0,0,0,0,0,0,BL86,0,~
0,0,0,0,0,0,0,0,0,0,0,0,0)';
      PINUSE='POWER';
      NO_LOAD_CHECK='Both';
      NO_IO_CHECK='Both';
      NO_ASSERT_CHECK='TRUE';
      NO_DIR_CHECK='TRUE';
      ALLOW_CONNECT='TRUE';
    'VCCIN24':
      PIN_NUMBER='(0,0,0,0,0,0,0,0,0,0,0,0,0,0,0,0,0,0,0,0,0,0,0,0,0,0,0,BL84,0,~
0,0,0,0,0,0,0,0,0,0,0,0,0)';
      PINUSE='POWER';
      NO_LOAD_CHECK='Both';
      NO_IO_CHECK='Both';
      NO_ASSERT_CHECK='TRUE';
      NO_DIR_CHECK='TRUE';
      ALLOW_CONNECT='TRUE';
    'VCCIN23':
      PIN_NUMBER='(0,0,0,0,0,0,0,0,0,0,0,0,0,0,0,0,0,0,0,0,0,0,0,0,0,0,0,BL82,0,~
0,0,0,0,0,0,0,0,0,0,0,0,0)';
      PINUSE='POWER';
      NO_LOAD_CHECK='Both';
      NO_IO_CHECK='Both';
      NO_ASSERT_CHECK='TRUE';
      NO_DIR_CHECK='TRUE';
      ALLOW_CONNECT='TRUE';
    'VCCIN22':
      PIN_NUMBER='(0,0,0,0,0,0,0,0,0,0,0,0,0,0,0,0,0,0,0,0,0,0,0,0,0,0,0,BL80,0,~
0,0,0,0,0,0,0,0,0,0,0,0,0)';
      PINUSE='POWER';
      NO_LOAD_CHECK='Both';
      NO_IO_CHECK='Both';
      NO_ASSERT_CHECK='TRUE';
      NO_DIR_CHECK='TRUE';
      ALLOW_CONNECT='TRUE';
    'VCCIN21':
      PIN_NUMBER='(0,0,0,0,0,0,0,0,0,0,0,0,0,0,0,0,0,0,0,0,0,0,0,0,0,0,0,BK91,0,~
0,0,0,0,0,0,0,0,0,0,0,0,0)';
      PINUSE='POWER';
      NO_LOAD_CHECK='Both';
      NO_IO_CHECK='Both';
      NO_ASSERT_CHECK='TRUE';
      NO_DIR_CHECK='TRUE';
      ALLOW_CONNECT='TRUE';
    'VCCIN20':
      PIN_NUMBER='(0,0,0,0,0,0,0,0,0,0,0,0,0,0,0,0,0,0,0,0,0,0,0,0,0,0,0,BK89,0,~
0,0,0,0,0,0,0,0,0,0,0,0,0)';
      PINUSE='POWER';
      NO_LOAD_CHECK='Both';
      NO_IO_CHECK='Both';
      NO_ASSERT_CHECK='TRUE';
      NO_DIR_CHECK='TRUE';
      ALLOW_CONNECT='TRUE';
    'VCCIN19':
      PIN_NUMBER='(0,0,0,0,0,0,0,0,0,0,0,0,0,0,0,0,0,0,0,0,0,0,0,0,0,0,0,BK87,0,~
0,0,0,0,0,0,0,0,0,0,0,0,0)';
      PINUSE='POWER';
      NO_LOAD_CHECK='Both';
      NO_IO_CHECK='Both';
      NO_ASSERT_CHECK='TRUE';
      NO_DIR_CHECK='TRUE';
      ALLOW_CONNECT='TRUE';
    'VCCIN18':
      PIN_NUMBER='(0,0,0,0,0,0,0,0,0,0,0,0,0,0,0,0,0,0,0,0,0,0,0,0,0,0,0,BK85,0,~
0,0,0,0,0,0,0,0,0,0,0,0,0)';
      PINUSE='POWER';
      NO_LOAD_CHECK='Both';
      NO_IO_CHECK='Both';
      NO_ASSERT_CHECK='TRUE';
      NO_DIR_CHECK='TRUE';
      ALLOW_CONNECT='TRUE';
    'VCCIN17':
      PIN_NUMBER='(0,0,0,0,0,0,0,0,0,0,0,0,0,0,0,0,0,0,0,0,0,0,0,0,0,0,0,BK83,0,~
0,0,0,0,0,0,0,0,0,0,0,0,0)';
      PINUSE='POWER';
      NO_LOAD_CHECK='Both';
      NO_IO_CHECK='Both';
      NO_ASSERT_CHECK='TRUE';
      NO_DIR_CHECK='TRUE';
      ALLOW_CONNECT='TRUE';
    'VCCIN16':
      PIN_NUMBER='(0,0,0,0,0,0,0,0,0,0,0,0,0,0,0,0,0,0,0,0,0,0,0,0,0,0,0,BK81,0,~
0,0,0,0,0,0,0,0,0,0,0,0,0)';
      PINUSE='POWER';
      NO_LOAD_CHECK='Both';
      NO_IO_CHECK='Both';
      NO_ASSERT_CHECK='TRUE';
      NO_DIR_CHECK='TRUE';
      ALLOW_CONNECT='TRUE';
    'VCCIN15':
      PIN_NUMBER='(0,0,0,0,0,0,0,0,0,0,0,0,0,0,0,0,0,0,0,0,0,0,0,0,0,0,0,BH91,0,~
0,0,0,0,0,0,0,0,0,0,0,0,0)';
      PINUSE='POWER';
      NO_LOAD_CHECK='Both';
      NO_IO_CHECK='Both';
      NO_ASSERT_CHECK='TRUE';
      NO_DIR_CHECK='TRUE';
      ALLOW_CONNECT='TRUE';
    'VCCIN14':
      PIN_NUMBER='(0,0,0,0,0,0,0,0,0,0,0,0,0,0,0,0,0,0,0,0,0,0,0,0,0,0,0,BH89,0,~
0,0,0,0,0,0,0,0,0,0,0,0,0)';
      PINUSE='POWER';
      NO_LOAD_CHECK='Both';
      NO_IO_CHECK='Both';
      NO_ASSERT_CHECK='TRUE';
      NO_DIR_CHECK='TRUE';
      ALLOW_CONNECT='TRUE';
    'VCCIN13':
      PIN_NUMBER='(0,0,0,0,0,0,0,0,0,0,0,0,0,0,0,0,0,0,0,0,0,0,0,0,0,0,0,BH87,0,~
0,0,0,0,0,0,0,0,0,0,0,0,0)';
      PINUSE='POWER';
      NO_LOAD_CHECK='Both';
      NO_IO_CHECK='Both';
      NO_ASSERT_CHECK='TRUE';
      NO_DIR_CHECK='TRUE';
      ALLOW_CONNECT='TRUE';
    'VCCIN12':
      PIN_NUMBER='(0,0,0,0,0,0,0,0,0,0,0,0,0,0,0,0,0,0,0,0,0,0,0,0,0,0,0,BH85,0,~
0,0,0,0,0,0,0,0,0,0,0,0,0)';
      PINUSE='POWER';
      NO_LOAD_CHECK='Both';
      NO_IO_CHECK='Both';
      NO_ASSERT_CHECK='TRUE';
      NO_DIR_CHECK='TRUE';
      ALLOW_CONNECT='TRUE';
    'VCCIN11':
      PIN_NUMBER='(0,0,0,0,0,0,0,0,0,0,0,0,0,0,0,0,0,0,0,0,0,0,0,0,0,0,0,BG90,0,~
0,0,0,0,0,0,0,0,0,0,0,0,0)';
      PINUSE='POWER';
      NO_LOAD_CHECK='Both';
      NO_IO_CHECK='Both';
      NO_ASSERT_CHECK='TRUE';
      NO_DIR_CHECK='TRUE';
      ALLOW_CONNECT='TRUE';
    'VCCIN10':
      PIN_NUMBER='(0,0,0,0,0,0,0,0,0,0,0,0,0,0,0,0,0,0,0,0,0,0,0,0,0,0,0,BG88,0,~
0,0,0,0,0,0,0,0,0,0,0,0,0)';
      PINUSE='POWER';
      NO_LOAD_CHECK='Both';
      NO_IO_CHECK='Both';
      NO_ASSERT_CHECK='TRUE';
      NO_DIR_CHECK='TRUE';
      ALLOW_CONNECT='TRUE';
    'VCCIN9':
      PIN_NUMBER='(0,0,0,0,0,0,0,0,0,0,0,0,0,0,0,0,0,0,0,0,0,0,0,0,0,0,0,BG86,0,~
0,0,0,0,0,0,0,0,0,0,0,0,0)';
      PINUSE='POWER';
      NO_LOAD_CHECK='Both';
      NO_IO_CHECK='Both';
      NO_ASSERT_CHECK='TRUE';
      NO_DIR_CHECK='TRUE';
      ALLOW_CONNECT='TRUE';
    'VCCIN8':
      PIN_NUMBER='(0,0,0,0,0,0,0,0,0,0,0,0,0,0,0,0,0,0,0,0,0,0,0,0,0,0,0,BG84,0,~
0,0,0,0,0,0,0,0,0,0,0,0,0)';
      PINUSE='POWER';
      NO_LOAD_CHECK='Both';
      NO_IO_CHECK='Both';
      NO_ASSERT_CHECK='TRUE';
      NO_DIR_CHECK='TRUE';
      ALLOW_CONNECT='TRUE';
    'VCCIN7':
      PIN_NUMBER='(0,0,0,0,0,0,0,0,0,0,0,0,0,0,0,0,0,0,0,0,0,0,0,0,0,0,0,BF91,0,~
0,0,0,0,0,0,0,0,0,0,0,0,0)';
      PINUSE='POWER';
      NO_LOAD_CHECK='Both';
      NO_IO_CHECK='Both';
      NO_ASSERT_CHECK='TRUE';
      NO_DIR_CHECK='TRUE';
      ALLOW_CONNECT='TRUE';
    'VCCIN6':
      PIN_NUMBER='(0,0,0,0,0,0,0,0,0,0,0,0,0,0,0,0,0,0,0,0,0,0,0,0,0,0,0,BF89,0,~
0,0,0,0,0,0,0,0,0,0,0,0,0)';
      PINUSE='POWER';
      NO_LOAD_CHECK='Both';
      NO_IO_CHECK='Both';
      NO_ASSERT_CHECK='TRUE';
      NO_DIR_CHECK='TRUE';
      ALLOW_CONNECT='TRUE';
    'VCCIN5':
      PIN_NUMBER='(0,0,0,0,0,0,0,0,0,0,0,0,0,0,0,0,0,0,0,0,0,0,0,0,0,0,0,BF87,0,~
0,0,0,0,0,0,0,0,0,0,0,0,0)';
      PINUSE='POWER';
      NO_LOAD_CHECK='Both';
      NO_IO_CHECK='Both';
      NO_ASSERT_CHECK='TRUE';
      NO_DIR_CHECK='TRUE';
      ALLOW_CONNECT='TRUE';
    'VCCIN4':
      PIN_NUMBER='(0,0,0,0,0,0,0,0,0,0,0,0,0,0,0,0,0,0,0,0,0,0,0,0,0,0,0,BF85,0,~
0,0,0,0,0,0,0,0,0,0,0,0,0)';
      PINUSE='POWER';
      NO_LOAD_CHECK='Both';
      NO_IO_CHECK='Both';
      NO_ASSERT_CHECK='TRUE';
      NO_DIR_CHECK='TRUE';
      ALLOW_CONNECT='TRUE';
    'VCCIN3':
      PIN_NUMBER='(0,0,0,0,0,0,0,0,0,0,0,0,0,0,0,0,0,0,0,0,0,0,0,0,0,0,0,BE90,0,~
0,0,0,0,0,0,0,0,0,0,0,0,0)';
      PINUSE='POWER';
      NO_LOAD_CHECK='Both';
      NO_IO_CHECK='Both';
      NO_ASSERT_CHECK='TRUE';
      NO_DIR_CHECK='TRUE';
      ALLOW_CONNECT='TRUE';
    'VCCIN2':
      PIN_NUMBER='(0,0,0,0,0,0,0,0,0,0,0,0,0,0,0,0,0,0,0,0,0,0,0,0,0,0,0,BE88,0,~
0,0,0,0,0,0,0,0,0,0,0,0,0)';
      PINUSE='POWER';
      NO_LOAD_CHECK='Both';
      NO_IO_CHECK='Both';
      NO_ASSERT_CHECK='TRUE';
      NO_DIR_CHECK='TRUE';
      ALLOW_CONNECT='TRUE';
    'VCCIN1':
      PIN_NUMBER='(0,0,0,0,0,0,0,0,0,0,0,0,0,0,0,0,0,0,0,0,0,0,0,0,0,0,0,BE86,0,~
0,0,0,0,0,0,0,0,0,0,0,0,0)';
      PINUSE='POWER';
      NO_LOAD_CHECK='Both';
      NO_IO_CHECK='Both';
      NO_ASSERT_CHECK='TRUE';
      NO_DIR_CHECK='TRUE';
      ALLOW_CONNECT='TRUE';
    'VCCIN0':
      PIN_NUMBER='(0,0,0,0,0,0,0,0,0,0,0,0,0,0,0,0,0,0,0,0,0,0,0,0,0,0,0,BD91,0,~
0,0,0,0,0,0,0,0,0,0,0,0,0)';
      PINUSE='POWER';
      NO_LOAD_CHECK='Both';
      NO_IO_CHECK='Both';
      NO_ASSERT_CHECK='TRUE';
      NO_DIR_CHECK='TRUE';
      ALLOW_CONNECT='TRUE';
    'VCCINFAON53':
      PIN_NUMBER='(0,0,0,0,0,0,0,0,0,0,0,0,0,0,0,0,0,0,0,0,0,0,0,0,0,0,0,DA21,0,~
0,0,0,0,0,0,0,0,0,0,0,0,0)';
      PINUSE='POWER';
      NO_LOAD_CHECK='Both';
      NO_IO_CHECK='Both';
      NO_ASSERT_CHECK='TRUE';
      NO_DIR_CHECK='TRUE';
      ALLOW_CONNECT='TRUE';
    'VCCINFAON52':
      PIN_NUMBER='(0,0,0,0,0,0,0,0,0,0,0,0,0,0,0,0,0,0,0,0,0,0,0,0,0,0,0,CW62,0,~
0,0,0,0,0,0,0,0,0,0,0,0,0)';
      PINUSE='POWER';
      NO_LOAD_CHECK='Both';
      NO_IO_CHECK='Both';
      NO_ASSERT_CHECK='TRUE';
      NO_DIR_CHECK='TRUE';
      ALLOW_CONNECT='TRUE';
    'VCCINFAON51':
      PIN_NUMBER='(0,0,0,0,0,0,0,0,0,0,0,0,0,0,0,0,0,0,0,0,0,0,0,0,0,0,0,CV63,0,~
0,0,0,0,0,0,0,0,0,0,0,0,0)';
      PINUSE='POWER';
      NO_LOAD_CHECK='Both';
      NO_IO_CHECK='Both';
      NO_ASSERT_CHECK='TRUE';
      NO_DIR_CHECK='TRUE';
      ALLOW_CONNECT='TRUE';
    'VCCINFAON50':
      PIN_NUMBER='(0,0,0,0,0,0,0,0,0,0,0,0,0,0,0,0,0,0,0,0,0,0,0,0,0,0,0,CV61,0,~
0,0,0,0,0,0,0,0,0,0,0,0,0)';
      PINUSE='POWER';
      NO_LOAD_CHECK='Both';
      NO_IO_CHECK='Both';
      NO_ASSERT_CHECK='TRUE';
      NO_DIR_CHECK='TRUE';
      ALLOW_CONNECT='TRUE';
    'VCCINFAON49':
      PIN_NUMBER='(0,0,0,0,0,0,0,0,0,0,0,0,0,0,0,0,0,0,0,0,0,0,0,0,0,0,0,CT63,0,~
0,0,0,0,0,0,0,0,0,0,0,0,0)';
      PINUSE='POWER';
      NO_LOAD_CHECK='Both';
      NO_IO_CHECK='Both';
      NO_ASSERT_CHECK='TRUE';
      NO_DIR_CHECK='TRUE';
      ALLOW_CONNECT='TRUE';
    'VCCINFAON48':
      PIN_NUMBER='(0,0,0,0,0,0,0,0,0,0,0,0,0,0,0,0,0,0,0,0,0,0,0,0,0,0,0,CP63,0,~
0,0,0,0,0,0,0,0,0,0,0,0,0)';
      PINUSE='POWER';
      NO_LOAD_CHECK='Both';
      NO_IO_CHECK='Both';
      NO_ASSERT_CHECK='TRUE';
      NO_DIR_CHECK='TRUE';
      ALLOW_CONNECT='TRUE';
    'VCCINFAON47':
      PIN_NUMBER='(0,0,0,0,0,0,0,0,0,0,0,0,0,0,0,0,0,0,0,0,0,0,0,0,0,0,0,CN19,0,~
0,0,0,0,0,0,0,0,0,0,0,0,0)';
      PINUSE='POWER';
      NO_LOAD_CHECK='Both';
      NO_IO_CHECK='Both';
      NO_ASSERT_CHECK='TRUE';
      NO_DIR_CHECK='TRUE';
      ALLOW_CONNECT='TRUE';
    'VCCINFAON46':
      PIN_NUMBER='(0,0,0,0,0,0,0,0,0,0,0,0,0,0,0,0,0,0,0,0,0,0,0,0,0,0,0,CJ19,0,~
0,0,0,0,0,0,0,0,0,0,0,0,0)';
      PINUSE='POWER';
      NO_LOAD_CHECK='Both';
      NO_IO_CHECK='Both';
      NO_ASSERT_CHECK='TRUE';
      NO_DIR_CHECK='TRUE';
      ALLOW_CONNECT='TRUE';
    'VCCINFAON45':
      PIN_NUMBER='(0,0,0,0,0,0,0,0,0,0,0,0,0,0,0,0,0,0,0,0,0,0,0,0,0,0,0,CJ11,0,~
0,0,0,0,0,0,0,0,0,0,0,0,0)';
      PINUSE='POWER';
      NO_LOAD_CHECK='Both';
      NO_IO_CHECK='Both';
      NO_ASSERT_CHECK='TRUE';
      NO_DIR_CHECK='TRUE';
      ALLOW_CONNECT='TRUE';
    'VCCINFAON44':
      PIN_NUMBER='(0,0,0,0,0,0,0,0,0,0,0,0,0,0,0,0,0,0,0,0,0,0,0,0,0,0,0,CE19,0,~
0,0,0,0,0,0,0,0,0,0,0,0,0)';
      PINUSE='POWER';
      NO_LOAD_CHECK='Both';
      NO_IO_CHECK='Both';
      NO_ASSERT_CHECK='TRUE';
      NO_DIR_CHECK='TRUE';
      ALLOW_CONNECT='TRUE';
    'VCCINFAON43':
      PIN_NUMBER='(0,0,0,0,0,0,0,0,0,0,0,0,0,0,0,0,0,0,0,0,0,0,0,0,0,0,0,CA15,0,~
0,0,0,0,0,0,0,0,0,0,0,0,0)';
      PINUSE='POWER';
      NO_LOAD_CHECK='Both';
      NO_IO_CHECK='Both';
      NO_ASSERT_CHECK='TRUE';
      NO_DIR_CHECK='TRUE';
      ALLOW_CONNECT='TRUE';
    'VCCINFAON42':
      PIN_NUMBER='(0,0,0,0,0,0,0,0,0,0,0,0,0,0,0,0,0,0,0,0,0,0,0,0,0,0,0,BN15,0,~
0,0,0,0,0,0,0,0,0,0,0,0,0)';
      PINUSE='POWER';
      NO_LOAD_CHECK='Both';
      NO_IO_CHECK='Both';
      NO_ASSERT_CHECK='TRUE';
      NO_DIR_CHECK='TRUE';
      ALLOW_CONNECT='TRUE';
    'VCCINFAON41':
      PIN_NUMBER='(0,0,0,0,0,0,0,0,0,0,0,0,0,0,0,0,0,0,0,0,0,0,0,0,0,0,0,BK61,0,~
0,0,0,0,0,0,0,0,0,0,0,0,0)';
      PINUSE='POWER';
      NO_LOAD_CHECK='Both';
      NO_IO_CHECK='Both';
      NO_ASSERT_CHECK='TRUE';
      NO_DIR_CHECK='TRUE';
      ALLOW_CONNECT='TRUE';
    'VCCINFAON40':
      PIN_NUMBER='(0,0,0,0,0,0,0,0,0,0,0,0,0,0,0,0,0,0,0,0,0,0,0,0,0,0,0,BJ60,0,~
0,0,0,0,0,0,0,0,0,0,0,0,0)';
      PINUSE='POWER';
      NO_LOAD_CHECK='Both';
      NO_IO_CHECK='Both';
      NO_ASSERT_CHECK='TRUE';
      NO_DIR_CHECK='TRUE';
      ALLOW_CONNECT='TRUE';
    'VCCINFAON39':
      PIN_NUMBER='(0,0,0,0,0,0,0,0,0,0,0,0,0,0,0,0,0,0,0,0,0,0,0,0,0,0,0,BJ15,0,~
0,0,0,0,0,0,0,0,0,0,0,0,0)';
      PINUSE='POWER';
      NO_LOAD_CHECK='Both';
      NO_IO_CHECK='Both';
      NO_ASSERT_CHECK='TRUE';
      NO_DIR_CHECK='TRUE';
      ALLOW_CONNECT='TRUE';
    'VCCINFAON38':
      PIN_NUMBER='(0,0,0,0,0,0,0,0,0,0,0,0,0,0,0,0,0,0,0,0,0,0,0,0,0,0,0,BG60,0,~
0,0,0,0,0,0,0,0,0,0,0,0,0)';
      PINUSE='POWER';
      NO_LOAD_CHECK='Both';
      NO_IO_CHECK='Both';
      NO_ASSERT_CHECK='TRUE';
      NO_DIR_CHECK='TRUE';
      ALLOW_CONNECT='TRUE';
    'VCCINFAON37':
      PIN_NUMBER='(0,0,0,0,0,0,0,0,0,0,0,0,0,0,0,0,0,0,0,0,0,0,0,0,0,0,0,BE60,0,~
0,0,0,0,0,0,0,0,0,0,0,0,0)';
      PINUSE='POWER';
      NO_LOAD_CHECK='Both';
      NO_IO_CHECK='Both';
      NO_ASSERT_CHECK='TRUE';
      NO_DIR_CHECK='TRUE';
      ALLOW_CONNECT='TRUE';
    'VCCINFAON36':
      PIN_NUMBER='(0,0,0,0,0,0,0,0,0,0,0,0,0,0,0,0,0,0,0,0,0,0,0,0,0,0,0,BE15,0,~
0,0,0,0,0,0,0,0,0,0,0,0,0)';
      PINUSE='POWER';
      NO_LOAD_CHECK='Both';
      NO_IO_CHECK='Both';
      NO_ASSERT_CHECK='TRUE';
      NO_DIR_CHECK='TRUE';
      ALLOW_CONNECT='TRUE';
    'VCCINFAON35':
      PIN_NUMBER='(0,0,0,0,0,0,0,0,0,0,0,0,0,0,0,0,0,0,0,0,0,0,0,0,0,0,0,BC60,0,~
0,0,0,0,0,0,0,0,0,0,0,0,0)';
      PINUSE='POWER';
      NO_LOAD_CHECK='Both';
      NO_IO_CHECK='Both';
      NO_ASSERT_CHECK='TRUE';
      NO_DIR_CHECK='TRUE';
      ALLOW_CONNECT='TRUE';
    'VCCINFAON34':
      PIN_NUMBER='(0,0,0,0,0,0,0,0,0,0,0,0,0,0,0,0,0,0,0,0,0,0,0,0,0,0,0,BA15,0,~
0,0,0,0,0,0,0,0,0,0,0,0,0)';
      PINUSE='POWER';
      NO_LOAD_CHECK='Both';
      NO_IO_CHECK='Both';
      NO_ASSERT_CHECK='TRUE';
      NO_DIR_CHECK='TRUE';
      ALLOW_CONNECT='TRUE';
    'VCCINFAON33':
      PIN_NUMBER='(0,0,0,0,0,0,0,0,0,0,0,0,0,0,0,0,0,0,0,0,0,0,0,0,0,0,0,AY18,0,~
0,0,0,0,0,0,0,0,0,0,0,0,0)';
      PINUSE='POWER';
      NO_LOAD_CHECK='Both';
      NO_IO_CHECK='Both';
      NO_ASSERT_CHECK='TRUE';
      NO_DIR_CHECK='TRUE';
      ALLOW_CONNECT='TRUE';
    'VCC_3P3_AUX0':
      PIN_NUMBER='(0,0,0,0,0,0,0,0,0,0,0,0,0,0,0,0,0,0,0,0,0,0,0,0,0,0,0,0,BC21,~
0,0,0,0,0,0,0,0,0,0,0,0,0)';
      PINUSE='POWER';
      NO_LOAD_CHECK='Both';
      NO_IO_CHECK='Both';
      NO_ASSERT_CHECK='TRUE';
      NO_DIR_CHECK='TRUE';
      ALLOW_CONNECT='TRUE';
    'VCC_3P3_AUX1':
      PIN_NUMBER='(0,0,0,0,0,0,0,0,0,0,0,0,0,0,0,0,0,0,0,0,0,0,0,0,0,0,0,0,BA21,~
0,0,0,0,0,0,0,0,0,0,0,0,0)';
      PINUSE='POWER';
      NO_LOAD_CHECK='Both';
      NO_IO_CHECK='Both';
      NO_ASSERT_CHECK='TRUE';
      NO_DIR_CHECK='TRUE';
      ALLOW_CONNECT='TRUE';
    'VCCD_HV28':
      PIN_NUMBER='(0,0,0,0,0,0,0,0,0,0,0,0,0,0,0,0,0,0,0,0,0,0,0,0,0,0,0,0,CY53,~
0,0,0,0,0,0,0,0,0,0,0,0,0)';
      PINUSE='POWER';
      NO_LOAD_CHECK='Both';
      NO_IO_CHECK='Both';
      NO_ASSERT_CHECK='TRUE';
      NO_DIR_CHECK='TRUE';
      ALLOW_CONNECT='TRUE';
    'VCCD_HV27':
      PIN_NUMBER='(0,0,0,0,0,0,0,0,0,0,0,0,0,0,0,0,0,0,0,0,0,0,0,0,0,0,0,0,CY36,~
0,0,0,0,0,0,0,0,0,0,0,0,0)';
      PINUSE='POWER';
      NO_LOAD_CHECK='Both';
      NO_IO_CHECK='Both';
      NO_ASSERT_CHECK='TRUE';
      NO_DIR_CHECK='TRUE';
      ALLOW_CONNECT='TRUE';
    'VCCD_HV24':
      PIN_NUMBER='(0,0,0,0,0,0,0,0,0,0,0,0,0,0,0,0,0,0,0,0,0,0,0,0,0,0,0,0,CW54,~
0,0,0,0,0,0,0,0,0,0,0,0,0)';
      PINUSE='POWER';
      NO_LOAD_CHECK='Both';
      NO_IO_CHECK='Both';
      NO_ASSERT_CHECK='TRUE';
      NO_DIR_CHECK='TRUE';
      ALLOW_CONNECT='TRUE';
    'VCCD_HV26':
      PIN_NUMBER='(0,0,0,0,0,0,0,0,0,0,0,0,0,0,0,0,0,0,0,0,0,0,0,0,0,0,0,0,CY34,~
0,0,0,0,0,0,0,0,0,0,0,0,0)';
      PINUSE='POWER';
      NO_LOAD_CHECK='Both';
      NO_IO_CHECK='Both';
      NO_ASSERT_CHECK='TRUE';
      NO_DIR_CHECK='TRUE';
      ALLOW_CONNECT='TRUE';
    'VCCD_HV25':
      PIN_NUMBER='(0,0,0,0,0,0,0,0,0,0,0,0,0,0,0,0,0,0,0,0,0,0,0,0,0,0,0,0,CW56,~
0,0,0,0,0,0,0,0,0,0,0,0,0)';
      PINUSE='POWER';
      NO_LOAD_CHECK='Both';
      NO_IO_CHECK='Both';
      NO_ASSERT_CHECK='TRUE';
      NO_DIR_CHECK='TRUE';
      ALLOW_CONNECT='TRUE';
    'VCCD_HV23':
      PIN_NUMBER='(0,0,0,0,0,0,0,0,0,0,0,0,0,0,0,0,0,0,0,0,0,0,0,0,0,0,0,0,CW52,~
0,0,0,0,0,0,0,0,0,0,0,0,0)';
      PINUSE='POWER';
      NO_LOAD_CHECK='Both';
      NO_IO_CHECK='Both';
      NO_ASSERT_CHECK='TRUE';
      NO_DIR_CHECK='TRUE';
      ALLOW_CONNECT='TRUE';
    'VCCD_HV22':
      PIN_NUMBER='(0,0,0,0,0,0,0,0,0,0,0,0,0,0,0,0,0,0,0,0,0,0,0,0,0,0,0,0,CW37,~
0,0,0,0,0,0,0,0,0,0,0,0,0)';
      PINUSE='POWER';
      NO_LOAD_CHECK='Both';
      NO_IO_CHECK='Both';
      NO_ASSERT_CHECK='TRUE';
      NO_DIR_CHECK='TRUE';
      ALLOW_CONNECT='TRUE';
    'VCCD_HV21':
      PIN_NUMBER='(0,0,0,0,0,0,0,0,0,0,0,0,0,0,0,0,0,0,0,0,0,0,0,0,0,0,0,0,CW35,~
0,0,0,0,0,0,0,0,0,0,0,0,0)';
      PINUSE='POWER';
      NO_LOAD_CHECK='Both';
      NO_IO_CHECK='Both';
      NO_ASSERT_CHECK='TRUE';
      NO_DIR_CHECK='TRUE';
      ALLOW_CONNECT='TRUE';
    'VCCD_HV20':
      PIN_NUMBER='(0,0,0,0,0,0,0,0,0,0,0,0,0,0,0,0,0,0,0,0,0,0,0,0,0,0,0,0,CE7,0~
,0,0,0,0,0,0,0,0,0,0,0,0)';
      PINUSE='POWER';
      NO_LOAD_CHECK='Both';
      NO_IO_CHECK='Both';
      NO_ASSERT_CHECK='TRUE';
      NO_DIR_CHECK='TRUE';
      ALLOW_CONNECT='TRUE';
    'VCCD_HV19':
      PIN_NUMBER='(0,0,0,0,0,0,0,0,0,0,0,0,0,0,0,0,0,0,0,0,0,0,0,0,0,0,0,0,CA7,0~
,0,0,0,0,0,0,0,0,0,0,0,0)';
      PINUSE='POWER';
      NO_LOAD_CHECK='Both';
      NO_IO_CHECK='Both';
      NO_ASSERT_CHECK='TRUE';
      NO_DIR_CHECK='TRUE';
      ALLOW_CONNECT='TRUE';
    'VCCD_HV18':
      PIN_NUMBER='(0,0,0,0,0,0,0,0,0,0,0,0,0,0,0,0,0,0,0,0,0,0,0,0,0,0,0,0,BN7,0~
,0,0,0,0,0,0,0,0,0,0,0,0)';
      PINUSE='POWER';
      NO_LOAD_CHECK='Both';
      NO_IO_CHECK='Both';
      NO_ASSERT_CHECK='TRUE';
      NO_DIR_CHECK='TRUE';
      ALLOW_CONNECT='TRUE';
    'VCCD_HV17':
      PIN_NUMBER='(0,0,0,0,0,0,0,0,0,0,0,0,0,0,0,0,0,0,0,0,0,0,0,0,0,0,0,0,BJ7,0~
,0,0,0,0,0,0,0,0,0,0,0,0)';
      PINUSE='POWER';
      NO_LOAD_CHECK='Both';
      NO_IO_CHECK='Both';
      NO_ASSERT_CHECK='TRUE';
      NO_DIR_CHECK='TRUE';
      ALLOW_CONNECT='TRUE';
    'VCCD_HV16':
      PIN_NUMBER='(0,0,0,0,0,0,0,0,0,0,0,0,0,0,0,0,0,0,0,0,0,0,0,0,0,0,0,0,BJ3,0~
,0,0,0,0,0,0,0,0,0,0,0,0)';
      PINUSE='POWER';
      NO_LOAD_CHECK='Both';
      NO_IO_CHECK='Both';
      NO_ASSERT_CHECK='TRUE';
      NO_DIR_CHECK='TRUE';
      ALLOW_CONNECT='TRUE';
    'VCCD_HV15':
      PIN_NUMBER='(0,0,0,0,0,0,0,0,0,0,0,0,0,0,0,0,0,0,0,0,0,0,0,0,0,0,0,0,BJ11,~
0,0,0,0,0,0,0,0,0,0,0,0,0)';
      PINUSE='POWER';
      NO_LOAD_CHECK='Both';
      NO_IO_CHECK='Both';
      NO_ASSERT_CHECK='TRUE';
      NO_DIR_CHECK='TRUE';
      ALLOW_CONNECT='TRUE';
    'VCCD_HV14':
      PIN_NUMBER='(0,0,0,0,0,0,0,0,0,0,0,0,0,0,0,0,0,0,0,0,0,0,0,0,0,0,0,0,BE7,0~
,0,0,0,0,0,0,0,0,0,0,0,0)';
      PINUSE='POWER';
      NO_LOAD_CHECK='Both';
      NO_IO_CHECK='Both';
      NO_ASSERT_CHECK='TRUE';
      NO_DIR_CHECK='TRUE';
      ALLOW_CONNECT='TRUE';
    'VCCD_HV13':
      PIN_NUMBER='(0,0,0,0,0,0,0,0,0,0,0,0,0,0,0,0,0,0,0,0,0,0,0,0,0,0,0,0,BE3,0~
,0,0,0,0,0,0,0,0,0,0,0,0)';
      PINUSE='POWER';
      NO_LOAD_CHECK='Both';
      NO_IO_CHECK='Both';
      NO_ASSERT_CHECK='TRUE';
      NO_DIR_CHECK='TRUE';
      ALLOW_CONNECT='TRUE';
    'VCCD_HV12':
      PIN_NUMBER='(0,0,0,0,0,0,0,0,0,0,0,0,0,0,0,0,0,0,0,0,0,0,0,0,0,0,0,0,BE11,~
0,0,0,0,0,0,0,0,0,0,0,0,0)';
      PINUSE='POWER';
      NO_LOAD_CHECK='Both';
      NO_IO_CHECK='Both';
      NO_ASSERT_CHECK='TRUE';
      NO_DIR_CHECK='TRUE';
      ALLOW_CONNECT='TRUE';
    'VCCD_HV11':
      PIN_NUMBER='(0,0,0,0,0,0,0,0,0,0,0,0,0,0,0,0,0,0,0,0,0,0,0,0,0,0,0,0,BA7,0~
,0,0,0,0,0,0,0,0,0,0,0,0)';
      PINUSE='POWER';
      NO_LOAD_CHECK='Both';
      NO_IO_CHECK='Both';
      NO_ASSERT_CHECK='TRUE';
      NO_DIR_CHECK='TRUE';
      ALLOW_CONNECT='TRUE';
    'VCCD_HV10':
      PIN_NUMBER='(0,0,0,0,0,0,0,0,0,0,0,0,0,0,0,0,0,0,0,0,0,0,0,0,0,0,0,0,BA3,0~
,0,0,0,0,0,0,0,0,0,0,0,0)';
      PINUSE='POWER';
      NO_LOAD_CHECK='Both';
      NO_IO_CHECK='Both';
      NO_ASSERT_CHECK='TRUE';
      NO_DIR_CHECK='TRUE';
      ALLOW_CONNECT='TRUE';
    'VCCD_HV9':
      PIN_NUMBER='(0,0,0,0,0,0,0,0,0,0,0,0,0,0,0,0,0,0,0,0,0,0,0,0,0,0,0,0,AV55,~
0,0,0,0,0,0,0,0,0,0,0,0,0)';
      PINUSE='POWER';
      NO_LOAD_CHECK='Both';
      NO_IO_CHECK='Both';
      NO_ASSERT_CHECK='TRUE';
      NO_DIR_CHECK='TRUE';
      ALLOW_CONNECT='TRUE';
    'VCCD_HV8':
      PIN_NUMBER='(0,0,0,0,0,0,0,0,0,0,0,0,0,0,0,0,0,0,0,0,0,0,0,0,0,0,0,0,AV53,~
0,0,0,0,0,0,0,0,0,0,0,0,0)';
      PINUSE='POWER';
      NO_LOAD_CHECK='Both';
      NO_IO_CHECK='Both';
      NO_ASSERT_CHECK='TRUE';
      NO_DIR_CHECK='TRUE';
      ALLOW_CONNECT='TRUE';
    'VCCD_HV7':
      PIN_NUMBER='(0,0,0,0,0,0,0,0,0,0,0,0,0,0,0,0,0,0,0,0,0,0,0,0,0,0,0,0,AV36,~
0,0,0,0,0,0,0,0,0,0,0,0,0)';
      PINUSE='POWER';
      NO_LOAD_CHECK='Both';
      NO_IO_CHECK='Both';
      NO_ASSERT_CHECK='TRUE';
      NO_DIR_CHECK='TRUE';
      ALLOW_CONNECT='TRUE';
    'VCCD_HV6':
      PIN_NUMBER='(0,0,0,0,0,0,0,0,0,0,0,0,0,0,0,0,0,0,0,0,0,0,0,0,0,0,0,0,AV34,~
0,0,0,0,0,0,0,0,0,0,0,0,0)';
      PINUSE='POWER';
      NO_LOAD_CHECK='Both';
      NO_IO_CHECK='Both';
      NO_ASSERT_CHECK='TRUE';
      NO_DIR_CHECK='TRUE';
      ALLOW_CONNECT='TRUE';
    'VCCD_HV5':
      PIN_NUMBER='(0,0,0,0,0,0,0,0,0,0,0,0,0,0,0,0,0,0,0,0,0,0,0,0,0,0,0,0,AU7,0~
,0,0,0,0,0,0,0,0,0,0,0,0)';
      PINUSE='POWER';
      NO_LOAD_CHECK='Both';
      NO_IO_CHECK='Both';
      NO_ASSERT_CHECK='TRUE';
      NO_DIR_CHECK='TRUE';
      ALLOW_CONNECT='TRUE';
    'VCCD_HV4':
      PIN_NUMBER='(0,0,0,0,0,0,0,0,0,0,0,0,0,0,0,0,0,0,0,0,0,0,0,0,0,0,0,0,AU54,~
0,0,0,0,0,0,0,0,0,0,0,0,0)';
      PINUSE='POWER';
      NO_LOAD_CHECK='Both';
      NO_IO_CHECK='Both';
      NO_ASSERT_CHECK='TRUE';
      NO_DIR_CHECK='TRUE';
      ALLOW_CONNECT='TRUE';
    'VCCD_HV3':
      PIN_NUMBER='(0,0,0,0,0,0,0,0,0,0,0,0,0,0,0,0,0,0,0,0,0,0,0,0,0,0,0,0,AU35,~
0,0,0,0,0,0,0,0,0,0,0,0,0)';
      PINUSE='POWER';
      NO_LOAD_CHECK='Both';
      NO_IO_CHECK='Both';
      NO_ASSERT_CHECK='TRUE';
      NO_DIR_CHECK='TRUE';
      ALLOW_CONNECT='TRUE';
    'VCCD_HV2':
      PIN_NUMBER='(0,0,0,0,0,0,0,0,0,0,0,0,0,0,0,0,0,0,0,0,0,0,0,0,0,0,0,0,AU3,0~
,0,0,0,0,0,0,0,0,0,0,0,0)';
      PINUSE='POWER';
      NO_LOAD_CHECK='Both';
      NO_IO_CHECK='Both';
      NO_ASSERT_CHECK='TRUE';
      NO_DIR_CHECK='TRUE';
      ALLOW_CONNECT='TRUE';
    'VCCD_HV1':
      PIN_NUMBER='(0,0,0,0,0,0,0,0,0,0,0,0,0,0,0,0,0,0,0,0,0,0,0,0,0,0,0,0,AT55,~
0,0,0,0,0,0,0,0,0,0,0,0,0)';
      PINUSE='POWER';
      NO_LOAD_CHECK='Both';
      NO_IO_CHECK='Both';
      NO_ASSERT_CHECK='TRUE';
      NO_DIR_CHECK='TRUE';
      ALLOW_CONNECT='TRUE';
    'VCCD_HV0':
      PIN_NUMBER='(0,0,0,0,0,0,0,0,0,0,0,0,0,0,0,0,0,0,0,0,0,0,0,0,0,0,0,0,AT36,~
0,0,0,0,0,0,0,0,0,0,0,0,0)';
      PINUSE='POWER';
      NO_LOAD_CHECK='Both';
      NO_IO_CHECK='Both';
      NO_ASSERT_CHECK='TRUE';
      NO_DIR_CHECK='TRUE';
      ALLOW_CONNECT='TRUE';
    'VCCFA_EHV8':
      PIN_NUMBER='(0,0,0,0,0,0,0,0,0,0,0,0,0,0,0,0,0,0,0,0,0,0,0,0,0,0,0,0,N3,0,~
0,0,0,0,0,0,0,0,0,0,0,0)';
      PINUSE='POWER';
      NO_LOAD_CHECK='Both';
      NO_IO_CHECK='Both';
      NO_ASSERT_CHECK='TRUE';
      NO_DIR_CHECK='TRUE';
      ALLOW_CONNECT='TRUE';
    'VCCFA_EHV9':
      PIN_NUMBER='(0,0,0,0,0,0,0,0,0,0,0,0,0,0,0,0,0,0,0,0,0,0,0,0,0,0,0,0,U3,0,~
0,0,0,0,0,0,0,0,0,0,0,0)';
      PINUSE='POWER';
      NO_LOAD_CHECK='Both';
      NO_IO_CHECK='Both';
      NO_ASSERT_CHECK='TRUE';
      NO_DIR_CHECK='TRUE';
      ALLOW_CONNECT='TRUE';
    'VCCFA_EHV7':
      PIN_NUMBER='(0,0,0,0,0,0,0,0,0,0,0,0,0,0,0,0,0,0,0,0,0,0,0,0,0,0,0,0,AW60,~
0,0,0,0,0,0,0,0,0,0,0,0,0)';
      PINUSE='POWER';
      NO_LOAD_CHECK='Both';
      NO_IO_CHECK='Both';
      NO_ASSERT_CHECK='TRUE';
      NO_DIR_CHECK='TRUE';
      ALLOW_CONNECT='TRUE';
    'VCCFA_EHV6':
      PIN_NUMBER='(0,0,0,0,0,0,0,0,0,0,0,0,0,0,0,0,0,0,0,0,0,0,0,0,0,0,0,0,AV61,~
0,0,0,0,0,0,0,0,0,0,0,0,0)';
      PINUSE='POWER';
      NO_LOAD_CHECK='Both';
      NO_IO_CHECK='Both';
      NO_ASSERT_CHECK='TRUE';
      NO_DIR_CHECK='TRUE';
      ALLOW_CONNECT='TRUE';
    'VCCFA_EHV5':
      PIN_NUMBER='(0,0,0,0,0,0,0,0,0,0,0,0,0,0,0,0,0,0,0,0,0,0,0,0,0,0,0,0,AU60,~
0,0,0,0,0,0,0,0,0,0,0,0,0)';
      PINUSE='POWER';
      NO_LOAD_CHECK='Both';
      NO_IO_CHECK='Both';
      NO_ASSERT_CHECK='TRUE';
      NO_DIR_CHECK='TRUE';
      ALLOW_CONNECT='TRUE';
    'VCCFA_EHV4':
      PIN_NUMBER='(0,0,0,0,0,0,0,0,0,0,0,0,0,0,0,0,0,0,0,0,0,0,0,0,0,0,0,0,AT61,~
0,0,0,0,0,0,0,0,0,0,0,0,0)';
      PINUSE='POWER';
      NO_LOAD_CHECK='Both';
      NO_IO_CHECK='Both';
      NO_ASSERT_CHECK='TRUE';
      NO_DIR_CHECK='TRUE';
      ALLOW_CONNECT='TRUE';
    'VCCFA_EHV3':
      PIN_NUMBER='(0,0,0,0,0,0,0,0,0,0,0,0,0,0,0,0,0,0,0,0,0,0,0,0,0,0,0,0,AN3,0~
,0,0,0,0,0,0,0,0,0,0,0,0)';
      PINUSE='POWER';
      NO_LOAD_CHECK='Both';
      NO_IO_CHECK='Both';
      NO_ASSERT_CHECK='TRUE';
      NO_DIR_CHECK='TRUE';
      ALLOW_CONNECT='TRUE';
    'VCCFA_EHV2':
      PIN_NUMBER='(0,0,0,0,0,0,0,0,0,0,0,0,0,0,0,0,0,0,0,0,0,0,0,0,0,0,0,0,AJ3,0~
,0,0,0,0,0,0,0,0,0,0,0,0)';
      PINUSE='POWER';
      NO_LOAD_CHECK='Both';
      NO_IO_CHECK='Both';
      NO_ASSERT_CHECK='TRUE';
      NO_DIR_CHECK='TRUE';
      ALLOW_CONNECT='TRUE';
    'VCCFA_EHV1':
      PIN_NUMBER='(0,0,0,0,0,0,0,0,0,0,0,0,0,0,0,0,0,0,0,0,0,0,0,0,0,0,0,0,AE3,0~
,0,0,0,0,0,0,0,0,0,0,0,0)';
      PINUSE='POWER';
      NO_LOAD_CHECK='Both';
      NO_IO_CHECK='Both';
      NO_ASSERT_CHECK='TRUE';
      NO_DIR_CHECK='TRUE';
      ALLOW_CONNECT='TRUE';
    'VCCFA_EHV0':
      PIN_NUMBER='(0,0,0,0,0,0,0,0,0,0,0,0,0,0,0,0,0,0,0,0,0,0,0,0,0,0,0,0,AA3,0~
,0,0,0,0,0,0,0,0,0,0,0,0)';
      PINUSE='POWER';
      NO_LOAD_CHECK='Both';
      NO_IO_CHECK='Both';
      NO_ASSERT_CHECK='TRUE';
      NO_DIR_CHECK='TRUE';
      ALLOW_CONNECT='TRUE';
    'VCCINFAON59':
      PIN_NUMBER='(0,0,0,0,0,0,0,0,0,0,0,0,0,0,0,0,0,0,0,0,0,0,0,0,0,0,0,0,DJ11,~
0,0,0,0,0,0,0,0,0,0,0,0,0)';
      PINUSE='POWER';
      NO_LOAD_CHECK='Both';
      NO_IO_CHECK='Both';
      NO_ASSERT_CHECK='TRUE';
      NO_DIR_CHECK='TRUE';
      ALLOW_CONNECT='TRUE';
    'VCCINFAON58':
      PIN_NUMBER='(0,0,0,0,0,0,0,0,0,0,0,0,0,0,0,0,0,0,0,0,0,0,0,0,0,0,0,0,DE7,0~
,0,0,0,0,0,0,0,0,0,0,0,0)';
      PINUSE='POWER';
      NO_LOAD_CHECK='Both';
      NO_IO_CHECK='Both';
      NO_ASSERT_CHECK='TRUE';
      NO_DIR_CHECK='TRUE';
      ALLOW_CONNECT='TRUE';
    'VCCINFAON57':
      PIN_NUMBER='(0,0,0,0,0,0,0,0,0,0,0,0,0,0,0,0,0,0,0,0,0,0,0,0,0,0,0,0,DA7,0~
,0,0,0,0,0,0,0,0,0,0,0,0)';
      PINUSE='POWER';
      NO_LOAD_CHECK='Both';
      NO_IO_CHECK='Both';
      NO_ASSERT_CHECK='TRUE';
      NO_DIR_CHECK='TRUE';
      ALLOW_CONNECT='TRUE';
    'VCCINFAON56':
      PIN_NUMBER='(0,0,0,0,0,0,0,0,0,0,0,0,0,0,0,0,0,0,0,0,0,0,0,0,0,0,0,0,DA3,0~
,0,0,0,0,0,0,0,0,0,0,0,0)';
      PINUSE='POWER';
      NO_LOAD_CHECK='Both';
      NO_IO_CHECK='Both';
      NO_ASSERT_CHECK='TRUE';
      NO_DIR_CHECK='TRUE';
      ALLOW_CONNECT='TRUE';
    'VCCINFAON55':
      PIN_NUMBER='(0,0,0,0,0,0,0,0,0,0,0,0,0,0,0,0,0,0,0,0,0,0,0,0,0,0,0,0,CW64,~
0,0,0,0,0,0,0,0,0,0,0,0,0)';
      PINUSE='POWER';
      NO_LOAD_CHECK='Both';
      NO_IO_CHECK='Both';
      NO_ASSERT_CHECK='TRUE';
      NO_DIR_CHECK='TRUE';
      ALLOW_CONNECT='TRUE';
    'VCCINFAON54':
      PIN_NUMBER='(0,0,0,0,0,0,0,0,0,0,0,0,0,0,0,0,0,0,0,0,0,0,0,0,0,0,0,0,CR66,~
0,0,0,0,0,0,0,0,0,0,0,0,0)';
      PINUSE='POWER';
      NO_LOAD_CHECK='Both';
      NO_IO_CHECK='Both';
      NO_ASSERT_CHECK='TRUE';
      NO_DIR_CHECK='TRUE';
      ALLOW_CONNECT='TRUE';
    'VCCINFAON32':
      PIN_NUMBER='(0,0,0,0,0,0,0,0,0,0,0,0,0,0,0,0,0,0,0,0,0,0,0,0,0,0,0,0,DJ7,0~
,0,0,0,0,0,0,0,0,0,0,0,0)';
      PINUSE='POWER';
      NO_LOAD_CHECK='Both';
      NO_IO_CHECK='Both';
      NO_ASSERT_CHECK='TRUE';
      NO_DIR_CHECK='TRUE';
      ALLOW_CONNECT='TRUE';
    'VCCINFAON31':
      PIN_NUMBER='(0,0,0,0,0,0,0,0,0,0,0,0,0,0,0,0,0,0,0,0,0,0,0,0,0,0,0,0,DJ3,0~
,0,0,0,0,0,0,0,0,0,0,0,0)';
      PINUSE='POWER';
      NO_LOAD_CHECK='Both';
      NO_IO_CHECK='Both';
      NO_ASSERT_CHECK='TRUE';
      NO_DIR_CHECK='TRUE';
      ALLOW_CONNECT='TRUE';
    'VCCINFAON30':
      PIN_NUMBER='(0,0,0,0,0,0,0,0,0,0,0,0,0,0,0,0,0,0,0,0,0,0,0,0,0,0,0,0,DJ15,~
0,0,0,0,0,0,0,0,0,0,0,0,0)';
      PINUSE='POWER';
      NO_LOAD_CHECK='Both';
      NO_IO_CHECK='Both';
      NO_ASSERT_CHECK='TRUE';
      NO_DIR_CHECK='TRUE';
      ALLOW_CONNECT='TRUE';
    'VCCINFAON29':
      PIN_NUMBER='(0,0,0,0,0,0,0,0,0,0,0,0,0,0,0,0,0,0,0,0,0,0,0,0,0,0,0,0,DE3,0~
,0,0,0,0,0,0,0,0,0,0,0,0)';
      PINUSE='POWER';
      NO_LOAD_CHECK='Both';
      NO_IO_CHECK='Both';
      NO_ASSERT_CHECK='TRUE';
      NO_DIR_CHECK='TRUE';
      ALLOW_CONNECT='TRUE';
    'VCCINFAON28':
      PIN_NUMBER='(0,0,0,0,0,0,0,0,0,0,0,0,0,0,0,0,0,0,0,0,0,0,0,0,0,0,0,0,DE15,~
0,0,0,0,0,0,0,0,0,0,0,0,0)';
      PINUSE='POWER';
      NO_LOAD_CHECK='Both';
      NO_IO_CHECK='Both';
      NO_ASSERT_CHECK='TRUE';
      NO_DIR_CHECK='TRUE';
      ALLOW_CONNECT='TRUE';
    'VCCINFAON27':
      PIN_NUMBER='(0,0,0,0,0,0,0,0,0,0,0,0,0,0,0,0,0,0,0,0,0,0,0,0,0,0,0,0,DE11,~
0,0,0,0,0,0,0,0,0,0,0,0,0)';
      PINUSE='POWER';
      NO_LOAD_CHECK='Both';
      NO_IO_CHECK='Both';
      NO_ASSERT_CHECK='TRUE';
      NO_DIR_CHECK='TRUE';
      ALLOW_CONNECT='TRUE';
    'VCCINFAON26':
      PIN_NUMBER='(0,0,0,0,0,0,0,0,0,0,0,0,0,0,0,0,0,0,0,0,0,0,0,0,0,0,0,0,DA64,~
0,0,0,0,0,0,0,0,0,0,0,0,0)';
      PINUSE='POWER';
      NO_LOAD_CHECK='Both';
      NO_IO_CHECK='Both';
      NO_ASSERT_CHECK='TRUE';
      NO_DIR_CHECK='TRUE';
      ALLOW_CONNECT='TRUE';
    'VCCINFAON25':
      PIN_NUMBER='(0,0,0,0,0,0,0,0,0,0,0,0,0,0,0,0,0,0,0,0,0,0,0,0,0,0,0,0,DA15,~
0,0,0,0,0,0,0,0,0,0,0,0,0)';
      PINUSE='POWER';
      NO_LOAD_CHECK='Both';
      NO_IO_CHECK='Both';
      NO_ASSERT_CHECK='TRUE';
      NO_DIR_CHECK='TRUE';
      ALLOW_CONNECT='TRUE';
    'VCCINFAON24':
      PIN_NUMBER='(0,0,0,0,0,0,0,0,0,0,0,0,0,0,0,0,0,0,0,0,0,0,0,0,0,0,0,0,DA11,~
0,0,0,0,0,0,0,0,0,0,0,0,0)';
      PINUSE='POWER';
      NO_LOAD_CHECK='Both';
      NO_IO_CHECK='Both';
      NO_ASSERT_CHECK='TRUE';
      NO_DIR_CHECK='TRUE';
      ALLOW_CONNECT='TRUE';
    'VCCINFAON23':
      PIN_NUMBER='(0,0,0,0,0,0,0,0,0,0,0,0,0,0,0,0,0,0,0,0,0,0,0,0,0,0,0,0,CY67,~
0,0,0,0,0,0,0,0,0,0,0,0,0)';
      PINUSE='POWER';
      NO_LOAD_CHECK='Both';
      NO_IO_CHECK='Both';
      NO_ASSERT_CHECK='TRUE';
      NO_DIR_CHECK='TRUE';
      ALLOW_CONNECT='TRUE';
    'VCCINFAON22':
      PIN_NUMBER='(0,0,0,0,0,0,0,0,0,0,0,0,0,0,0,0,0,0,0,0,0,0,0,0,0,0,0,0,CY65,~
0,0,0,0,0,0,0,0,0,0,0,0,0)';
      PINUSE='POWER';
      NO_LOAD_CHECK='Both';
      NO_IO_CHECK='Both';
      NO_ASSERT_CHECK='TRUE';
      NO_DIR_CHECK='TRUE';
      ALLOW_CONNECT='TRUE';
    'VCCINFAON21':
      PIN_NUMBER='(0,0,0,0,0,0,0,0,0,0,0,0,0,0,0,0,0,0,0,0,0,0,0,0,0,0,0,0,CW66,~
0,0,0,0,0,0,0,0,0,0,0,0,0)';
      PINUSE='POWER';
      NO_LOAD_CHECK='Both';
      NO_IO_CHECK='Both';
      NO_ASSERT_CHECK='TRUE';
      NO_DIR_CHECK='TRUE';
      ALLOW_CONNECT='TRUE';
    'VCCINFAON20':
      PIN_NUMBER='(0,0,0,0,0,0,0,0,0,0,0,0,0,0,0,0,0,0,0,0,0,0,0,0,0,0,0,0,CV67,~
0,0,0,0,0,0,0,0,0,0,0,0,0)';
      PINUSE='POWER';
      NO_LOAD_CHECK='Both';
      NO_IO_CHECK='Both';
      NO_ASSERT_CHECK='TRUE';
      NO_DIR_CHECK='TRUE';
      ALLOW_CONNECT='TRUE';
    'VCCINFAON19':
      PIN_NUMBER='(0,0,0,0,0,0,0,0,0,0,0,0,0,0,0,0,0,0,0,0,0,0,0,0,0,0,0,0,CV65,~
0,0,0,0,0,0,0,0,0,0,0,0,0)';
      PINUSE='POWER';
      NO_LOAD_CHECK='Both';
      NO_IO_CHECK='Both';
      NO_ASSERT_CHECK='TRUE';
      NO_DIR_CHECK='TRUE';
      ALLOW_CONNECT='TRUE';
    'VCCINFAON18':
      PIN_NUMBER='(0,0,0,0,0,0,0,0,0,0,0,0,0,0,0,0,0,0,0,0,0,0,0,0,0,0,0,0,CU7,0~
,0,0,0,0,0,0,0,0,0,0,0,0)';
      PINUSE='POWER';
      NO_LOAD_CHECK='Both';
      NO_IO_CHECK='Both';
      NO_ASSERT_CHECK='TRUE';
      NO_DIR_CHECK='TRUE';
      ALLOW_CONNECT='TRUE';
    'VCCINFAON17':
      PIN_NUMBER='(0,0,0,0,0,0,0,0,0,0,0,0,0,0,0,0,0,0,0,0,0,0,0,0,0,0,0,0,CU64,~
0,0,0,0,0,0,0,0,0,0,0,0,0)';
      PINUSE='POWER';
      NO_LOAD_CHECK='Both';
      NO_IO_CHECK='Both';
      NO_ASSERT_CHECK='TRUE';
      NO_DIR_CHECK='TRUE';
      ALLOW_CONNECT='TRUE';
    'VCCINFAON16':
      PIN_NUMBER='(0,0,0,0,0,0,0,0,0,0,0,0,0,0,0,0,0,0,0,0,0,0,0,0,0,0,0,0,CU3,0~
,0,0,0,0,0,0,0,0,0,0,0,0)';
      PINUSE='POWER';
      NO_LOAD_CHECK='Both';
      NO_IO_CHECK='Both';
      NO_ASSERT_CHECK='TRUE';
      NO_DIR_CHECK='TRUE';
      ALLOW_CONNECT='TRUE';
    'VCCINFAON15':
      PIN_NUMBER='(0,0,0,0,0,0,0,0,0,0,0,0,0,0,0,0,0,0,0,0,0,0,0,0,0,0,0,0,CU15,~
0,0,0,0,0,0,0,0,0,0,0,0,0)';
      PINUSE='POWER';
      NO_LOAD_CHECK='Both';
      NO_IO_CHECK='Both';
      NO_ASSERT_CHECK='TRUE';
      NO_DIR_CHECK='TRUE';
      ALLOW_CONNECT='TRUE';
    'VCCINFAON14':
      PIN_NUMBER='(0,0,0,0,0,0,0,0,0,0,0,0,0,0,0,0,0,0,0,0,0,0,0,0,0,0,0,0,CU11,~
0,0,0,0,0,0,0,0,0,0,0,0,0)';
      PINUSE='POWER';
      NO_LOAD_CHECK='Both';
      NO_IO_CHECK='Both';
      NO_ASSERT_CHECK='TRUE';
      NO_DIR_CHECK='TRUE';
      ALLOW_CONNECT='TRUE';
    'VCCINFAON13':
      PIN_NUMBER='(0,0,0,0,0,0,0,0,0,0,0,0,0,0,0,0,0,0,0,0,0,0,0,0,0,0,0,0,CT67,~
0,0,0,0,0,0,0,0,0,0,0,0,0)';
      PINUSE='POWER';
      NO_LOAD_CHECK='Both';
      NO_IO_CHECK='Both';
      NO_ASSERT_CHECK='TRUE';
      NO_DIR_CHECK='TRUE';
      ALLOW_CONNECT='TRUE';
    'VCCINFAON12':
      PIN_NUMBER='(0,0,0,0,0,0,0,0,0,0,0,0,0,0,0,0,0,0,0,0,0,0,0,0,0,0,0,0,CT65,~
0,0,0,0,0,0,0,0,0,0,0,0,0)';
      PINUSE='POWER';
      NO_LOAD_CHECK='Both';
      NO_IO_CHECK='Both';
      NO_ASSERT_CHECK='TRUE';
      NO_DIR_CHECK='TRUE';
      ALLOW_CONNECT='TRUE';
    'VCCINFAON11':
      PIN_NUMBER='(0,0,0,0,0,0,0,0,0,0,0,0,0,0,0,0,0,0,0,0,0,0,0,0,0,0,0,0,CP67,~
0,0,0,0,0,0,0,0,0,0,0,0,0)';
      PINUSE='POWER';
      NO_LOAD_CHECK='Both';
      NO_IO_CHECK='Both';
      NO_ASSERT_CHECK='TRUE';
      NO_DIR_CHECK='TRUE';
      ALLOW_CONNECT='TRUE';
    'VCCINFAON10':
      PIN_NUMBER='(0,0,0,0,0,0,0,0,0,0,0,0,0,0,0,0,0,0,0,0,0,0,0,0,0,0,0,0,CP65,~
0,0,0,0,0,0,0,0,0,0,0,0,0)';
      PINUSE='POWER';
      NO_LOAD_CHECK='Both';
      NO_IO_CHECK='Both';
      NO_ASSERT_CHECK='TRUE';
      NO_DIR_CHECK='TRUE';
      ALLOW_CONNECT='TRUE';
    'VCCINFAON9':
      PIN_NUMBER='(0,0,0,0,0,0,0,0,0,0,0,0,0,0,0,0,0,0,0,0,0,0,0,0,0,0,0,0,CN7,0~
,0,0,0,0,0,0,0,0,0,0,0,0)';
      PINUSE='POWER';
      NO_LOAD_CHECK='Both';
      NO_IO_CHECK='Both';
      NO_ASSERT_CHECK='TRUE';
      NO_DIR_CHECK='TRUE';
      ALLOW_CONNECT='TRUE';
    'VCCINFAON8':
      PIN_NUMBER='(0,0,0,0,0,0,0,0,0,0,0,0,0,0,0,0,0,0,0,0,0,0,0,0,0,0,0,0,CN66,~
0,0,0,0,0,0,0,0,0,0,0,0,0)';
      PINUSE='POWER';
      NO_LOAD_CHECK='Both';
      NO_IO_CHECK='Both';
      NO_ASSERT_CHECK='TRUE';
      NO_DIR_CHECK='TRUE';
      ALLOW_CONNECT='TRUE';
    'VCCINFAON7':
      PIN_NUMBER='(0,0,0,0,0,0,0,0,0,0,0,0,0,0,0,0,0,0,0,0,0,0,0,0,0,0,0,0,CN64,~
0,0,0,0,0,0,0,0,0,0,0,0,0)';
      PINUSE='POWER';
      NO_LOAD_CHECK='Both';
      NO_IO_CHECK='Both';
      NO_ASSERT_CHECK='TRUE';
      NO_DIR_CHECK='TRUE';
      ALLOW_CONNECT='TRUE';
    'VCCINFAON6':
      PIN_NUMBER='(0,0,0,0,0,0,0,0,0,0,0,0,0,0,0,0,0,0,0,0,0,0,0,0,0,0,0,0,CN3,0~
,0,0,0,0,0,0,0,0,0,0,0,0)';
      PINUSE='POWER';
      NO_LOAD_CHECK='Both';
      NO_IO_CHECK='Both';
      NO_ASSERT_CHECK='TRUE';
      NO_DIR_CHECK='TRUE';
      ALLOW_CONNECT='TRUE';
    'VCCINFAON5':
      PIN_NUMBER='(0,0,0,0,0,0,0,0,0,0,0,0,0,0,0,0,0,0,0,0,0,0,0,0,0,0,0,0,CN15,~
0,0,0,0,0,0,0,0,0,0,0,0,0)';
      PINUSE='POWER';
      NO_LOAD_CHECK='Both';
      NO_IO_CHECK='Both';
      NO_ASSERT_CHECK='TRUE';
      NO_DIR_CHECK='TRUE';
      ALLOW_CONNECT='TRUE';
    'VCCINFAON4':
      PIN_NUMBER='(0,0,0,0,0,0,0,0,0,0,0,0,0,0,0,0,0,0,0,0,0,0,0,0,0,0,0,0,CN11,~
0,0,0,0,0,0,0,0,0,0,0,0,0)';
      PINUSE='POWER';
      NO_LOAD_CHECK='Both';
      NO_IO_CHECK='Both';
      NO_ASSERT_CHECK='TRUE';
      NO_DIR_CHECK='TRUE';
      ALLOW_CONNECT='TRUE';
    'VCCINFAON3':
      PIN_NUMBER='(0,0,0,0,0,0,0,0,0,0,0,0,0,0,0,0,0,0,0,0,0,0,0,0,0,0,0,0,CJ7,0~
,0,0,0,0,0,0,0,0,0,0,0,0)';
      PINUSE='POWER';
      NO_LOAD_CHECK='Both';
      NO_IO_CHECK='Both';
      NO_ASSERT_CHECK='TRUE';
      NO_DIR_CHECK='TRUE';
      ALLOW_CONNECT='TRUE';
    'VCCINFAON2':
      PIN_NUMBER='(0,0,0,0,0,0,0,0,0,0,0,0,0,0,0,0,0,0,0,0,0,0,0,0,0,0,0,0,CJ3,0~
,0,0,0,0,0,0,0,0,0,0,0,0)';
      PINUSE='POWER';
      NO_LOAD_CHECK='Both';
      NO_IO_CHECK='Both';
      NO_ASSERT_CHECK='TRUE';
      NO_DIR_CHECK='TRUE';
      ALLOW_CONNECT='TRUE';
    'VCCINFAON1':
      PIN_NUMBER='(0,0,0,0,0,0,0,0,0,0,0,0,0,0,0,0,0,0,0,0,0,0,0,0,0,0,0,0,CJ15,~
0,0,0,0,0,0,0,0,0,0,0,0,0)';
      PINUSE='POWER';
      NO_LOAD_CHECK='Both';
      NO_IO_CHECK='Both';
      NO_ASSERT_CHECK='TRUE';
      NO_DIR_CHECK='TRUE';
      ALLOW_CONNECT='TRUE';
    'VCCINFAON0':
      PIN_NUMBER='(0,0,0,0,0,0,0,0,0,0,0,0,0,0,0,0,0,0,0,0,0,0,0,0,0,0,0,0,CE15,~
0,0,0,0,0,0,0,0,0,0,0,0,0)';
      PINUSE='POWER';
      NO_LOAD_CHECK='Both';
      NO_IO_CHECK='Both';
      NO_ASSERT_CHECK='TRUE';
      NO_DIR_CHECK='TRUE';
      ALLOW_CONNECT='TRUE';
    'VCCVNN3':
      PIN_NUMBER='(0,0,0,0,0,0,0,0,0,0,0,0,0,0,0,0,0,0,0,0,0,0,0,0,0,0,0,0,BN19,~
0,0,0,0,0,0,0,0,0,0,0,0,0)';
      PINUSE='POWER';
      NO_LOAD_CHECK='Both';
      NO_IO_CHECK='Both';
      NO_ASSERT_CHECK='TRUE';
      NO_DIR_CHECK='TRUE';
      ALLOW_CONNECT='TRUE';
    'VCCVNN2':
      PIN_NUMBER='(0,0,0,0,0,0,0,0,0,0,0,0,0,0,0,0,0,0,0,0,0,0,0,0,0,0,0,0,BJ19,~
0,0,0,0,0,0,0,0,0,0,0,0,0)';
      PINUSE='POWER';
      NO_LOAD_CHECK='Both';
      NO_IO_CHECK='Both';
      NO_ASSERT_CHECK='TRUE';
      NO_DIR_CHECK='TRUE';
      ALLOW_CONNECT='TRUE';
    'VCCVNN1':
      PIN_NUMBER='(0,0,0,0,0,0,0,0,0,0,0,0,0,0,0,0,0,0,0,0,0,0,0,0,0,0,0,0,BE19,~
0,0,0,0,0,0,0,0,0,0,0,0,0)';
      PINUSE='POWER';
      NO_LOAD_CHECK='Both';
      NO_IO_CHECK='Both';
      NO_ASSERT_CHECK='TRUE';
      NO_DIR_CHECK='TRUE';
      ALLOW_CONNECT='TRUE';
    'VCCVNN0':
      PIN_NUMBER='(0,0,0,0,0,0,0,0,0,0,0,0,0,0,0,0,0,0,0,0,0,0,0,0,0,0,0,0,BA19,~
0,0,0,0,0,0,0,0,0,0,0,0,0)';
      PINUSE='POWER';
      NO_LOAD_CHECK='Both';
      NO_IO_CHECK='Both';
      NO_ASSERT_CHECK='TRUE';
      NO_DIR_CHECK='TRUE';
      ALLOW_CONNECT='TRUE';
    'VPP_HBM':
      PIN_NUMBER='(0,0,0,0,0,0,0,0,0,0,0,0,0,0,0,0,0,0,0,0,0,0,0,0,0,0,0,0,CG68,~
0,0,0,0,0,0,0,0,0,0,0,0,0)';
      PINUSE='POWER';
      NO_LOAD_CHECK='Both';
      NO_IO_CHECK='Both';
      NO_ASSERT_CHECK='TRUE';
      NO_DIR_CHECK='TRUE';
      ALLOW_CONNECT='TRUE';
    'VPP_HBM1':
      PIN_NUMBER='(0,0,0,0,0,0,0,0,0,0,0,0,0,0,0,0,0,0,0,0,0,0,0,0,0,0,0,0,CF67,~
0,0,0,0,0,0,0,0,0,0,0,0,0)';
      PINUSE='POWER';
      NO_LOAD_CHECK='Both';
      NO_IO_CHECK='Both';
      NO_ASSERT_CHECK='TRUE';
      NO_DIR_CHECK='TRUE';
      ALLOW_CONNECT='TRUE';
    'VPP_HBM2':
      PIN_NUMBER='(0,0,0,0,0,0,0,0,0,0,0,0,0,0,0,0,0,0,0,0,0,0,0,0,0,0,0,0,CE68,~
0,0,0,0,0,0,0,0,0,0,0,0,0)';
      PINUSE='POWER';
      NO_LOAD_CHECK='Both';
      NO_IO_CHECK='Both';
      NO_ASSERT_CHECK='TRUE';
      NO_DIR_CHECK='TRUE';
      ALLOW_CONNECT='TRUE';
    'VPP_HBM3':
      PIN_NUMBER='(0,0,0,0,0,0,0,0,0,0,0,0,0,0,0,0,0,0,0,0,0,0,0,0,0,0,0,0,CD67,~
0,0,0,0,0,0,0,0,0,0,0,0,0)';
      PINUSE='POWER';
      NO_LOAD_CHECK='Both';
      NO_IO_CHECK='Both';
      NO_ASSERT_CHECK='TRUE';
      NO_DIR_CHECK='TRUE';
      ALLOW_CONNECT='TRUE';
    'VPP_HBM4':
      PIN_NUMBER='(0,0,0,0,0,0,0,0,0,0,0,0,0,0,0,0,0,0,0,0,0,0,0,0,0,0,0,0,CC68,~
0,0,0,0,0,0,0,0,0,0,0,0,0)';
      PINUSE='POWER';
      NO_LOAD_CHECK='Both';
      NO_IO_CHECK='Both';
      NO_ASSERT_CHECK='TRUE';
      NO_DIR_CHECK='TRUE';
      ALLOW_CONNECT='TRUE';
    'VCCFA_EHV_FIVRA104':
      PIN_NUMBER='(0,0,0,0,0,0,0,0,0,0,0,0,0,0,0,0,0,0,0,0,0,0,0,0,0,0,0,0,0,Y89~
,0,0,0,0,0,0,0,0,0,0,0,0)';
      PINUSE='POWER';
      NO_LOAD_CHECK='Both';
      NO_IO_CHECK='Both';
      NO_ASSERT_CHECK='TRUE';
      NO_DIR_CHECK='TRUE';
      ALLOW_CONNECT='TRUE';
    'VCCFA_EHV_FIVRA103':
      PIN_NUMBER='(0,0,0,0,0,0,0,0,0,0,0,0,0,0,0,0,0,0,0,0,0,0,0,0,0,0,0,0,0,Y85~
,0,0,0,0,0,0,0,0,0,0,0,0)';
      PINUSE='POWER';
      NO_LOAD_CHECK='Both';
      NO_IO_CHECK='Both';
      NO_ASSERT_CHECK='TRUE';
      NO_DIR_CHECK='TRUE';
      ALLOW_CONNECT='TRUE';
    'VCCFA_EHV_FIVRA102':
      PIN_NUMBER='(0,0,0,0,0,0,0,0,0,0,0,0,0,0,0,0,0,0,0,0,0,0,0,0,0,0,0,0,0,Y79~
,0,0,0,0,0,0,0,0,0,0,0,0)';
      PINUSE='POWER';
      NO_LOAD_CHECK='Both';
      NO_IO_CHECK='Both';
      NO_ASSERT_CHECK='TRUE';
      NO_DIR_CHECK='TRUE';
      ALLOW_CONNECT='TRUE';
    'VCCFA_EHV_FIVRA101':
      PIN_NUMBER='(0,0,0,0,0,0,0,0,0,0,0,0,0,0,0,0,0,0,0,0,0,0,0,0,0,0,0,0,0,W80~
,0,0,0,0,0,0,0,0,0,0,0,0)';
      PINUSE='POWER';
      NO_LOAD_CHECK='Both';
      NO_IO_CHECK='Both';
      NO_ASSERT_CHECK='TRUE';
      NO_DIR_CHECK='TRUE';
      ALLOW_CONNECT='TRUE';
    'VCCFA_EHV_FIVRA100':
      PIN_NUMBER='(0,0,0,0,0,0,0,0,0,0,0,0,0,0,0,0,0,0,0,0,0,0,0,0,0,0,0,0,0,U7,~
0,0,0,0,0,0,0,0,0,0,0,0)';
      PINUSE='POWER';
      NO_LOAD_CHECK='Both';
      NO_IO_CHECK='Both';
      NO_ASSERT_CHECK='TRUE';
      NO_DIR_CHECK='TRUE';
      ALLOW_CONNECT='TRUE';
    'VCCFA_EHV_FIVRA99':
      PIN_NUMBER='(0,0,0,0,0,0,0,0,0,0,0,0,0,0,0,0,0,0,0,0,0,0,0,0,0,0,0,0,0,U15~
,0,0,0,0,0,0,0,0,0,0,0,0)';
      PINUSE='POWER';
      NO_LOAD_CHECK='Both';
      NO_IO_CHECK='Both';
      NO_ASSERT_CHECK='TRUE';
      NO_DIR_CHECK='TRUE';
      ALLOW_CONNECT='TRUE';
    'VCCFA_EHV_FIVRA98':
      PIN_NUMBER='(0,0,0,0,0,0,0,0,0,0,0,0,0,0,0,0,0,0,0,0,0,0,0,0,0,0,0,0,0,U11~
,0,0,0,0,0,0,0,0,0,0,0,0)';
      PINUSE='POWER';
      NO_LOAD_CHECK='Both';
      NO_IO_CHECK='Both';
      NO_ASSERT_CHECK='TRUE';
      NO_DIR_CHECK='TRUE';
      ALLOW_CONNECT='TRUE';
    'VCCFA_EHV_FIVRA97':
      PIN_NUMBER='(0,0,0,0,0,0,0,0,0,0,0,0,0,0,0,0,0,0,0,0,0,0,0,0,0,0,0,0,0,T89~
,0,0,0,0,0,0,0,0,0,0,0,0)';
      PINUSE='POWER';
      NO_LOAD_CHECK='Both';
      NO_IO_CHECK='Both';
      NO_ASSERT_CHECK='TRUE';
      NO_DIR_CHECK='TRUE';
      ALLOW_CONNECT='TRUE';
    'VCCFA_EHV_FIVRA96':
      PIN_NUMBER='(0,0,0,0,0,0,0,0,0,0,0,0,0,0,0,0,0,0,0,0,0,0,0,0,0,0,0,0,0,T85~
,0,0,0,0,0,0,0,0,0,0,0,0)';
      PINUSE='POWER';
      NO_LOAD_CHECK='Both';
      NO_IO_CHECK='Both';
      NO_ASSERT_CHECK='TRUE';
      NO_DIR_CHECK='TRUE';
      ALLOW_CONNECT='TRUE';
    'VCCFA_EHV_FIVRA95':
      PIN_NUMBER='(0,0,0,0,0,0,0,0,0,0,0,0,0,0,0,0,0,0,0,0,0,0,0,0,0,0,0,0,0,R80~
,0,0,0,0,0,0,0,0,0,0,0,0)';
      PINUSE='POWER';
      NO_LOAD_CHECK='Both';
      NO_IO_CHECK='Both';
      NO_ASSERT_CHECK='TRUE';
      NO_DIR_CHECK='TRUE';
      ALLOW_CONNECT='TRUE';
    'VCCFA_EHV_FIVRA94':
      PIN_NUMBER='(0,0,0,0,0,0,0,0,0,0,0,0,0,0,0,0,0,0,0,0,0,0,0,0,0,0,0,0,0,P79~
,0,0,0,0,0,0,0,0,0,0,0,0)';
      PINUSE='POWER';
      NO_LOAD_CHECK='Both';
      NO_IO_CHECK='Both';
      NO_ASSERT_CHECK='TRUE';
      NO_DIR_CHECK='TRUE';
      ALLOW_CONNECT='TRUE';
    'VCCFA_EHV_FIVRA93':
      PIN_NUMBER='(0,0,0,0,0,0,0,0,0,0,0,0,0,0,0,0,0,0,0,0,0,0,0,0,0,0,0,0,0,N7,~
0,0,0,0,0,0,0,0,0,0,0,0)';
      PINUSE='POWER';
      NO_LOAD_CHECK='Both';
      NO_IO_CHECK='Both';
      NO_ASSERT_CHECK='TRUE';
      NO_DIR_CHECK='TRUE';
      ALLOW_CONNECT='TRUE';
    'VCCFA_EHV_FIVRA92':
      PIN_NUMBER='(0,0,0,0,0,0,0,0,0,0,0,0,0,0,0,0,0,0,0,0,0,0,0,0,0,0,0,0,0,N11~
,0,0,0,0,0,0,0,0,0,0,0,0)';
      PINUSE='POWER';
      NO_LOAD_CHECK='Both';
      NO_IO_CHECK='Both';
      NO_ASSERT_CHECK='TRUE';
      NO_DIR_CHECK='TRUE';
      ALLOW_CONNECT='TRUE';
    'VCCFA_EHV_FIVRA91':
      PIN_NUMBER='(0,0,0,0,0,0,0,0,0,0,0,0,0,0,0,0,0,0,0,0,0,0,0,0,0,0,0,0,0,M89~
,0,0,0,0,0,0,0,0,0,0,0,0)';
      PINUSE='POWER';
      NO_LOAD_CHECK='Both';
      NO_IO_CHECK='Both';
      NO_ASSERT_CHECK='TRUE';
      NO_DIR_CHECK='TRUE';
      ALLOW_CONNECT='TRUE';
    'VCCFA_EHV_FIVRA90':
      PIN_NUMBER='(0,0,0,0,0,0,0,0,0,0,0,0,0,0,0,0,0,0,0,0,0,0,0,0,0,0,0,0,0,M85~
,0,0,0,0,0,0,0,0,0,0,0,0)';
      PINUSE='POWER';
      NO_LOAD_CHECK='Both';
      NO_IO_CHECK='Both';
      NO_ASSERT_CHECK='TRUE';
      NO_DIR_CHECK='TRUE';
      ALLOW_CONNECT='TRUE';
    'VCCFA_EHV_FIVRA89':
      PIN_NUMBER='(0,0,0,0,0,0,0,0,0,0,0,0,0,0,0,0,0,0,0,0,0,0,0,0,0,0,0,0,0,L84~
,0,0,0,0,0,0,0,0,0,0,0,0)';
      PINUSE='POWER';
      NO_LOAD_CHECK='Both';
      NO_IO_CHECK='Both';
      NO_ASSERT_CHECK='TRUE';
      NO_DIR_CHECK='TRUE';
      ALLOW_CONNECT='TRUE';
    'VCCFA_EHV_FIVRA88':
      PIN_NUMBER='(0,0,0,0,0,0,0,0,0,0,0,0,0,0,0,0,0,0,0,0,0,0,0,0,0,0,0,0,0,K87~
,0,0,0,0,0,0,0,0,0,0,0,0)';
      PINUSE='POWER';
      NO_LOAD_CHECK='Both';
      NO_IO_CHECK='Both';
      NO_ASSERT_CHECK='TRUE';
      NO_DIR_CHECK='TRUE';
      ALLOW_CONNECT='TRUE';
    'VCCFA_EHV_FIVRA87':
      PIN_NUMBER='(0,0,0,0,0,0,0,0,0,0,0,0,0,0,0,0,0,0,0,0,0,0,0,0,0,0,0,0,0,J80~
,0,0,0,0,0,0,0,0,0,0,0,0)';
      PINUSE='POWER';
      NO_LOAD_CHECK='Both';
      NO_IO_CHECK='Both';
      NO_ASSERT_CHECK='TRUE';
      NO_DIR_CHECK='TRUE';
      ALLOW_CONNECT='TRUE';
    'VCCFA_EHV_FIVRA86':
      PIN_NUMBER='(0,0,0,0,0,0,0,0,0,0,0,0,0,0,0,0,0,0,0,0,0,0,0,0,0,0,0,0,0,J7,~
0,0,0,0,0,0,0,0,0,0,0,0)';
      PINUSE='POWER';
      NO_LOAD_CHECK='Both';
      NO_IO_CHECK='Both';
      NO_ASSERT_CHECK='TRUE';
      NO_DIR_CHECK='TRUE';
      ALLOW_CONNECT='TRUE';
    'VCCFA_EHV_FIVRA85':
      PIN_NUMBER='(0,0,0,0,0,0,0,0,0,0,0,0,0,0,0,0,0,0,0,0,0,0,0,0,0,0,0,0,0,J11~
,0,0,0,0,0,0,0,0,0,0,0,0)';
      PINUSE='POWER';
      NO_LOAD_CHECK='Both';
      NO_IO_CHECK='Both';
      NO_ASSERT_CHECK='TRUE';
      NO_DIR_CHECK='TRUE';
      ALLOW_CONNECT='TRUE';
    'VCCFA_EHV_FIVRA84':
      PIN_NUMBER='(0,0,0,0,0,0,0,0,0,0,0,0,0,0,0,0,0,0,0,0,0,0,0,0,0,0,0,0,0,H89~
,0,0,0,0,0,0,0,0,0,0,0,0)';
      PINUSE='POWER';
      NO_LOAD_CHECK='Both';
      NO_IO_CHECK='Both';
      NO_ASSERT_CHECK='TRUE';
      NO_DIR_CHECK='TRUE';
      ALLOW_CONNECT='TRUE';
    'VCCFA_EHV_FIVRA83':
      PIN_NUMBER='(0,0,0,0,0,0,0,0,0,0,0,0,0,0,0,0,0,0,0,0,0,0,0,0,0,0,0,0,0,EN8~
4,0,0,0,0,0,0,0,0,0,0,0,0)';
      PINUSE='POWER';
      NO_LOAD_CHECK='Both';
      NO_IO_CHECK='Both';
      NO_ASSERT_CHECK='TRUE';
      NO_DIR_CHECK='TRUE';
      ALLOW_CONNECT='TRUE';
    'VCCFA_EHV_FIVRA82':
      PIN_NUMBER='(0,0,0,0,0,0,0,0,0,0,0,0,0,0,0,0,0,0,0,0,0,0,0,0,0,0,0,0,0,EJ8~
4,0,0,0,0,0,0,0,0,0,0,0,0)';
      PINUSE='POWER';
      NO_LOAD_CHECK='Both';
      NO_IO_CHECK='Both';
      NO_ASSERT_CHECK='TRUE';
      NO_DIR_CHECK='TRUE';
      ALLOW_CONNECT='TRUE';
    'VCCFA_EHV_FIVRA81':
      PIN_NUMBER='(0,0,0,0,0,0,0,0,0,0,0,0,0,0,0,0,0,0,0,0,0,0,0,0,0,0,0,0,0,EJ1~
5,0,0,0,0,0,0,0,0,0,0,0,0)';
      PINUSE='POWER';
      NO_LOAD_CHECK='Both';
      NO_IO_CHECK='Both';
      NO_ASSERT_CHECK='TRUE';
      NO_DIR_CHECK='TRUE';
      ALLOW_CONNECT='TRUE';
    'VCCFA_EHV_FIVRA80':
      PIN_NUMBER='(0,0,0,0,0,0,0,0,0,0,0,0,0,0,0,0,0,0,0,0,0,0,0,0,0,0,0,0,0,EG8~
0,0,0,0,0,0,0,0,0,0,0,0,0)';
      PINUSE='POWER';
      NO_LOAD_CHECK='Both';
      NO_IO_CHECK='Both';
      NO_ASSERT_CHECK='TRUE';
      NO_DIR_CHECK='TRUE';
      ALLOW_CONNECT='TRUE';
    'VCCFA_EHV_FIVRA79':
      PIN_NUMBER='(0,0,0,0,0,0,0,0,0,0,0,0,0,0,0,0,0,0,0,0,0,0,0,0,0,0,0,0,0,EF7~
9,0,0,0,0,0,0,0,0,0,0,0,0)';
      PINUSE='POWER';
      NO_LOAD_CHECK='Both';
      NO_IO_CHECK='Both';
      NO_ASSERT_CHECK='TRUE';
      NO_DIR_CHECK='TRUE';
      ALLOW_CONNECT='TRUE';
    'VCCFA_EHV_FIVRA78':
      PIN_NUMBER='(0,0,0,0,0,0,0,0,0,0,0,0,0,0,0,0,0,0,0,0,0,0,0,0,0,0,0,0,0,EE8~
4,0,0,0,0,0,0,0,0,0,0,0,0)';
      PINUSE='POWER';
      NO_LOAD_CHECK='Both';
      NO_IO_CHECK='Both';
      NO_ASSERT_CHECK='TRUE';
      NO_DIR_CHECK='TRUE';
      ALLOW_CONNECT='TRUE';
    'VCCFA_EHV_FIVRA77':
      PIN_NUMBER='(0,0,0,0,0,0,0,0,0,0,0,0,0,0,0,0,0,0,0,0,0,0,0,0,0,0,0,0,0,EE7~
,0,0,0,0,0,0,0,0,0,0,0,0)';
      PINUSE='POWER';
      NO_LOAD_CHECK='Both';
      NO_IO_CHECK='Both';
      NO_ASSERT_CHECK='TRUE';
      NO_DIR_CHECK='TRUE';
      ALLOW_CONNECT='TRUE';
    'VCCFA_EHV_FIVRA76':
      PIN_NUMBER='(0,0,0,0,0,0,0,0,0,0,0,0,0,0,0,0,0,0,0,0,0,0,0,0,0,0,0,0,0,EE1~
5,0,0,0,0,0,0,0,0,0,0,0,0)';
      PINUSE='POWER';
      NO_LOAD_CHECK='Both';
      NO_IO_CHECK='Both';
      NO_ASSERT_CHECK='TRUE';
      NO_DIR_CHECK='TRUE';
      ALLOW_CONNECT='TRUE';
    'VCCFA_EHV_FIVRA75':
      PIN_NUMBER='(0,0,0,0,0,0,0,0,0,0,0,0,0,0,0,0,0,0,0,0,0,0,0,0,0,0,0,0,0,EE1~
1,0,0,0,0,0,0,0,0,0,0,0,0)';
      PINUSE='POWER';
      NO_LOAD_CHECK='Both';
      NO_IO_CHECK='Both';
      NO_ASSERT_CHECK='TRUE';
      NO_DIR_CHECK='TRUE';
      ALLOW_CONNECT='TRUE';
    'VCCFA_EHV_FIVRA74':
      PIN_NUMBER='(0,0,0,0,0,0,0,0,0,0,0,0,0,0,0,0,0,0,0,0,0,0,0,0,0,0,0,0,0,ED8~
9,0,0,0,0,0,0,0,0,0,0,0,0)';
      PINUSE='POWER';
      NO_LOAD_CHECK='Both';
      NO_IO_CHECK='Both';
      NO_ASSERT_CHECK='TRUE';
      NO_DIR_CHECK='TRUE';
      ALLOW_CONNECT='TRUE';
    'VCCFA_EHV_FIVRA73':
      PIN_NUMBER='(0,0,0,0,0,0,0,0,0,0,0,0,0,0,0,0,0,0,0,0,0,0,0,0,0,0,0,0,0,ED8~
5,0,0,0,0,0,0,0,0,0,0,0,0)';
      PINUSE='POWER';
      NO_LOAD_CHECK='Both';
      NO_IO_CHECK='Both';
      NO_ASSERT_CHECK='TRUE';
      NO_DIR_CHECK='TRUE';
      ALLOW_CONNECT='TRUE';
    'VCCFA_EHV_FIVRA72':
      PIN_NUMBER='(0,0,0,0,0,0,0,0,0,0,0,0,0,0,0,0,0,0,0,0,0,0,0,0,0,0,0,0,0,ED7~
9,0,0,0,0,0,0,0,0,0,0,0,0)';
      PINUSE='POWER';
      NO_LOAD_CHECK='Both';
      NO_IO_CHECK='Both';
      NO_ASSERT_CHECK='TRUE';
      NO_DIR_CHECK='TRUE';
      ALLOW_CONNECT='TRUE';
    'VCCFA_EHV_FIVRA71':
      PIN_NUMBER='(0,0,0,0,0,0,0,0,0,0,0,0,0,0,0,0,0,0,0,0,0,0,0,0,0,0,0,0,0,EC7~
8,0,0,0,0,0,0,0,0,0,0,0,0)';
      PINUSE='POWER';
      NO_LOAD_CHECK='Both';
      NO_IO_CHECK='Both';
      NO_ASSERT_CHECK='TRUE';
      NO_DIR_CHECK='TRUE';
      ALLOW_CONNECT='TRUE';
    'VCCFA_EHV_FIVRA70':
      PIN_NUMBER='(0,0,0,0,0,0,0,0,0,0,0,0,0,0,0,0,0,0,0,0,0,0,0,0,0,0,0,0,0,EA7~
,0,0,0,0,0,0,0,0,0,0,0,0)';
      PINUSE='POWER';
      NO_LOAD_CHECK='Both';
      NO_IO_CHECK='Both';
      NO_ASSERT_CHECK='TRUE';
      NO_DIR_CHECK='TRUE';
      ALLOW_CONNECT='TRUE';
    'VCCFA_EHV_FIVRA69':
      PIN_NUMBER='(0,0,0,0,0,0,0,0,0,0,0,0,0,0,0,0,0,0,0,0,0,0,0,0,0,0,0,0,0,EA3~
,0,0,0,0,0,0,0,0,0,0,0,0)';
      PINUSE='POWER';
      NO_LOAD_CHECK='Both';
      NO_IO_CHECK='Both';
      NO_ASSERT_CHECK='TRUE';
      NO_DIR_CHECK='TRUE';
      ALLOW_CONNECT='TRUE';
    'VCCFA_EHV_FIVRA68':
      PIN_NUMBER='(0,0,0,0,0,0,0,0,0,0,0,0,0,0,0,0,0,0,0,0,0,0,0,0,0,0,0,0,0,EA1~
5,0,0,0,0,0,0,0,0,0,0,0,0)';
      PINUSE='POWER';
      NO_LOAD_CHECK='Both';
      NO_IO_CHECK='Both';
      NO_ASSERT_CHECK='TRUE';
      NO_DIR_CHECK='TRUE';
      ALLOW_CONNECT='TRUE';
    'VCCFA_EHV_FIVRA67':
      PIN_NUMBER='(0,0,0,0,0,0,0,0,0,0,0,0,0,0,0,0,0,0,0,0,0,0,0,0,0,0,0,0,0,EA1~
1,0,0,0,0,0,0,0,0,0,0,0,0)';
      PINUSE='POWER';
      NO_LOAD_CHECK='Both';
      NO_IO_CHECK='Both';
      NO_ASSERT_CHECK='TRUE';
      NO_DIR_CHECK='TRUE';
      ALLOW_CONNECT='TRUE';
    'VCCFA_EHV_FIVRA66':
      PIN_NUMBER='(0,0,0,0,0,0,0,0,0,0,0,0,0,0,0,0,0,0,0,0,0,0,0,0,0,0,0,0,0,DY8~
9,0,0,0,0,0,0,0,0,0,0,0,0)';
      PINUSE='POWER';
      NO_LOAD_CHECK='Both';
      NO_IO_CHECK='Both';
      NO_ASSERT_CHECK='TRUE';
      NO_DIR_CHECK='TRUE';
      ALLOW_CONNECT='TRUE';
    'VCCFA_EHV_FIVRA65':
      PIN_NUMBER='(0,0,0,0,0,0,0,0,0,0,0,0,0,0,0,0,0,0,0,0,0,0,0,0,0,0,0,0,0,DY8~
5,0,0,0,0,0,0,0,0,0,0,0,0)';
      PINUSE='POWER';
      NO_LOAD_CHECK='Both';
      NO_IO_CHECK='Both';
      NO_ASSERT_CHECK='TRUE';
      NO_DIR_CHECK='TRUE';
      ALLOW_CONNECT='TRUE';
    'VCCFA_EHV_FIVRA64':
      PIN_NUMBER='(0,0,0,0,0,0,0,0,0,0,0,0,0,0,0,0,0,0,0,0,0,0,0,0,0,0,0,0,0,DU7~
,0,0,0,0,0,0,0,0,0,0,0,0)';
      PINUSE='POWER';
      NO_LOAD_CHECK='Both';
      NO_IO_CHECK='Both';
      NO_ASSERT_CHECK='TRUE';
      NO_DIR_CHECK='TRUE';
      ALLOW_CONNECT='TRUE';
    'VCCFA_EHV_FIVRA63':
      PIN_NUMBER='(0,0,0,0,0,0,0,0,0,0,0,0,0,0,0,0,0,0,0,0,0,0,0,0,0,0,0,0,0,DU3~
,0,0,0,0,0,0,0,0,0,0,0,0)';
      PINUSE='POWER';
      NO_LOAD_CHECK='Both';
      NO_IO_CHECK='Both';
      NO_ASSERT_CHECK='TRUE';
      NO_DIR_CHECK='TRUE';
      ALLOW_CONNECT='TRUE';
    'VCCFA_EHV_FIVRA62':
      PIN_NUMBER='(0,0,0,0,0,0,0,0,0,0,0,0,0,0,0,0,0,0,0,0,0,0,0,0,0,0,0,0,0,DU1~
5,0,0,0,0,0,0,0,0,0,0,0,0)';
      PINUSE='POWER';
      NO_LOAD_CHECK='Both';
      NO_IO_CHECK='Both';
      NO_ASSERT_CHECK='TRUE';
      NO_DIR_CHECK='TRUE';
      ALLOW_CONNECT='TRUE';
    'VCCFA_EHV_FIVRA61':
      PIN_NUMBER='(0,0,0,0,0,0,0,0,0,0,0,0,0,0,0,0,0,0,0,0,0,0,0,0,0,0,0,0,0,DU1~
1,0,0,0,0,0,0,0,0,0,0,0,0)';
      PINUSE='POWER';
      NO_LOAD_CHECK='Both';
      NO_IO_CHECK='Both';
      NO_ASSERT_CHECK='TRUE';
      NO_DIR_CHECK='TRUE';
      ALLOW_CONNECT='TRUE';
    'VCCFA_EHV_FIVRA60':
      PIN_NUMBER='(0,0,0,0,0,0,0,0,0,0,0,0,0,0,0,0,0,0,0,0,0,0,0,0,0,0,0,0,0,DT8~
9,0,0,0,0,0,0,0,0,0,0,0,0)';
      PINUSE='POWER';
      NO_LOAD_CHECK='Both';
      NO_IO_CHECK='Both';
      NO_ASSERT_CHECK='TRUE';
      NO_DIR_CHECK='TRUE';
      ALLOW_CONNECT='TRUE';
    'VCCFA_EHV_FIVRA59':
      PIN_NUMBER='(0,0,0,0,0,0,0,0,0,0,0,0,0,0,0,0,0,0,0,0,0,0,0,0,0,0,0,0,0,DT8~
5,0,0,0,0,0,0,0,0,0,0,0,0)';
      PINUSE='POWER';
      NO_LOAD_CHECK='Both';
      NO_IO_CHECK='Both';
      NO_ASSERT_CHECK='TRUE';
      NO_DIR_CHECK='TRUE';
      ALLOW_CONNECT='TRUE';
    'VCCFA_EHV_FIVRA58':
      PIN_NUMBER='(0,0,0,0,0,0,0,0,0,0,0,0,0,0,0,0,0,0,0,0,0,0,0,0,0,0,0,0,0,DT7~
9,0,0,0,0,0,0,0,0,0,0,0,0)';
      PINUSE='POWER';
      NO_LOAD_CHECK='Both';
      NO_IO_CHECK='Both';
      NO_ASSERT_CHECK='TRUE';
      NO_DIR_CHECK='TRUE';
      ALLOW_CONNECT='TRUE';
    'VCCFA_EHV_FIVRA57':
      PIN_NUMBER='(0,0,0,0,0,0,0,0,0,0,0,0,0,0,0,0,0,0,0,0,0,0,0,0,0,0,0,0,0,DN7~
,0,0,0,0,0,0,0,0,0,0,0,0)';
      PINUSE='POWER';
      NO_LOAD_CHECK='Both';
      NO_IO_CHECK='Both';
      NO_ASSERT_CHECK='TRUE';
      NO_DIR_CHECK='TRUE';
      ALLOW_CONNECT='TRUE';
    'VCCFA_EHV_FIVRA56':
      PIN_NUMBER='(0,0,0,0,0,0,0,0,0,0,0,0,0,0,0,0,0,0,0,0,0,0,0,0,0,0,0,0,0,DN3~
,0,0,0,0,0,0,0,0,0,0,0,0)';
      PINUSE='POWER';
      NO_LOAD_CHECK='Both';
      NO_IO_CHECK='Both';
      NO_ASSERT_CHECK='TRUE';
      NO_DIR_CHECK='TRUE';
      ALLOW_CONNECT='TRUE';
    'VCCFA_EHV_FIVRA55':
      PIN_NUMBER='(0,0,0,0,0,0,0,0,0,0,0,0,0,0,0,0,0,0,0,0,0,0,0,0,0,0,0,0,0,DN1~
5,0,0,0,0,0,0,0,0,0,0,0,0)';
      PINUSE='POWER';
      NO_LOAD_CHECK='Both';
      NO_IO_CHECK='Both';
      NO_ASSERT_CHECK='TRUE';
      NO_DIR_CHECK='TRUE';
      ALLOW_CONNECT='TRUE';
    'VCCFA_EHV_FIVRA54':
      PIN_NUMBER='(0,0,0,0,0,0,0,0,0,0,0,0,0,0,0,0,0,0,0,0,0,0,0,0,0,0,0,0,0,DN1~
1,0,0,0,0,0,0,0,0,0,0,0,0)';
      PINUSE='POWER';
      NO_LOAD_CHECK='Both';
      NO_IO_CHECK='Both';
      NO_ASSERT_CHECK='TRUE';
      NO_DIR_CHECK='TRUE';
      ALLOW_CONNECT='TRUE';
    'VCCFA_EHV_FIVRA53':
      PIN_NUMBER='(0,0,0,0,0,0,0,0,0,0,0,0,0,0,0,0,0,0,0,0,0,0,0,0,0,0,0,0,0,DM8~
9,0,0,0,0,0,0,0,0,0,0,0,0)';
      PINUSE='POWER';
      NO_LOAD_CHECK='Both';
      NO_IO_CHECK='Both';
      NO_ASSERT_CHECK='TRUE';
      NO_DIR_CHECK='TRUE';
      ALLOW_CONNECT='TRUE';
    'VCCFA_EHV_FIVRA52':
      PIN_NUMBER='(0,0,0,0,0,0,0,0,0,0,0,0,0,0,0,0,0,0,0,0,0,0,0,0,0,0,0,0,0,DM8~
5,0,0,0,0,0,0,0,0,0,0,0,0)';
      PINUSE='POWER';
      NO_LOAD_CHECK='Both';
      NO_IO_CHECK='Both';
      NO_ASSERT_CHECK='TRUE';
      NO_DIR_CHECK='TRUE';
      ALLOW_CONNECT='TRUE';
    'VCCFA_EHV_FIVRA51':
      PIN_NUMBER='(0,0,0,0,0,0,0,0,0,0,0,0,0,0,0,0,0,0,0,0,0,0,0,0,0,0,0,0,0,DM8~
3,0,0,0,0,0,0,0,0,0,0,0,0)';
      PINUSE='POWER';
      NO_LOAD_CHECK='Both';
      NO_IO_CHECK='Both';
      NO_ASSERT_CHECK='TRUE';
      NO_DIR_CHECK='TRUE';
      ALLOW_CONNECT='TRUE';
    'VCCFA_EHV_FIVRA50':
      PIN_NUMBER='(0,0,0,0,0,0,0,0,0,0,0,0,0,0,0,0,0,0,0,0,0,0,0,0,0,0,0,0,0,DH8~
9,0,0,0,0,0,0,0,0,0,0,0,0)';
      PINUSE='POWER';
      NO_LOAD_CHECK='Both';
      NO_IO_CHECK='Both';
      NO_ASSERT_CHECK='TRUE';
      NO_DIR_CHECK='TRUE';
      ALLOW_CONNECT='TRUE';
    'VCCFA_EHV_FIVRA49':
      PIN_NUMBER='(0,0,0,0,0,0,0,0,0,0,0,0,0,0,0,0,0,0,0,0,0,0,0,0,0,0,0,0,0,DD8~
9,0,0,0,0,0,0,0,0,0,0,0,0)';
      PINUSE='POWER';
      NO_LOAD_CHECK='Both';
      NO_IO_CHECK='Both';
      NO_ASSERT_CHECK='TRUE';
      NO_DIR_CHECK='TRUE';
      ALLOW_CONNECT='TRUE';
    'VCCFA_EHV_FIVRA48':
      PIN_NUMBER='(0,0,0,0,0,0,0,0,0,0,0,0,0,0,0,0,0,0,0,0,0,0,0,0,0,0,0,0,0,DD8~
5,0,0,0,0,0,0,0,0,0,0,0,0)';
      PINUSE='POWER';
      NO_LOAD_CHECK='Both';
      NO_IO_CHECK='Both';
      NO_ASSERT_CHECK='TRUE';
      NO_DIR_CHECK='TRUE';
      ALLOW_CONNECT='TRUE';
    'VCCFA_EHV_FIVRA47':
      PIN_NUMBER='(0,0,0,0,0,0,0,0,0,0,0,0,0,0,0,0,0,0,0,0,0,0,0,0,0,0,0,0,0,DD8~
3,0,0,0,0,0,0,0,0,0,0,0,0)';
      PINUSE='POWER';
      NO_LOAD_CHECK='Both';
      NO_IO_CHECK='Both';
      NO_ASSERT_CHECK='TRUE';
      NO_DIR_CHECK='TRUE';
      ALLOW_CONNECT='TRUE';
    'VCCFA_EHV_FIVRA46':
      PIN_NUMBER='(0,0,0,0,0,0,0,0,0,0,0,0,0,0,0,0,0,0,0,0,0,0,0,0,0,0,0,0,0,DD7~
7,0,0,0,0,0,0,0,0,0,0,0,0)';
      PINUSE='POWER';
      NO_LOAD_CHECK='Both';
      NO_IO_CHECK='Both';
      NO_ASSERT_CHECK='TRUE';
      NO_DIR_CHECK='TRUE';
      ALLOW_CONNECT='TRUE';
    'VCCFA_EHV_FIVRA45':
      PIN_NUMBER='(0,0,0,0,0,0,0,0,0,0,0,0,0,0,0,0,0,0,0,0,0,0,0,0,0,0,0,0,0,CY8~
9,0,0,0,0,0,0,0,0,0,0,0,0)';
      PINUSE='POWER';
      NO_LOAD_CHECK='Both';
      NO_IO_CHECK='Both';
      NO_ASSERT_CHECK='TRUE';
      NO_DIR_CHECK='TRUE';
      ALLOW_CONNECT='TRUE';
    'VCCFA_EHV_FIVRA44':
      PIN_NUMBER='(0,0,0,0,0,0,0,0,0,0,0,0,0,0,0,0,0,0,0,0,0,0,0,0,0,0,0,0,0,CY8~
5,0,0,0,0,0,0,0,0,0,0,0,0)';
      PINUSE='POWER';
      NO_LOAD_CHECK='Both';
      NO_IO_CHECK='Both';
      NO_ASSERT_CHECK='TRUE';
      NO_DIR_CHECK='TRUE';
      ALLOW_CONNECT='TRUE';
    'VCCFA_EHV_FIVRA43':
      PIN_NUMBER='(0,0,0,0,0,0,0,0,0,0,0,0,0,0,0,0,0,0,0,0,0,0,0,0,0,0,0,0,0,CY7~
9,0,0,0,0,0,0,0,0,0,0,0,0)';
      PINUSE='POWER';
      NO_LOAD_CHECK='Both';
      NO_IO_CHECK='Both';
      NO_ASSERT_CHECK='TRUE';
      NO_DIR_CHECK='TRUE';
      ALLOW_CONNECT='TRUE';
    'VCCFA_EHV_FIVRA42':
      PIN_NUMBER='(0,0,0,0,0,0,0,0,0,0,0,0,0,0,0,0,0,0,0,0,0,0,0,0,0,0,0,0,0,CY7~
5,0,0,0,0,0,0,0,0,0,0,0,0)';
      PINUSE='POWER';
      NO_LOAD_CHECK='Both';
      NO_IO_CHECK='Both';
      NO_ASSERT_CHECK='TRUE';
      NO_DIR_CHECK='TRUE';
      ALLOW_CONNECT='TRUE';
    'VCCFA_EHV_FIVRA41':
      PIN_NUMBER='(0,0,0,0,0,0,0,0,0,0,0,0,0,0,0,0,0,0,0,0,0,0,0,0,0,0,0,0,0,CT8~
5,0,0,0,0,0,0,0,0,0,0,0,0)';
      PINUSE='POWER';
      NO_LOAD_CHECK='Both';
      NO_IO_CHECK='Both';
      NO_ASSERT_CHECK='TRUE';
      NO_DIR_CHECK='TRUE';
      ALLOW_CONNECT='TRUE';
    'VCCFA_EHV_FIVRA40':
      PIN_NUMBER='(0,0,0,0,0,0,0,0,0,0,0,0,0,0,0,0,0,0,0,0,0,0,0,0,0,0,0,0,0,CT7~
7,0,0,0,0,0,0,0,0,0,0,0,0)';
      PINUSE='POWER';
      NO_LOAD_CHECK='Both';
      NO_IO_CHECK='Both';
      NO_ASSERT_CHECK='TRUE';
      NO_DIR_CHECK='TRUE';
      ALLOW_CONNECT='TRUE';
    'VCCFA_EHV_FIVRA39':
      PIN_NUMBER='(0,0,0,0,0,0,0,0,0,0,0,0,0,0,0,0,0,0,0,0,0,0,0,0,0,0,0,0,0,CP7~
3,0,0,0,0,0,0,0,0,0,0,0,0)';
      PINUSE='POWER';
      NO_LOAD_CHECK='Both';
      NO_IO_CHECK='Both';
      NO_ASSERT_CHECK='TRUE';
      NO_DIR_CHECK='TRUE';
      ALLOW_CONNECT='TRUE';
    'VCCFA_EHV_FIVRA38':
      PIN_NUMBER='(0,0,0,0,0,0,0,0,0,0,0,0,0,0,0,0,0,0,0,0,0,0,0,0,0,0,0,0,0,CN7~
8,0,0,0,0,0,0,0,0,0,0,0,0)';
      PINUSE='POWER';
      NO_LOAD_CHECK='Both';
      NO_IO_CHECK='Both';
      NO_ASSERT_CHECK='TRUE';
      NO_DIR_CHECK='TRUE';
      ALLOW_CONNECT='TRUE';
    'VCCFA_EHV_FIVRA37':
      PIN_NUMBER='(0,0,0,0,0,0,0,0,0,0,0,0,0,0,0,0,0,0,0,0,0,0,0,0,0,0,0,0,0,CM7~
3,0,0,0,0,0,0,0,0,0,0,0,0)';
      PINUSE='POWER';
      NO_LOAD_CHECK='Both';
      NO_IO_CHECK='Both';
      NO_ASSERT_CHECK='TRUE';
      NO_DIR_CHECK='TRUE';
      ALLOW_CONNECT='TRUE';
    'VCCFA_EHV_FIVRA36':
      PIN_NUMBER='(0,0,0,0,0,0,0,0,0,0,0,0,0,0,0,0,0,0,0,0,0,0,0,0,0,0,0,0,0,CK7~
9,0,0,0,0,0,0,0,0,0,0,0,0)';
      PINUSE='POWER';
      NO_LOAD_CHECK='Both';
      NO_IO_CHECK='Both';
      NO_ASSERT_CHECK='TRUE';
      NO_DIR_CHECK='TRUE';
      ALLOW_CONNECT='TRUE';
    'VCCFA_EHV_FIVRA35':
      PIN_NUMBER='(0,0,0,0,0,0,0,0,0,0,0,0,0,0,0,0,0,0,0,0,0,0,0,0,0,0,0,0,0,CK7~
3,0,0,0,0,0,0,0,0,0,0,0,0)';
      PINUSE='POWER';
      NO_LOAD_CHECK='Both';
      NO_IO_CHECK='Both';
      NO_ASSERT_CHECK='TRUE';
      NO_DIR_CHECK='TRUE';
      ALLOW_CONNECT='TRUE';
    'VCCFA_EHV_FIVRA34':
      PIN_NUMBER='(0,0,0,0,0,0,0,0,0,0,0,0,0,0,0,0,0,0,0,0,0,0,0,0,0,0,0,0,0,CE7~
4,0,0,0,0,0,0,0,0,0,0,0,0)';
      PINUSE='POWER';
      NO_LOAD_CHECK='Both';
      NO_IO_CHECK='Both';
      NO_ASSERT_CHECK='TRUE';
      NO_DIR_CHECK='TRUE';
      ALLOW_CONNECT='TRUE';
    'VCCFA_EHV_FIVRA33':
      PIN_NUMBER='(0,0,0,0,0,0,0,0,0,0,0,0,0,0,0,0,0,0,0,0,0,0,0,0,0,0,0,0,0,C88~
,0,0,0,0,0,0,0,0,0,0,0,0)';
      PINUSE='POWER';
      NO_LOAD_CHECK='Both';
      NO_IO_CHECK='Both';
      NO_ASSERT_CHECK='TRUE';
      NO_DIR_CHECK='TRUE';
      ALLOW_CONNECT='TRUE';
    'VCCFA_EHV_FIVRA32':
      PIN_NUMBER='(0,0,0,0,0,0,0,0,0,0,0,0,0,0,0,0,0,0,0,0,0,0,0,0,0,0,0,0,0,C84~
,0,0,0,0,0,0,0,0,0,0,0,0)';
      PINUSE='POWER';
      NO_LOAD_CHECK='Both';
      NO_IO_CHECK='Both';
      NO_ASSERT_CHECK='TRUE';
      NO_DIR_CHECK='TRUE';
      ALLOW_CONNECT='TRUE';
    'VCCFA_EHV_FIVRA31':
      PIN_NUMBER='(0,0,0,0,0,0,0,0,0,0,0,0,0,0,0,0,0,0,0,0,0,0,0,0,0,0,0,0,0,BJ7~
8,0,0,0,0,0,0,0,0,0,0,0,0)';
      PINUSE='POWER';
      NO_LOAD_CHECK='Both';
      NO_IO_CHECK='Both';
      NO_ASSERT_CHECK='TRUE';
      NO_DIR_CHECK='TRUE';
      ALLOW_CONNECT='TRUE';
    'VCCFA_EHV_FIVRA30':
      PIN_NUMBER='(0,0,0,0,0,0,0,0,0,0,0,0,0,0,0,0,0,0,0,0,0,0,0,0,0,0,0,0,0,BJ7~
2,0,0,0,0,0,0,0,0,0,0,0,0)';
      PINUSE='POWER';
      NO_LOAD_CHECK='Both';
      NO_IO_CHECK='Both';
      NO_ASSERT_CHECK='TRUE';
      NO_DIR_CHECK='TRUE';
      ALLOW_CONNECT='TRUE';
    'VCCFA_EHV_FIVRA29':
      PIN_NUMBER='(0,0,0,0,0,0,0,0,0,0,0,0,0,0,0,0,0,0,0,0,0,0,0,0,0,0,0,0,0,BH7~
9,0,0,0,0,0,0,0,0,0,0,0,0)';
      PINUSE='POWER';
      NO_LOAD_CHECK='Both';
      NO_IO_CHECK='Both';
      NO_ASSERT_CHECK='TRUE';
      NO_DIR_CHECK='TRUE';
      ALLOW_CONNECT='TRUE';
    'VCCFA_EHV_FIVRA28':
      PIN_NUMBER='(0,0,0,0,0,0,0,0,0,0,0,0,0,0,0,0,0,0,0,0,0,0,0,0,0,0,0,0,0,BF7~
7,0,0,0,0,0,0,0,0,0,0,0,0)';
      PINUSE='POWER';
      NO_LOAD_CHECK='Both';
      NO_IO_CHECK='Both';
      NO_ASSERT_CHECK='TRUE';
      NO_DIR_CHECK='TRUE';
      ALLOW_CONNECT='TRUE';
    'VCCFA_EHV_FIVRA27':
      PIN_NUMBER='(0,0,0,0,0,0,0,0,0,0,0,0,0,0,0,0,0,0,0,0,0,0,0,0,0,0,0,0,0,BE7~
2,0,0,0,0,0,0,0,0,0,0,0,0)';
      PINUSE='POWER';
      NO_LOAD_CHECK='Both';
      NO_IO_CHECK='Both';
      NO_ASSERT_CHECK='TRUE';
      NO_DIR_CHECK='TRUE';
      ALLOW_CONNECT='TRUE';
    'VCCFA_EHV_FIVRA26':
      PIN_NUMBER='(0,0,0,0,0,0,0,0,0,0,0,0,0,0,0,0,0,0,0,0,0,0,0,0,0,0,0,0,0,AY8~
9,0,0,0,0,0,0,0,0,0,0,0,0)';
      PINUSE='POWER';
      NO_LOAD_CHECK='Both';
      NO_IO_CHECK='Both';
      NO_ASSERT_CHECK='TRUE';
      NO_DIR_CHECK='TRUE';
      ALLOW_CONNECT='TRUE';
    'VCCFA_EHV_FIVRA25':
      PIN_NUMBER='(0,0,0,0,0,0,0,0,0,0,0,0,0,0,0,0,0,0,0,0,0,0,0,0,0,0,0,0,0,AW7~
6,0,0,0,0,0,0,0,0,0,0,0,0)';
      PINUSE='POWER';
      NO_LOAD_CHECK='Both';
      NO_IO_CHECK='Both';
      NO_ASSERT_CHECK='TRUE';
      NO_DIR_CHECK='TRUE';
      ALLOW_CONNECT='TRUE';
    'VCCFA_EHV_FIVRA24':
      PIN_NUMBER='(0,0,0,0,0,0,0,0,0,0,0,0,0,0,0,0,0,0,0,0,0,0,0,0,0,0,0,0,0,AU1~
5,0,0,0,0,0,0,0,0,0,0,0,0)';
      PINUSE='POWER';
      NO_LOAD_CHECK='Both';
      NO_IO_CHECK='Both';
      NO_ASSERT_CHECK='TRUE';
      NO_DIR_CHECK='TRUE';
      ALLOW_CONNECT='TRUE';
    'VCCFA_EHV_FIVRA23':
      PIN_NUMBER='(0,0,0,0,0,0,0,0,0,0,0,0,0,0,0,0,0,0,0,0,0,0,0,0,0,0,0,0,0,AT8~
9,0,0,0,0,0,0,0,0,0,0,0,0)';
      PINUSE='POWER';
      NO_LOAD_CHECK='Both';
      NO_IO_CHECK='Both';
      NO_ASSERT_CHECK='TRUE';
      NO_DIR_CHECK='TRUE';
      ALLOW_CONNECT='TRUE';
    'VCCFA_EHV_FIVRA22':
      PIN_NUMBER='(0,0,0,0,0,0,0,0,0,0,0,0,0,0,0,0,0,0,0,0,0,0,0,0,0,0,0,0,0,AT7~
3,0,0,0,0,0,0,0,0,0,0,0,0)';
      PINUSE='POWER';
      NO_LOAD_CHECK='Both';
      NO_IO_CHECK='Both';
      NO_ASSERT_CHECK='TRUE';
      NO_DIR_CHECK='TRUE';
      ALLOW_CONNECT='TRUE';
    'VCCFA_EHV_FIVRA21':
      PIN_NUMBER='(0,0,0,0,0,0,0,0,0,0,0,0,0,0,0,0,0,0,0,0,0,0,0,0,0,0,0,0,0,AN8~
0,0,0,0,0,0,0,0,0,0,0,0,0)';
      PINUSE='POWER';
      NO_LOAD_CHECK='Both';
      NO_IO_CHECK='Both';
      NO_ASSERT_CHECK='TRUE';
      NO_DIR_CHECK='TRUE';
      ALLOW_CONNECT='TRUE';
    'VCCFA_EHV_FIVRA20':
      PIN_NUMBER='(0,0,0,0,0,0,0,0,0,0,0,0,0,0,0,0,0,0,0,0,0,0,0,0,0,0,0,0,0,AN7~
,0,0,0,0,0,0,0,0,0,0,0,0)';
      PINUSE='POWER';
      NO_LOAD_CHECK='Both';
      NO_IO_CHECK='Both';
      NO_ASSERT_CHECK='TRUE';
      NO_DIR_CHECK='TRUE';
      ALLOW_CONNECT='TRUE';
    'VCCFA_EHV_FIVRA19':
      PIN_NUMBER='(0,0,0,0,0,0,0,0,0,0,0,0,0,0,0,0,0,0,0,0,0,0,0,0,0,0,0,0,0,AN1~
5,0,0,0,0,0,0,0,0,0,0,0,0)';
      PINUSE='POWER';
      NO_LOAD_CHECK='Both';
      NO_IO_CHECK='Both';
      NO_ASSERT_CHECK='TRUE';
      NO_DIR_CHECK='TRUE';
      ALLOW_CONNECT='TRUE';
    'VCCFA_EHV_FIVRA18':
      PIN_NUMBER='(0,0,0,0,0,0,0,0,0,0,0,0,0,0,0,0,0,0,0,0,0,0,0,0,0,0,0,0,0,AN1~
1,0,0,0,0,0,0,0,0,0,0,0,0)';
      PINUSE='POWER';
      NO_LOAD_CHECK='Both';
      NO_IO_CHECK='Both';
      NO_ASSERT_CHECK='TRUE';
      NO_DIR_CHECK='TRUE';
      ALLOW_CONNECT='TRUE';
    'VCCFA_EHV_FIVRA17':
      PIN_NUMBER='(0,0,0,0,0,0,0,0,0,0,0,0,0,0,0,0,0,0,0,0,0,0,0,0,0,0,0,0,0,AM8~
9,0,0,0,0,0,0,0,0,0,0,0,0)';
      PINUSE='POWER';
      NO_LOAD_CHECK='Both';
      NO_IO_CHECK='Both';
      NO_ASSERT_CHECK='TRUE';
      NO_DIR_CHECK='TRUE';
      ALLOW_CONNECT='TRUE';
    'VCCFA_EHV_FIVRA16':
      PIN_NUMBER='(0,0,0,0,0,0,0,0,0,0,0,0,0,0,0,0,0,0,0,0,0,0,0,0,0,0,0,0,0,AM8~
5,0,0,0,0,0,0,0,0,0,0,0,0)';
      PINUSE='POWER';
      NO_LOAD_CHECK='Both';
      NO_IO_CHECK='Both';
      NO_ASSERT_CHECK='TRUE';
      NO_DIR_CHECK='TRUE';
      ALLOW_CONNECT='TRUE';
    'VCCFA_EHV_FIVRA15':
      PIN_NUMBER='(0,0,0,0,0,0,0,0,0,0,0,0,0,0,0,0,0,0,0,0,0,0,0,0,0,0,0,0,0,AM7~
9,0,0,0,0,0,0,0,0,0,0,0,0)';
      PINUSE='POWER';
      NO_LOAD_CHECK='Both';
      NO_IO_CHECK='Both';
      NO_ASSERT_CHECK='TRUE';
      NO_DIR_CHECK='TRUE';
      ALLOW_CONNECT='TRUE';
    'VCCFA_EHV_FIVRA14':
      PIN_NUMBER='(0,0,0,0,0,0,0,0,0,0,0,0,0,0,0,0,0,0,0,0,0,0,0,0,0,0,0,0,0,AJ7~
,0,0,0,0,0,0,0,0,0,0,0,0)';
      PINUSE='POWER';
      NO_LOAD_CHECK='Both';
      NO_IO_CHECK='Both';
      NO_ASSERT_CHECK='TRUE';
      NO_DIR_CHECK='TRUE';
      ALLOW_CONNECT='TRUE';
    'VCCFA_EHV_FIVRA13':
      PIN_NUMBER='(0,0,0,0,0,0,0,0,0,0,0,0,0,0,0,0,0,0,0,0,0,0,0,0,0,0,0,0,0,AJ1~
5,0,0,0,0,0,0,0,0,0,0,0,0)';
      PINUSE='POWER';
      NO_LOAD_CHECK='Both';
      NO_IO_CHECK='Both';
      NO_ASSERT_CHECK='TRUE';
      NO_DIR_CHECK='TRUE';
      ALLOW_CONNECT='TRUE';
    'VCCFA_EHV_FIVRA12':
      PIN_NUMBER='(0,0,0,0,0,0,0,0,0,0,0,0,0,0,0,0,0,0,0,0,0,0,0,0,0,0,0,0,0,AJ1~
1,0,0,0,0,0,0,0,0,0,0,0,0)';
      PINUSE='POWER';
      NO_LOAD_CHECK='Both';
      NO_IO_CHECK='Both';
      NO_ASSERT_CHECK='TRUE';
      NO_DIR_CHECK='TRUE';
      ALLOW_CONNECT='TRUE';
    'VCCFA_EHV_FIVRA11':
      PIN_NUMBER='(0,0,0,0,0,0,0,0,0,0,0,0,0,0,0,0,0,0,0,0,0,0,0,0,0,0,0,0,0,AH8~
9,0,0,0,0,0,0,0,0,0,0,0,0)';
      PINUSE='POWER';
      NO_LOAD_CHECK='Both';
      NO_IO_CHECK='Both';
      NO_ASSERT_CHECK='TRUE';
      NO_DIR_CHECK='TRUE';
      ALLOW_CONNECT='TRUE';
    'VCCFA_EHV_FIVRA10':
      PIN_NUMBER='(0,0,0,0,0,0,0,0,0,0,0,0,0,0,0,0,0,0,0,0,0,0,0,0,0,0,0,0,0,AH8~
5,0,0,0,0,0,0,0,0,0,0,0,0)';
      PINUSE='POWER';
      NO_LOAD_CHECK='Both';
      NO_IO_CHECK='Both';
      NO_ASSERT_CHECK='TRUE';
      NO_DIR_CHECK='TRUE';
      ALLOW_CONNECT='TRUE';
    'VCCFA_EHV_FIVRA9':
      PIN_NUMBER='(0,0,0,0,0,0,0,0,0,0,0,0,0,0,0,0,0,0,0,0,0,0,0,0,0,0,0,0,0,AG7~
8,0,0,0,0,0,0,0,0,0,0,0,0)';
      PINUSE='POWER';
      NO_LOAD_CHECK='Both';
      NO_IO_CHECK='Both';
      NO_ASSERT_CHECK='TRUE';
      NO_DIR_CHECK='TRUE';
      ALLOW_CONNECT='TRUE';
    'VCCFA_EHV_FIVRA8':
      PIN_NUMBER='(0,0,0,0,0,0,0,0,0,0,0,0,0,0,0,0,0,0,0,0,0,0,0,0,0,0,0,0,0,AF7~
7,0,0,0,0,0,0,0,0,0,0,0,0)';
      PINUSE='POWER';
      NO_LOAD_CHECK='Both';
      NO_IO_CHECK='Both';
      NO_ASSERT_CHECK='TRUE';
      NO_DIR_CHECK='TRUE';
      ALLOW_CONNECT='TRUE';
    'VCCFA_EHV_FIVRA7':
      PIN_NUMBER='(0,0,0,0,0,0,0,0,0,0,0,0,0,0,0,0,0,0,0,0,0,0,0,0,0,0,0,0,0,AE7~
,0,0,0,0,0,0,0,0,0,0,0,0)';
      PINUSE='POWER';
      NO_LOAD_CHECK='Both';
      NO_IO_CHECK='Both';
      NO_ASSERT_CHECK='TRUE';
      NO_DIR_CHECK='TRUE';
      ALLOW_CONNECT='TRUE';
    'VCCFA_EHV_FIVRA6':
      PIN_NUMBER='(0,0,0,0,0,0,0,0,0,0,0,0,0,0,0,0,0,0,0,0,0,0,0,0,0,0,0,0,0,AE1~
5,0,0,0,0,0,0,0,0,0,0,0,0)';
      PINUSE='POWER';
      NO_LOAD_CHECK='Both';
      NO_IO_CHECK='Both';
      NO_ASSERT_CHECK='TRUE';
      NO_DIR_CHECK='TRUE';
      ALLOW_CONNECT='TRUE';
    'VCCFA_EHV_FIVRA5':
      PIN_NUMBER='(0,0,0,0,0,0,0,0,0,0,0,0,0,0,0,0,0,0,0,0,0,0,0,0,0,0,0,0,0,AE1~
1,0,0,0,0,0,0,0,0,0,0,0,0)';
      PINUSE='POWER';
      NO_LOAD_CHECK='Both';
      NO_IO_CHECK='Both';
      NO_ASSERT_CHECK='TRUE';
      NO_DIR_CHECK='TRUE';
      ALLOW_CONNECT='TRUE';
    'VCCFA_EHV_FIVRA4':
      PIN_NUMBER='(0,0,0,0,0,0,0,0,0,0,0,0,0,0,0,0,0,0,0,0,0,0,0,0,0,0,0,0,0,AD8~
9,0,0,0,0,0,0,0,0,0,0,0,0)';
      PINUSE='POWER';
      NO_LOAD_CHECK='Both';
      NO_IO_CHECK='Both';
      NO_ASSERT_CHECK='TRUE';
      NO_DIR_CHECK='TRUE';
      ALLOW_CONNECT='TRUE';
    'VCCFA_EHV_FIVRA3':
      PIN_NUMBER='(0,0,0,0,0,0,0,0,0,0,0,0,0,0,0,0,0,0,0,0,0,0,0,0,0,0,0,0,0,AD8~
5,0,0,0,0,0,0,0,0,0,0,0,0)';
      PINUSE='POWER';
      NO_LOAD_CHECK='Both';
      NO_IO_CHECK='Both';
      NO_ASSERT_CHECK='TRUE';
      NO_DIR_CHECK='TRUE';
      ALLOW_CONNECT='TRUE';
    'VCCFA_EHV_FIVRA2':
      PIN_NUMBER='(0,0,0,0,0,0,0,0,0,0,0,0,0,0,0,0,0,0,0,0,0,0,0,0,0,0,0,0,0,AA7~
,0,0,0,0,0,0,0,0,0,0,0,0)';
      PINUSE='POWER';
      NO_LOAD_CHECK='Both';
      NO_IO_CHECK='Both';
      NO_ASSERT_CHECK='TRUE';
      NO_DIR_CHECK='TRUE';
      ALLOW_CONNECT='TRUE';
    'VCCFA_EHV_FIVRA1':
      PIN_NUMBER='(0,0,0,0,0,0,0,0,0,0,0,0,0,0,0,0,0,0,0,0,0,0,0,0,0,0,0,0,0,AA1~
5,0,0,0,0,0,0,0,0,0,0,0,0)';
      PINUSE='POWER';
      NO_LOAD_CHECK='Both';
      NO_IO_CHECK='Both';
      NO_ASSERT_CHECK='TRUE';
      NO_DIR_CHECK='TRUE';
      ALLOW_CONNECT='TRUE';
    'VCCFA_EHV_FIVRA0':
      PIN_NUMBER='(0,0,0,0,0,0,0,0,0,0,0,0,0,0,0,0,0,0,0,0,0,0,0,0,0,0,0,0,0,AA1~
1,0,0,0,0,0,0,0,0,0,0,0,0)';
      PINUSE='POWER';
      NO_LOAD_CHECK='Both';
      NO_IO_CHECK='Both';
      NO_ASSERT_CHECK='TRUE';
      NO_DIR_CHECK='TRUE';
      ALLOW_CONNECT='TRUE';
    'VSS1834':
      PIN_NUMBER='(0,0,0,0,0,0,0,0,0,0,0,0,0,0,0,0,0,0,0,0,0,0,0,0,0,0,0,0,0,0,E~
R41,0,0,0,0,0,0,0,0,0,0,0)';
      PINUSE='POWER';
      NO_LOAD_CHECK='Both';
      NO_IO_CHECK='Both';
      NO_ASSERT_CHECK='TRUE';
      NO_DIR_CHECK='TRUE';
      ALLOW_CONNECT='TRUE';
    'VSS1835':
      PIN_NUMBER='(0,0,0,0,0,0,0,0,0,0,0,0,0,0,0,0,0,0,0,0,0,0,0,0,0,0,0,0,0,0,E~
R43,0,0,0,0,0,0,0,0,0,0,0)';
      PINUSE='POWER';
      NO_LOAD_CHECK='Both';
      NO_IO_CHECK='Both';
      NO_ASSERT_CHECK='TRUE';
      NO_DIR_CHECK='TRUE';
      ALLOW_CONNECT='TRUE';
    'VSS1836':
      PIN_NUMBER='(0,0,0,0,0,0,0,0,0,0,0,0,0,0,0,0,0,0,0,0,0,0,0,0,0,0,0,0,0,0,E~
R48,0,0,0,0,0,0,0,0,0,0,0)';
      PINUSE='POWER';
      NO_LOAD_CHECK='Both';
      NO_IO_CHECK='Both';
      NO_ASSERT_CHECK='TRUE';
      NO_DIR_CHECK='TRUE';
      ALLOW_CONNECT='TRUE';
    'VSS1837':
      PIN_NUMBER='(0,0,0,0,0,0,0,0,0,0,0,0,0,0,0,0,0,0,0,0,0,0,0,0,0,0,0,0,0,0,E~
R50,0,0,0,0,0,0,0,0,0,0,0)';
      PINUSE='POWER';
      NO_LOAD_CHECK='Both';
      NO_IO_CHECK='Both';
      NO_ASSERT_CHECK='TRUE';
      NO_DIR_CHECK='TRUE';
      ALLOW_CONNECT='TRUE';
    'VSS1569':
      PIN_NUMBER='(0,0,0,0,0,0,0,0,0,0,0,0,0,0,0,0,0,0,0,0,0,0,0,0,0,0,0,0,0,0,E~
T57,0,0,0,0,0,0,0,0,0,0,0)';
      PINUSE='POWER';
      NO_LOAD_CHECK='Both';
      NO_IO_CHECK='Both';
      NO_ASSERT_CHECK='TRUE';
      NO_DIR_CHECK='TRUE';
      ALLOW_CONNECT='TRUE';
    'VSS1565':
      PIN_NUMBER='(0,0,0,0,0,0,0,0,0,0,0,0,0,0,0,0,0,0,0,0,0,0,0,0,0,0,0,0,0,0,E~
T38,0,0,0,0,0,0,0,0,0,0,0)';
      PINUSE='POWER';
      NO_LOAD_CHECK='Both';
      NO_IO_CHECK='Both';
      NO_ASSERT_CHECK='TRUE';
      NO_DIR_CHECK='TRUE';
      ALLOW_CONNECT='TRUE';
    'VSS1563':
      PIN_NUMBER='(0,0,0,0,0,0,0,0,0,0,0,0,0,0,0,0,0,0,0,0,0,0,0,0,0,0,0,0,0,0,E~
T34,0,0,0,0,0,0,0,0,0,0,0)';
      PINUSE='POWER';
      NO_LOAD_CHECK='Both';
      NO_IO_CHECK='Both';
      NO_ASSERT_CHECK='TRUE';
      NO_DIR_CHECK='TRUE';
      ALLOW_CONNECT='TRUE';
    'VSS1562':
      PIN_NUMBER='(0,0,0,0,0,0,0,0,0,0,0,0,0,0,0,0,0,0,0,0,0,0,0,0,0,0,0,0,0,0,E~
T28,0,0,0,0,0,0,0,0,0,0,0)';
      PINUSE='POWER';
      NO_LOAD_CHECK='Both';
      NO_IO_CHECK='Both';
      NO_ASSERT_CHECK='TRUE';
      NO_DIR_CHECK='TRUE';
      ALLOW_CONNECT='TRUE';
    'VSS1561':
      PIN_NUMBER='(0,0,0,0,0,0,0,0,0,0,0,0,0,0,0,0,0,0,0,0,0,0,0,0,0,0,0,0,0,0,E~
T22,0,0,0,0,0,0,0,0,0,0,0)';
      PINUSE='POWER';
      NO_LOAD_CHECK='Both';
      NO_IO_CHECK='Both';
      NO_ASSERT_CHECK='TRUE';
      NO_DIR_CHECK='TRUE';
      ALLOW_CONNECT='TRUE';
    'VSS1559':
      PIN_NUMBER='(0,0,0,0,0,0,0,0,0,0,0,0,0,0,0,0,0,0,0,0,0,0,0,0,0,0,0,0,0,0,E~
T16,0,0,0,0,0,0,0,0,0,0,0)';
      PINUSE='POWER';
      NO_LOAD_CHECK='Both';
      NO_IO_CHECK='Both';
      NO_ASSERT_CHECK='TRUE';
      NO_DIR_CHECK='TRUE';
      ALLOW_CONNECT='TRUE';
    'VSS1557':
      PIN_NUMBER='(0,0,0,0,0,0,0,0,0,0,0,0,0,0,0,0,0,0,0,0,0,0,0,0,0,0,0,0,0,0,E~
T10,0,0,0,0,0,0,0,0,0,0,0)';
      PINUSE='POWER';
      NO_LOAD_CHECK='Both';
      NO_IO_CHECK='Both';
      NO_ASSERT_CHECK='TRUE';
      NO_DIR_CHECK='TRUE';
      ALLOW_CONNECT='TRUE';
    'VSS1556':
      PIN_NUMBER='(0,0,0,0,0,0,0,0,0,0,0,0,0,0,0,0,0,0,0,0,0,0,0,0,0,0,0,0,0,0,E~
R86,0,0,0,0,0,0,0,0,0,0,0)';
      PINUSE='POWER';
      NO_LOAD_CHECK='Both';
      NO_IO_CHECK='Both';
      NO_ASSERT_CHECK='TRUE';
      NO_DIR_CHECK='TRUE';
      ALLOW_CONNECT='TRUE';
    'VSS1555':
      PIN_NUMBER='(0,0,0,0,0,0,0,0,0,0,0,0,0,0,0,0,0,0,0,0,0,0,0,0,0,0,0,0,0,0,E~
R84,0,0,0,0,0,0,0,0,0,0,0)';
      PINUSE='POWER';
      NO_LOAD_CHECK='Both';
      NO_IO_CHECK='Both';
      NO_ASSERT_CHECK='TRUE';
      NO_DIR_CHECK='TRUE';
      ALLOW_CONNECT='TRUE';
    'VSS1554':
      PIN_NUMBER='(0,0,0,0,0,0,0,0,0,0,0,0,0,0,0,0,0,0,0,0,0,0,0,0,0,0,0,0,0,0,E~
R80,0,0,0,0,0,0,0,0,0,0,0)';
      PINUSE='POWER';
      NO_LOAD_CHECK='Both';
      NO_IO_CHECK='Both';
      NO_ASSERT_CHECK='TRUE';
      NO_DIR_CHECK='TRUE';
      ALLOW_CONNECT='TRUE';
    'VSS1553':
      PIN_NUMBER='(0,0,0,0,0,0,0,0,0,0,0,0,0,0,0,0,0,0,0,0,0,0,0,0,0,0,0,0,0,0,E~
R78,0,0,0,0,0,0,0,0,0,0,0)';
      PINUSE='POWER';
      NO_LOAD_CHECK='Both';
      NO_IO_CHECK='Both';
      NO_ASSERT_CHECK='TRUE';
      NO_DIR_CHECK='TRUE';
      ALLOW_CONNECT='TRUE';
    'VSS1552':
      PIN_NUMBER='(0,0,0,0,0,0,0,0,0,0,0,0,0,0,0,0,0,0,0,0,0,0,0,0,0,0,0,0,0,0,E~
R74,0,0,0,0,0,0,0,0,0,0,0)';
      PINUSE='POWER';
      NO_LOAD_CHECK='Both';
      NO_IO_CHECK='Both';
      NO_ASSERT_CHECK='TRUE';
      NO_DIR_CHECK='TRUE';
      ALLOW_CONNECT='TRUE';
    'VSS1551':
      PIN_NUMBER='(0,0,0,0,0,0,0,0,0,0,0,0,0,0,0,0,0,0,0,0,0,0,0,0,0,0,0,0,0,0,E~
R70,0,0,0,0,0,0,0,0,0,0,0)';
      PINUSE='POWER';
      NO_LOAD_CHECK='Both';
      NO_IO_CHECK='Both';
      NO_ASSERT_CHECK='TRUE';
      NO_DIR_CHECK='TRUE';
      ALLOW_CONNECT='TRUE';
    'VSS1550':
      PIN_NUMBER='(0,0,0,0,0,0,0,0,0,0,0,0,0,0,0,0,0,0,0,0,0,0,0,0,0,0,0,0,0,0,E~
R7,0,0,0,0,0,0,0,0,0,0,0)';
      PINUSE='POWER';
      NO_LOAD_CHECK='Both';
      NO_IO_CHECK='Both';
      NO_ASSERT_CHECK='TRUE';
      NO_DIR_CHECK='TRUE';
      ALLOW_CONNECT='TRUE';
    'VSS1549':
      PIN_NUMBER='(0,0,0,0,0,0,0,0,0,0,0,0,0,0,0,0,0,0,0,0,0,0,0,0,0,0,0,0,0,0,E~
R5,0,0,0,0,0,0,0,0,0,0,0)';
      PINUSE='POWER';
      NO_LOAD_CHECK='Both';
      NO_IO_CHECK='Both';
      NO_ASSERT_CHECK='TRUE';
      NO_DIR_CHECK='TRUE';
      ALLOW_CONNECT='TRUE';
    'VSS1548':
      PIN_NUMBER='(0,0,0,0,0,0,0,0,0,0,0,0,0,0,0,0,0,0,0,0,0,0,0,0,0,0,0,0,0,0,E~
R33,0,0,0,0,0,0,0,0,0,0,0)';
      PINUSE='POWER';
      NO_LOAD_CHECK='Both';
      NO_IO_CHECK='Both';
      NO_ASSERT_CHECK='TRUE';
      NO_DIR_CHECK='TRUE';
      ALLOW_CONNECT='TRUE';
    'VSS1547':
      PIN_NUMBER='(0,0,0,0,0,0,0,0,0,0,0,0,0,0,0,0,0,0,0,0,0,0,0,0,0,0,0,0,0,0,E~
R27,0,0,0,0,0,0,0,0,0,0,0)';
      PINUSE='POWER';
      NO_LOAD_CHECK='Both';
      NO_IO_CHECK='Both';
      NO_ASSERT_CHECK='TRUE';
      NO_DIR_CHECK='TRUE';
      ALLOW_CONNECT='TRUE';
    'VSS1545':
      PIN_NUMBER='(0,0,0,0,0,0,0,0,0,0,0,0,0,0,0,0,0,0,0,0,0,0,0,0,0,0,0,0,0,0,E~
P83,0,0,0,0,0,0,0,0,0,0,0)';
      PINUSE='POWER';
      NO_LOAD_CHECK='Both';
      NO_IO_CHECK='Both';
      NO_ASSERT_CHECK='TRUE';
      NO_DIR_CHECK='TRUE';
      ALLOW_CONNECT='TRUE';
    'VSS1543':
      PIN_NUMBER='(0,0,0,0,0,0,0,0,0,0,0,0,0,0,0,0,0,0,0,0,0,0,0,0,0,0,0,0,0,0,E~
P67,0,0,0,0,0,0,0,0,0,0,0)';
      PINUSE='POWER';
      NO_LOAD_CHECK='Both';
      NO_IO_CHECK='Both';
      NO_ASSERT_CHECK='TRUE';
      NO_DIR_CHECK='TRUE';
      ALLOW_CONNECT='TRUE';
    'VSS1542':
      PIN_NUMBER='(0,0,0,0,0,0,0,0,0,0,0,0,0,0,0,0,0,0,0,0,0,0,0,0,0,0,0,0,0,0,E~
N80,0,0,0,0,0,0,0,0,0,0,0)';
      PINUSE='POWER';
      NO_LOAD_CHECK='Both';
      NO_IO_CHECK='Both';
      NO_ASSERT_CHECK='TRUE';
      NO_DIR_CHECK='TRUE';
      ALLOW_CONNECT='TRUE';
    'VSS1541':
      PIN_NUMBER='(0,0,0,0,0,0,0,0,0,0,0,0,0,0,0,0,0,0,0,0,0,0,0,0,0,0,0,0,0,0,E~
N78,0,0,0,0,0,0,0,0,0,0,0)';
      PINUSE='POWER';
      NO_LOAD_CHECK='Both';
      NO_IO_CHECK='Both';
      NO_ASSERT_CHECK='TRUE';
      NO_DIR_CHECK='TRUE';
      ALLOW_CONNECT='TRUE';
    'VSS1540':
      PIN_NUMBER='(0,0,0,0,0,0,0,0,0,0,0,0,0,0,0,0,0,0,0,0,0,0,0,0,0,0,0,0,0,0,E~
N64,0,0,0,0,0,0,0,0,0,0,0)';
      PINUSE='POWER';
      NO_LOAD_CHECK='Both';
      NO_IO_CHECK='Both';
      NO_ASSERT_CHECK='TRUE';
      NO_DIR_CHECK='TRUE';
      ALLOW_CONNECT='TRUE';
    'VSS1539':
      PIN_NUMBER='(0,0,0,0,0,0,0,0,0,0,0,0,0,0,0,0,0,0,0,0,0,0,0,0,0,0,0,0,0,0,E~
N56,0,0,0,0,0,0,0,0,0,0,0)';
      PINUSE='POWER';
      NO_LOAD_CHECK='Both';
      NO_IO_CHECK='Both';
      NO_ASSERT_CHECK='TRUE';
      NO_DIR_CHECK='TRUE';
      ALLOW_CONNECT='TRUE';
    'VSS1537':
      PIN_NUMBER='(0,0,0,0,0,0,0,0,0,0,0,0,0,0,0,0,0,0,0,0,0,0,0,0,0,0,0,0,0,0,E~
N54,0,0,0,0,0,0,0,0,0,0,0)';
      PINUSE='POWER';
      NO_LOAD_CHECK='Both';
      NO_IO_CHECK='Both';
      NO_ASSERT_CHECK='TRUE';
      NO_DIR_CHECK='TRUE';
      ALLOW_CONNECT='TRUE';
    'VSS1533':
      PIN_NUMBER='(0,0,0,0,0,0,0,0,0,0,0,0,0,0,0,0,0,0,0,0,0,0,0,0,0,0,0,0,0,0,E~
N52,0,0,0,0,0,0,0,0,0,0,0)';
      PINUSE='POWER';
      NO_LOAD_CHECK='Both';
      NO_IO_CHECK='Both';
      NO_ASSERT_CHECK='TRUE';
      NO_DIR_CHECK='TRUE';
      ALLOW_CONNECT='TRUE';
    'VSS1531':
      PIN_NUMBER='(0,0,0,0,0,0,0,0,0,0,0,0,0,0,0,0,0,0,0,0,0,0,0,0,0,0,0,0,0,0,E~
N50,0,0,0,0,0,0,0,0,0,0,0)';
      PINUSE='POWER';
      NO_LOAD_CHECK='Both';
      NO_IO_CHECK='Both';
      NO_ASSERT_CHECK='TRUE';
      NO_DIR_CHECK='TRUE';
      ALLOW_CONNECT='TRUE';
    'VSS1530':
      PIN_NUMBER='(0,0,0,0,0,0,0,0,0,0,0,0,0,0,0,0,0,0,0,0,0,0,0,0,0,0,0,0,0,0,E~
N48,0,0,0,0,0,0,0,0,0,0,0)';
      PINUSE='POWER';
      NO_LOAD_CHECK='Both';
      NO_IO_CHECK='Both';
      NO_ASSERT_CHECK='TRUE';
      NO_DIR_CHECK='TRUE';
      ALLOW_CONNECT='TRUE';
    'VSS1529':
      PIN_NUMBER='(0,0,0,0,0,0,0,0,0,0,0,0,0,0,0,0,0,0,0,0,0,0,0,0,0,0,0,0,0,0,E~
N45,0,0,0,0,0,0,0,0,0,0,0)';
      PINUSE='POWER';
      NO_LOAD_CHECK='Both';
      NO_IO_CHECK='Both';
      NO_ASSERT_CHECK='TRUE';
      NO_DIR_CHECK='TRUE';
      ALLOW_CONNECT='TRUE';
    'VSS1528':
      PIN_NUMBER='(0,0,0,0,0,0,0,0,0,0,0,0,0,0,0,0,0,0,0,0,0,0,0,0,0,0,0,0,0,0,E~
N43,0,0,0,0,0,0,0,0,0,0,0)';
      PINUSE='POWER';
      NO_LOAD_CHECK='Both';
      NO_IO_CHECK='Both';
      NO_ASSERT_CHECK='TRUE';
      NO_DIR_CHECK='TRUE';
      ALLOW_CONNECT='TRUE';
    'VSS1526':
      PIN_NUMBER='(0,0,0,0,0,0,0,0,0,0,0,0,0,0,0,0,0,0,0,0,0,0,0,0,0,0,0,0,0,0,E~
N41,0,0,0,0,0,0,0,0,0,0,0)';
      PINUSE='POWER';
      NO_LOAD_CHECK='Both';
      NO_IO_CHECK='Both';
      NO_ASSERT_CHECK='TRUE';
      NO_DIR_CHECK='TRUE';
      ALLOW_CONNECT='TRUE';
    'VSS1525':
      PIN_NUMBER='(0,0,0,0,0,0,0,0,0,0,0,0,0,0,0,0,0,0,0,0,0,0,0,0,0,0,0,0,0,0,E~
N37,0,0,0,0,0,0,0,0,0,0,0)';
      PINUSE='POWER';
      NO_LOAD_CHECK='Both';
      NO_IO_CHECK='Both';
      NO_ASSERT_CHECK='TRUE';
      NO_DIR_CHECK='TRUE';
      ALLOW_CONNECT='TRUE';
    'VSS1524':
      PIN_NUMBER='(0,0,0,0,0,0,0,0,0,0,0,0,0,0,0,0,0,0,0,0,0,0,0,0,0,0,0,0,0,0,E~
N35,0,0,0,0,0,0,0,0,0,0,0)';
      PINUSE='POWER';
      NO_LOAD_CHECK='Both';
      NO_IO_CHECK='Both';
      NO_ASSERT_CHECK='TRUE';
      NO_DIR_CHECK='TRUE';
      ALLOW_CONNECT='TRUE';
    'VSS1522':
      PIN_NUMBER='(0,0,0,0,0,0,0,0,0,0,0,0,0,0,0,0,0,0,0,0,0,0,0,0,0,0,0,0,0,0,E~
N33,0,0,0,0,0,0,0,0,0,0,0)';
      PINUSE='POWER';
      NO_LOAD_CHECK='Both';
      NO_IO_CHECK='Both';
      NO_ASSERT_CHECK='TRUE';
      NO_DIR_CHECK='TRUE';
      ALLOW_CONNECT='TRUE';
    'VSS1520':
      PIN_NUMBER='(0,0,0,0,0,0,0,0,0,0,0,0,0,0,0,0,0,0,0,0,0,0,0,0,0,0,0,0,0,0,E~
N31,0,0,0,0,0,0,0,0,0,0,0)';
      PINUSE='POWER';
      NO_LOAD_CHECK='Both';
      NO_IO_CHECK='Both';
      NO_ASSERT_CHECK='TRUE';
      NO_DIR_CHECK='TRUE';
      ALLOW_CONNECT='TRUE';
    'VSS1518':
      PIN_NUMBER='(0,0,0,0,0,0,0,0,0,0,0,0,0,0,0,0,0,0,0,0,0,0,0,0,0,0,0,0,0,0,E~
N29,0,0,0,0,0,0,0,0,0,0,0)';
      PINUSE='POWER';
      NO_LOAD_CHECK='Both';
      NO_IO_CHECK='Both';
      NO_ASSERT_CHECK='TRUE';
      NO_DIR_CHECK='TRUE';
      ALLOW_CONNECT='TRUE';
    'VSS1517':
      PIN_NUMBER='(0,0,0,0,0,0,0,0,0,0,0,0,0,0,0,0,0,0,0,0,0,0,0,0,0,0,0,0,0,0,E~
N27,0,0,0,0,0,0,0,0,0,0,0)';
      PINUSE='POWER';
      NO_LOAD_CHECK='Both';
      NO_IO_CHECK='Both';
      NO_ASSERT_CHECK='TRUE';
      NO_DIR_CHECK='TRUE';
      ALLOW_CONNECT='TRUE';
    'VSS1515':
      PIN_NUMBER='(0,0,0,0,0,0,0,0,0,0,0,0,0,0,0,0,0,0,0,0,0,0,0,0,0,0,0,0,0,0,E~
N25,0,0,0,0,0,0,0,0,0,0,0)';
      PINUSE='POWER';
      NO_LOAD_CHECK='Both';
      NO_IO_CHECK='Both';
      NO_ASSERT_CHECK='TRUE';
      NO_DIR_CHECK='TRUE';
      ALLOW_CONNECT='TRUE';
    'VSS1513':
      PIN_NUMBER='(0,0,0,0,0,0,0,0,0,0,0,0,0,0,0,0,0,0,0,0,0,0,0,0,0,0,0,0,0,0,E~
N23,0,0,0,0,0,0,0,0,0,0,0)';
      PINUSE='POWER';
      NO_LOAD_CHECK='Both';
      NO_IO_CHECK='Both';
      NO_ASSERT_CHECK='TRUE';
      NO_DIR_CHECK='TRUE';
      ALLOW_CONNECT='TRUE';
    'VSS1512':
      PIN_NUMBER='(0,0,0,0,0,0,0,0,0,0,0,0,0,0,0,0,0,0,0,0,0,0,0,0,0,0,0,0,0,0,E~
N21,0,0,0,0,0,0,0,0,0,0,0)';
      PINUSE='POWER';
      NO_LOAD_CHECK='Both';
      NO_IO_CHECK='Both';
      NO_ASSERT_CHECK='TRUE';
      NO_DIR_CHECK='TRUE';
      ALLOW_CONNECT='TRUE';
    'VSS1506':
      PIN_NUMBER='(0,0,0,0,0,0,0,0,0,0,0,0,0,0,0,0,0,0,0,0,0,0,0,0,0,0,0,0,0,0,E~
N19,0,0,0,0,0,0,0,0,0,0,0)';
      PINUSE='POWER';
      NO_LOAD_CHECK='Both';
      NO_IO_CHECK='Both';
      NO_ASSERT_CHECK='TRUE';
      NO_DIR_CHECK='TRUE';
      ALLOW_CONNECT='TRUE';
    'VSS1505':
      PIN_NUMBER='(0,0,0,0,0,0,0,0,0,0,0,0,0,0,0,0,0,0,0,0,0,0,0,0,0,0,0,0,0,0,E~
N17,0,0,0,0,0,0,0,0,0,0,0)';
      PINUSE='POWER';
      NO_LOAD_CHECK='Both';
      NO_IO_CHECK='Both';
      NO_ASSERT_CHECK='TRUE';
      NO_DIR_CHECK='TRUE';
      ALLOW_CONNECT='TRUE';
    'VSS1503':
      PIN_NUMBER='(0,0,0,0,0,0,0,0,0,0,0,0,0,0,0,0,0,0,0,0,0,0,0,0,0,0,0,0,0,0,E~
N15,0,0,0,0,0,0,0,0,0,0,0)';
      PINUSE='POWER';
      NO_LOAD_CHECK='Both';
      NO_IO_CHECK='Both';
      NO_ASSERT_CHECK='TRUE';
      NO_DIR_CHECK='TRUE';
      ALLOW_CONNECT='TRUE';
    'VSS1501':
      PIN_NUMBER='(0,0,0,0,0,0,0,0,0,0,0,0,0,0,0,0,0,0,0,0,0,0,0,0,0,0,0,0,0,0,E~
N13,0,0,0,0,0,0,0,0,0,0,0)';
      PINUSE='POWER';
      NO_LOAD_CHECK='Both';
      NO_IO_CHECK='Both';
      NO_ASSERT_CHECK='TRUE';
      NO_DIR_CHECK='TRUE';
      ALLOW_CONNECT='TRUE';
    'VSS1500':
      PIN_NUMBER='(0,0,0,0,0,0,0,0,0,0,0,0,0,0,0,0,0,0,0,0,0,0,0,0,0,0,0,0,0,0,E~
N11,0,0,0,0,0,0,0,0,0,0,0)';
      PINUSE='POWER';
      NO_LOAD_CHECK='Both';
      NO_IO_CHECK='Both';
      NO_ASSERT_CHECK='TRUE';
      NO_DIR_CHECK='TRUE';
      ALLOW_CONNECT='TRUE';
    'VSS1499':
      PIN_NUMBER='(0,0,0,0,0,0,0,0,0,0,0,0,0,0,0,0,0,0,0,0,0,0,0,0,0,0,0,0,0,0,E~
M83,0,0,0,0,0,0,0,0,0,0,0)';
      PINUSE='POWER';
      NO_LOAD_CHECK='Both';
      NO_IO_CHECK='Both';
      NO_ASSERT_CHECK='TRUE';
      NO_DIR_CHECK='TRUE';
      ALLOW_CONNECT='TRUE';
    'VSS1498':
      PIN_NUMBER='(0,0,0,0,0,0,0,0,0,0,0,0,0,0,0,0,0,0,0,0,0,0,0,0,0,0,0,0,0,0,E~
M81,0,0,0,0,0,0,0,0,0,0,0)';
      PINUSE='POWER';
      NO_LOAD_CHECK='Both';
      NO_IO_CHECK='Both';
      NO_ASSERT_CHECK='TRUE';
      NO_DIR_CHECK='TRUE';
      ALLOW_CONNECT='TRUE';
    'VSS1497':
      PIN_NUMBER='(0,0,0,0,0,0,0,0,0,0,0,0,0,0,0,0,0,0,0,0,0,0,0,0,0,0,0,0,0,0,E~
M8,0,0,0,0,0,0,0,0,0,0,0)';
      PINUSE='POWER';
      NO_LOAD_CHECK='Both';
      NO_IO_CHECK='Both';
      NO_ASSERT_CHECK='TRUE';
      NO_DIR_CHECK='TRUE';
      ALLOW_CONNECT='TRUE';
    'VSS1496':
      PIN_NUMBER='(0,0,0,0,0,0,0,0,0,0,0,0,0,0,0,0,0,0,0,0,0,0,0,0,0,0,0,0,0,0,E~
M73,0,0,0,0,0,0,0,0,0,0,0)';
      PINUSE='POWER';
      NO_LOAD_CHECK='Both';
      NO_IO_CHECK='Both';
      NO_ASSERT_CHECK='TRUE';
      NO_DIR_CHECK='TRUE';
      ALLOW_CONNECT='TRUE';
    'VSS1493':
      PIN_NUMBER='(0,0,0,0,0,0,0,0,0,0,0,0,0,0,0,0,0,0,0,0,0,0,0,0,0,0,0,0,0,0,E~
T59,0,0,0,0,0,0,0,0,0,0,0)';
      PINUSE='POWER';
      NO_LOAD_CHECK='Both';
      NO_IO_CHECK='Both';
      NO_ASSERT_CHECK='TRUE';
      NO_DIR_CHECK='TRUE';
      ALLOW_CONNECT='TRUE';
    'VSS1492':
      PIN_NUMBER='(0,0,0,0,0,0,0,0,0,0,0,0,0,0,0,0,0,0,0,0,0,0,0,0,0,0,0,0,0,0,E~
M42,0,0,0,0,0,0,0,0,0,0,0)';
      PINUSE='POWER';
      NO_LOAD_CHECK='Both';
      NO_IO_CHECK='Both';
      NO_ASSERT_CHECK='TRUE';
      NO_DIR_CHECK='TRUE';
      ALLOW_CONNECT='TRUE';
    'VSS1491':
      PIN_NUMBER='(0,0,0,0,0,0,0,0,0,0,0,0,0,0,0,0,0,0,0,0,0,0,0,0,0,0,0,0,0,0,E~
T53,0,0,0,0,0,0,0,0,0,0,0)';
      PINUSE='POWER';
      NO_LOAD_CHECK='Both';
      NO_IO_CHECK='Both';
      NO_ASSERT_CHECK='TRUE';
      NO_DIR_CHECK='TRUE';
      ALLOW_CONNECT='TRUE';
    'VSS1489':
      PIN_NUMBER='(0,0,0,0,0,0,0,0,0,0,0,0,0,0,0,0,0,0,0,0,0,0,0,0,0,0,0,0,0,0,E~
L76,0,0,0,0,0,0,0,0,0,0,0)';
      PINUSE='POWER';
      NO_LOAD_CHECK='Both';
      NO_IO_CHECK='Both';
      NO_ASSERT_CHECK='TRUE';
      NO_DIR_CHECK='TRUE';
      ALLOW_CONNECT='TRUE';
    'VSS1488':
      PIN_NUMBER='(0,0,0,0,0,0,0,0,0,0,0,0,0,0,0,0,0,0,0,0,0,0,0,0,0,0,0,0,0,0,E~
L64,0,0,0,0,0,0,0,0,0,0,0)';
      PINUSE='POWER';
      NO_LOAD_CHECK='Both';
      NO_IO_CHECK='Both';
      NO_ASSERT_CHECK='TRUE';
      NO_DIR_CHECK='TRUE';
      ALLOW_CONNECT='TRUE';
    'VSS1486':
      PIN_NUMBER='(0,0,0,0,0,0,0,0,0,0,0,0,0,0,0,0,0,0,0,0,0,0,0,0,0,0,0,0,0,0,E~
L5,0,0,0,0,0,0,0,0,0,0,0)';
      PINUSE='POWER';
      NO_LOAD_CHECK='Both';
      NO_IO_CHECK='Both';
      NO_ASSERT_CHECK='TRUE';
      NO_DIR_CHECK='TRUE';
      ALLOW_CONNECT='TRUE';
    'VSS1485':
      PIN_NUMBER='(0,0,0,0,0,0,0,0,0,0,0,0,0,0,0,0,0,0,0,0,0,0,0,0,0,0,0,0,0,0,E~
L45,0,0,0,0,0,0,0,0,0,0,0)';
      PINUSE='POWER';
      NO_LOAD_CHECK='Both';
      NO_IO_CHECK='Both';
      NO_ASSERT_CHECK='TRUE';
      NO_DIR_CHECK='TRUE';
      ALLOW_CONNECT='TRUE';
    'VSS1484':
      PIN_NUMBER='(0,0,0,0,0,0,0,0,0,0,0,0,0,0,0,0,0,0,0,0,0,0,0,0,0,0,0,0,0,0,E~
T32,0,0,0,0,0,0,0,0,0,0,0)';
      PINUSE='POWER';
      NO_LOAD_CHECK='Both';
      NO_IO_CHECK='Both';
      NO_ASSERT_CHECK='TRUE';
      NO_DIR_CHECK='TRUE';
      ALLOW_CONNECT='TRUE';
    'VSS1483':
      PIN_NUMBER='(0,0,0,0,0,0,0,0,0,0,0,0,0,0,0,0,0,0,0,0,0,0,0,0,0,0,0,0,0,0,E~
L39,0,0,0,0,0,0,0,0,0,0,0)';
      PINUSE='POWER';
      NO_LOAD_CHECK='Both';
      NO_IO_CHECK='Both';
      NO_ASSERT_CHECK='TRUE';
      NO_DIR_CHECK='TRUE';
      ALLOW_CONNECT='TRUE';
    'VSS1482':
      PIN_NUMBER='(0,0,0,0,0,0,0,0,0,0,0,0,0,0,0,0,0,0,0,0,0,0,0,0,0,0,0,0,0,0,E~
T26,0,0,0,0,0,0,0,0,0,0,0)';
      PINUSE='POWER';
      NO_LOAD_CHECK='Both';
      NO_IO_CHECK='Both';
      NO_ASSERT_CHECK='TRUE';
      NO_DIR_CHECK='TRUE';
      ALLOW_CONNECT='TRUE';
    'VSS1481':
      PIN_NUMBER='(0,0,0,0,0,0,0,0,0,0,0,0,0,0,0,0,0,0,0,0,0,0,0,0,0,0,0,0,0,0,E~
L33,0,0,0,0,0,0,0,0,0,0,0)';
      PINUSE='POWER';
      NO_LOAD_CHECK='Both';
      NO_IO_CHECK='Both';
      NO_ASSERT_CHECK='TRUE';
      NO_DIR_CHECK='TRUE';
      ALLOW_CONNECT='TRUE';
    'VSS1480':
      PIN_NUMBER='(0,0,0,0,0,0,0,0,0,0,0,0,0,0,0,0,0,0,0,0,0,0,0,0,0,0,0,0,0,0,E~
T20,0,0,0,0,0,0,0,0,0,0,0)';
      PINUSE='POWER';
      NO_LOAD_CHECK='Both';
      NO_IO_CHECK='Both';
      NO_ASSERT_CHECK='TRUE';
      NO_DIR_CHECK='TRUE';
      ALLOW_CONNECT='TRUE';
    'VSS1479':
      PIN_NUMBER='(0,0,0,0,0,0,0,0,0,0,0,0,0,0,0,0,0,0,0,0,0,0,0,0,0,0,0,0,0,0,E~
L3,0,0,0,0,0,0,0,0,0,0,0)';
      PINUSE='POWER';
      NO_LOAD_CHECK='Both';
      NO_IO_CHECK='Both';
      NO_ASSERT_CHECK='TRUE';
      NO_DIR_CHECK='TRUE';
      ALLOW_CONNECT='TRUE';
    'VSS1478':
      PIN_NUMBER='(0,0,0,0,0,0,0,0,0,0,0,0,0,0,0,0,0,0,0,0,0,0,0,0,0,0,0,0,0,0,E~
T14,0,0,0,0,0,0,0,0,0,0,0)';
      PINUSE='POWER';
      NO_LOAD_CHECK='Both';
      NO_IO_CHECK='Both';
      NO_ASSERT_CHECK='TRUE';
      NO_DIR_CHECK='TRUE';
      ALLOW_CONNECT='TRUE';
    'VSS1477':
      PIN_NUMBER='(0,0,0,0,0,0,0,0,0,0,0,0,0,0,0,0,0,0,0,0,0,0,0,0,0,0,0,0,0,0,E~
L27,0,0,0,0,0,0,0,0,0,0,0)';
      PINUSE='POWER';
      NO_LOAD_CHECK='Both';
      NO_IO_CHECK='Both';
      NO_ASSERT_CHECK='TRUE';
      NO_DIR_CHECK='TRUE';
      ALLOW_CONNECT='TRUE';
    'VSS1476':
      PIN_NUMBER='(0,0,0,0,0,0,0,0,0,0,0,0,0,0,0,0,0,0,0,0,0,0,0,0,0,0,0,0,0,0,E~
R9,0,0,0,0,0,0,0,0,0,0,0)';
      PINUSE='POWER';
      NO_LOAD_CHECK='Both';
      NO_IO_CHECK='Both';
      NO_ASSERT_CHECK='TRUE';
      NO_DIR_CHECK='TRUE';
      ALLOW_CONNECT='TRUE';
    'VSS1475':
      PIN_NUMBER='(0,0,0,0,0,0,0,0,0,0,0,0,0,0,0,0,0,0,0,0,0,0,0,0,0,0,0,0,0,0,E~
L21,0,0,0,0,0,0,0,0,0,0,0)';
      PINUSE='POWER';
      NO_LOAD_CHECK='Both';
      NO_IO_CHECK='Both';
      NO_ASSERT_CHECK='TRUE';
      NO_DIR_CHECK='TRUE';
      ALLOW_CONNECT='TRUE';
    'VSS1474':
      PIN_NUMBER='(0,0,0,0,0,0,0,0,0,0,0,0,0,0,0,0,0,0,0,0,0,0,0,0,0,0,0,0,0,0,E~
K75,0,0,0,0,0,0,0,0,0,0,0)';
      PINUSE='POWER';
      NO_LOAD_CHECK='Both';
      NO_IO_CHECK='Both';
      NO_ASSERT_CHECK='TRUE';
      NO_DIR_CHECK='TRUE';
      ALLOW_CONNECT='TRUE';
    'VSS1473':
      PIN_NUMBER='(0,0,0,0,0,0,0,0,0,0,0,0,0,0,0,0,0,0,0,0,0,0,0,0,0,0,0,0,0,0,E~
K69,0,0,0,0,0,0,0,0,0,0,0)';
      PINUSE='POWER';
      NO_LOAD_CHECK='Both';
      NO_IO_CHECK='Both';
      NO_ASSERT_CHECK='TRUE';
      NO_DIR_CHECK='TRUE';
      ALLOW_CONNECT='TRUE';
    'VSS1472':
      PIN_NUMBER='(0,0,0,0,0,0,0,0,0,0,0,0,0,0,0,0,0,0,0,0,0,0,0,0,0,0,0,0,0,0,E~
K65,0,0,0,0,0,0,0,0,0,0,0)';
      PINUSE='POWER';
      NO_LOAD_CHECK='Both';
      NO_IO_CHECK='Both';
      NO_ASSERT_CHECK='TRUE';
      NO_DIR_CHECK='TRUE';
      ALLOW_CONNECT='TRUE';
    'VSS1471':
      PIN_NUMBER='(0,0,0,0,0,0,0,0,0,0,0,0,0,0,0,0,0,0,0,0,0,0,0,0,0,0,0,0,0,0,E~
K57,0,0,0,0,0,0,0,0,0,0,0)';
      PINUSE='POWER';
      NO_LOAD_CHECK='Both';
      NO_IO_CHECK='Both';
      NO_ASSERT_CHECK='TRUE';
      NO_DIR_CHECK='TRUE';
      ALLOW_CONNECT='TRUE';
    'VSS1470':
      PIN_NUMBER='(0,0,0,0,0,0,0,0,0,0,0,0,0,0,0,0,0,0,0,0,0,0,0,0,0,0,0,0,0,0,E~
K47,0,0,0,0,0,0,0,0,0,0,0)';
      PINUSE='POWER';
      NO_LOAD_CHECK='Both';
      NO_IO_CHECK='Both';
      NO_ASSERT_CHECK='TRUE';
      NO_DIR_CHECK='TRUE';
      ALLOW_CONNECT='TRUE';
    'VSS1469':
      PIN_NUMBER='(0,0,0,0,0,0,0,0,0,0,0,0,0,0,0,0,0,0,0,0,0,0,0,0,0,0,0,0,0,0,E~
K40,0,0,0,0,0,0,0,0,0,0,0)';
      PINUSE='POWER';
      NO_LOAD_CHECK='Both';
      NO_IO_CHECK='Both';
      NO_ASSERT_CHECK='TRUE';
      NO_DIR_CHECK='TRUE';
      ALLOW_CONNECT='TRUE';
    'VSS1468':
      PIN_NUMBER='(0,0,0,0,0,0,0,0,0,0,0,0,0,0,0,0,0,0,0,0,0,0,0,0,0,0,0,0,0,0,E~
R64,0,0,0,0,0,0,0,0,0,0,0)';
      PINUSE='POWER';
      NO_LOAD_CHECK='Both';
      NO_IO_CHECK='Both';
      NO_ASSERT_CHECK='TRUE';
      NO_DIR_CHECK='TRUE';
      ALLOW_CONNECT='TRUE';
    'VSS1467':
      PIN_NUMBER='(0,0,0,0,0,0,0,0,0,0,0,0,0,0,0,0,0,0,0,0,0,0,0,0,0,0,0,0,0,0,E~
R58,0,0,0,0,0,0,0,0,0,0,0)';
      PINUSE='POWER';
      NO_LOAD_CHECK='Both';
      NO_IO_CHECK='Both';
      NO_ASSERT_CHECK='TRUE';
      NO_DIR_CHECK='TRUE';
      ALLOW_CONNECT='TRUE';
    'VSS1466':
      PIN_NUMBER='(0,0,0,0,0,0,0,0,0,0,0,0,0,0,0,0,0,0,0,0,0,0,0,0,0,0,0,0,0,0,E~
K4,0,0,0,0,0,0,0,0,0,0,0)';
      PINUSE='POWER';
      NO_LOAD_CHECK='Both';
      NO_IO_CHECK='Both';
      NO_ASSERT_CHECK='TRUE';
      NO_DIR_CHECK='TRUE';
      ALLOW_CONNECT='TRUE';
    'VSS1465':
      PIN_NUMBER='(0,0,0,0,0,0,0,0,0,0,0,0,0,0,0,0,0,0,0,0,0,0,0,0,0,0,0,0,0,0,E~
K38,0,0,0,0,0,0,0,0,0,0,0)';
      PINUSE='POWER';
      NO_LOAD_CHECK='Both';
      NO_IO_CHECK='Both';
      NO_ASSERT_CHECK='TRUE';
      NO_DIR_CHECK='TRUE';
      ALLOW_CONNECT='TRUE';
    'VSS1464':
      PIN_NUMBER='(0,0,0,0,0,0,0,0,0,0,0,0,0,0,0,0,0,0,0,0,0,0,0,0,0,0,0,0,0,0,E~
R52,0,0,0,0,0,0,0,0,0,0,0)';
      PINUSE='POWER';
      NO_LOAD_CHECK='Both';
      NO_IO_CHECK='Both';
      NO_ASSERT_CHECK='TRUE';
      NO_DIR_CHECK='TRUE';
      ALLOW_CONNECT='TRUE';
    'VSS1463':
      PIN_NUMBER='(0,0,0,0,0,0,0,0,0,0,0,0,0,0,0,0,0,0,0,0,0,0,0,0,0,0,0,0,0,0,E~
K34,0,0,0,0,0,0,0,0,0,0,0)';
      PINUSE='POWER';
      NO_LOAD_CHECK='Both';
      NO_IO_CHECK='Both';
      NO_ASSERT_CHECK='TRUE';
      NO_DIR_CHECK='TRUE';
      ALLOW_CONNECT='TRUE';
    'VSS1462':
      PIN_NUMBER='(0,0,0,0,0,0,0,0,0,0,0,0,0,0,0,0,0,0,0,0,0,0,0,0,0,0,0,0,0,0,E~
R39,0,0,0,0,0,0,0,0,0,0,0)';
      PINUSE='POWER';
      NO_LOAD_CHECK='Both';
      NO_IO_CHECK='Both';
      NO_ASSERT_CHECK='TRUE';
      NO_DIR_CHECK='TRUE';
      ALLOW_CONNECT='TRUE';
    'VSS1461':
      PIN_NUMBER='(0,0,0,0,0,0,0,0,0,0,0,0,0,0,0,0,0,0,0,0,0,0,0,0,0,0,0,0,0,0,E~
K32,0,0,0,0,0,0,0,0,0,0,0)';
      PINUSE='POWER';
      NO_LOAD_CHECK='Both';
      NO_IO_CHECK='Both';
      NO_ASSERT_CHECK='TRUE';
      NO_DIR_CHECK='TRUE';
      ALLOW_CONNECT='TRUE';
    'VSS1460':
      PIN_NUMBER='(0,0,0,0,0,0,0,0,0,0,0,0,0,0,0,0,0,0,0,0,0,0,0,0,0,0,0,0,0,0,E~
K28,0,0,0,0,0,0,0,0,0,0,0)';
      PINUSE='POWER';
      NO_LOAD_CHECK='Both';
      NO_IO_CHECK='Both';
      NO_ASSERT_CHECK='TRUE';
      NO_DIR_CHECK='TRUE';
      ALLOW_CONNECT='TRUE';
    'VSS1459':
      PIN_NUMBER='(0,0,0,0,0,0,0,0,0,0,0,0,0,0,0,0,0,0,0,0,0,0,0,0,0,0,0,0,0,0,E~
K22,0,0,0,0,0,0,0,0,0,0,0)';
      PINUSE='POWER';
      NO_LOAD_CHECK='Both';
      NO_IO_CHECK='Both';
      NO_ASSERT_CHECK='TRUE';
      NO_DIR_CHECK='TRUE';
      ALLOW_CONNECT='TRUE';
    'VSS1458':
      PIN_NUMBER='(0,0,0,0,0,0,0,0,0,0,0,0,0,0,0,0,0,0,0,0,0,0,0,0,0,0,0,0,0,0,E~
K2,0,0,0,0,0,0,0,0,0,0,0)';
      PINUSE='POWER';
      NO_LOAD_CHECK='Both';
      NO_IO_CHECK='Both';
      NO_ASSERT_CHECK='TRUE';
      NO_DIR_CHECK='TRUE';
      ALLOW_CONNECT='TRUE';
    'VSS1457':
      PIN_NUMBER='(0,0,0,0,0,0,0,0,0,0,0,0,0,0,0,0,0,0,0,0,0,0,0,0,0,0,0,0,0,0,E~
R21,0,0,0,0,0,0,0,0,0,0,0)';
      PINUSE='POWER';
      NO_LOAD_CHECK='Both';
      NO_IO_CHECK='Both';
      NO_ASSERT_CHECK='TRUE';
      NO_DIR_CHECK='TRUE';
      ALLOW_CONNECT='TRUE';
    'VSS1456':
      PIN_NUMBER='(0,0,0,0,0,0,0,0,0,0,0,0,0,0,0,0,0,0,0,0,0,0,0,0,0,0,0,0,0,0,E~
R15,0,0,0,0,0,0,0,0,0,0,0)';
      PINUSE='POWER';
      NO_LOAD_CHECK='Both';
      NO_IO_CHECK='Both';
      NO_ASSERT_CHECK='TRUE';
      NO_DIR_CHECK='TRUE';
      ALLOW_CONNECT='TRUE';
    'VSS1455':
      PIN_NUMBER='(0,0,0,0,0,0,0,0,0,0,0,0,0,0,0,0,0,0,0,0,0,0,0,0,0,0,0,0,0,0,E~
K14,0,0,0,0,0,0,0,0,0,0,0)';
      PINUSE='POWER';
      NO_LOAD_CHECK='Both';
      NO_IO_CHECK='Both';
      NO_ASSERT_CHECK='TRUE';
      NO_DIR_CHECK='TRUE';
      ALLOW_CONNECT='TRUE';
    'VSS1454':
      PIN_NUMBER='(0,0,0,0,0,0,0,0,0,0,0,0,0,0,0,0,0,0,0,0,0,0,0,0,0,0,0,0,0,0,E~
P77,0,0,0,0,0,0,0,0,0,0,0)';
      PINUSE='POWER';
      NO_LOAD_CHECK='Both';
      NO_IO_CHECK='Both';
      NO_ASSERT_CHECK='TRUE';
      NO_DIR_CHECK='TRUE';
      ALLOW_CONNECT='TRUE';
    'VSS1453':
      PIN_NUMBER='(0,0,0,0,0,0,0,0,0,0,0,0,0,0,0,0,0,0,0,0,0,0,0,0,0,0,0,0,0,0,E~
P71,0,0,0,0,0,0,0,0,0,0,0)';
      PINUSE='POWER';
      NO_LOAD_CHECK='Both';
      NO_IO_CHECK='Both';
      NO_ASSERT_CHECK='TRUE';
      NO_DIR_CHECK='TRUE';
      ALLOW_CONNECT='TRUE';
    'VSS1452':
      PIN_NUMBER='(0,0,0,0,0,0,0,0,0,0,0,0,0,0,0,0,0,0,0,0,0,0,0,0,0,0,0,0,0,0,E~
P69,0,0,0,0,0,0,0,0,0,0,0)';
      PINUSE='POWER';
      NO_LOAD_CHECK='Both';
      NO_IO_CHECK='Both';
      NO_ASSERT_CHECK='TRUE';
      NO_DIR_CHECK='TRUE';
      ALLOW_CONNECT='TRUE';
    'VSS1451':
      PIN_NUMBER='(0,0,0,0,0,0,0,0,0,0,0,0,0,0,0,0,0,0,0,0,0,0,0,0,0,0,0,0,0,0,E~
K10,0,0,0,0,0,0,0,0,0,0,0)';
      PINUSE='POWER';
      NO_LOAD_CHECK='Both';
      NO_IO_CHECK='Both';
      NO_ASSERT_CHECK='TRUE';
      NO_DIR_CHECK='TRUE';
      ALLOW_CONNECT='TRUE';
    'VSS1450':
      PIN_NUMBER='(0,0,0,0,0,0,0,0,0,0,0,0,0,0,0,0,0,0,0,0,0,0,0,0,0,0,0,0,0,0,E~
J9,0,0,0,0,0,0,0,0,0,0,0)';
      PINUSE='POWER';
      NO_LOAD_CHECK='Both';
      NO_IO_CHECK='Both';
      NO_ASSERT_CHECK='TRUE';
      NO_DIR_CHECK='TRUE';
      ALLOW_CONNECT='TRUE';
    'VSS1449':
      PIN_NUMBER='(0,0,0,0,0,0,0,0,0,0,0,0,0,0,0,0,0,0,0,0,0,0,0,0,0,0,0,0,0,0,E~
J88,0,0,0,0,0,0,0,0,0,0,0)';
      PINUSE='POWER';
      NO_LOAD_CHECK='Both';
      NO_IO_CHECK='Both';
      NO_ASSERT_CHECK='TRUE';
      NO_DIR_CHECK='TRUE';
      ALLOW_CONNECT='TRUE';
    'VSS1448':
      PIN_NUMBER='(0,0,0,0,0,0,0,0,0,0,0,0,0,0,0,0,0,0,0,0,0,0,0,0,0,0,0,0,0,0,E~
J78,0,0,0,0,0,0,0,0,0,0,0)';
      PINUSE='POWER';
      NO_LOAD_CHECK='Both';
      NO_IO_CHECK='Both';
      NO_ASSERT_CHECK='TRUE';
      NO_DIR_CHECK='TRUE';
      ALLOW_CONNECT='TRUE';
    'VSS1447':
      PIN_NUMBER='(0,0,0,0,0,0,0,0,0,0,0,0,0,0,0,0,0,0,0,0,0,0,0,0,0,0,0,0,0,0,E~
J74,0,0,0,0,0,0,0,0,0,0,0)';
      PINUSE='POWER';
      NO_LOAD_CHECK='Both';
      NO_IO_CHECK='Both';
      NO_ASSERT_CHECK='TRUE';
      NO_DIR_CHECK='TRUE';
      ALLOW_CONNECT='TRUE';
    'VSS1446':
      PIN_NUMBER='(0,0,0,0,0,0,0,0,0,0,0,0,0,0,0,0,0,0,0,0,0,0,0,0,0,0,0,0,0,0,E~
N9,0,0,0,0,0,0,0,0,0,0,0)';
      PINUSE='POWER';
      NO_LOAD_CHECK='Both';
      NO_IO_CHECK='Both';
      NO_ASSERT_CHECK='TRUE';
      NO_DIR_CHECK='TRUE';
      ALLOW_CONNECT='TRUE';
    'VSS1445':
      PIN_NUMBER='(0,0,0,0,0,0,0,0,0,0,0,0,0,0,0,0,0,0,0,0,0,0,0,0,0,0,0,0,0,0,E~
N88,0,0,0,0,0,0,0,0,0,0,0)';
      PINUSE='POWER';
      NO_LOAD_CHECK='Both';
      NO_IO_CHECK='Both';
      NO_ASSERT_CHECK='TRUE';
      NO_DIR_CHECK='TRUE';
      ALLOW_CONNECT='TRUE';
    'VSS1444':
      PIN_NUMBER='(0,0,0,0,0,0,0,0,0,0,0,0,0,0,0,0,0,0,0,0,0,0,0,0,0,0,0,0,0,0,E~
J7,0,0,0,0,0,0,0,0,0,0,0)';
      PINUSE='POWER';
      NO_LOAD_CHECK='Both';
      NO_IO_CHECK='Both';
      NO_ASSERT_CHECK='TRUE';
      NO_DIR_CHECK='TRUE';
      ALLOW_CONNECT='TRUE';
    'VSS1443':
      PIN_NUMBER='(0,0,0,0,0,0,0,0,0,0,0,0,0,0,0,0,0,0,0,0,0,0,0,0,0,0,0,0,0,0,E~
J66,0,0,0,0,0,0,0,0,0,0,0)';
      PINUSE='POWER';
      NO_LOAD_CHECK='Both';
      NO_IO_CHECK='Both';
      NO_ASSERT_CHECK='TRUE';
      NO_DIR_CHECK='TRUE';
      ALLOW_CONNECT='TRUE';
    'VSS1442':
      PIN_NUMBER='(0,0,0,0,0,0,0,0,0,0,0,0,0,0,0,0,0,0,0,0,0,0,0,0,0,0,0,0,0,0,E~
J60,0,0,0,0,0,0,0,0,0,0,0)';
      PINUSE='POWER';
      NO_LOAD_CHECK='Both';
      NO_IO_CHECK='Both';
      NO_ASSERT_CHECK='TRUE';
      NO_DIR_CHECK='TRUE';
      ALLOW_CONNECT='TRUE';
    'VSS1441':
      PIN_NUMBER='(0,0,0,0,0,0,0,0,0,0,0,0,0,0,0,0,0,0,0,0,0,0,0,0,0,0,0,0,0,0,E~
N72,0,0,0,0,0,0,0,0,0,0,0)';
      PINUSE='POWER';
      NO_LOAD_CHECK='Both';
      NO_IO_CHECK='Both';
      NO_ASSERT_CHECK='TRUE';
      NO_DIR_CHECK='TRUE';
      ALLOW_CONNECT='TRUE';
    'VSS1440':
      PIN_NUMBER='(0,0,0,0,0,0,0,0,0,0,0,0,0,0,0,0,0,0,0,0,0,0,0,0,0,0,0,0,0,0,E~
N66,0,0,0,0,0,0,0,0,0,0,0)';
      PINUSE='POWER';
      NO_LOAD_CHECK='Both';
      NO_IO_CHECK='Both';
      NO_ASSERT_CHECK='TRUE';
      NO_DIR_CHECK='TRUE';
      ALLOW_CONNECT='TRUE';
    'VSS1439':
      PIN_NUMBER='(0,0,0,0,0,0,0,0,0,0,0,0,0,0,0,0,0,0,0,0,0,0,0,0,0,0,0,0,0,0,E~
J56,0,0,0,0,0,0,0,0,0,0,0)';
      PINUSE='POWER';
      NO_LOAD_CHECK='Both';
      NO_IO_CHECK='Both';
      NO_ASSERT_CHECK='TRUE';
      NO_DIR_CHECK='TRUE';
      ALLOW_CONNECT='TRUE';
    'VSS1438':
      PIN_NUMBER='(0,0,0,0,0,0,0,0,0,0,0,0,0,0,0,0,0,0,0,0,0,0,0,0,0,0,0,0,0,0,E~
N62,0,0,0,0,0,0,0,0,0,0,0)';
      PINUSE='POWER';
      NO_LOAD_CHECK='Both';
      NO_IO_CHECK='Both';
      NO_ASSERT_CHECK='TRUE';
      NO_DIR_CHECK='TRUE';
      ALLOW_CONNECT='TRUE';
    'VSS1437':
      PIN_NUMBER='(0,0,0,0,0,0,0,0,0,0,0,0,0,0,0,0,0,0,0,0,0,0,0,0,0,0,0,0,0,0,E~
N60,0,0,0,0,0,0,0,0,0,0,0)';
      PINUSE='POWER';
      NO_LOAD_CHECK='Both';
      NO_IO_CHECK='Both';
      NO_ASSERT_CHECK='TRUE';
      NO_DIR_CHECK='TRUE';
      ALLOW_CONNECT='TRUE';
    'VSS1436':
      PIN_NUMBER='(0,0,0,0,0,0,0,0,0,0,0,0,0,0,0,0,0,0,0,0,0,0,0,0,0,0,0,0,0,0,E~
N58,0,0,0,0,0,0,0,0,0,0,0)';
      PINUSE='POWER';
      NO_LOAD_CHECK='Both';
      NO_IO_CHECK='Both';
      NO_ASSERT_CHECK='TRUE';
      NO_DIR_CHECK='TRUE';
      ALLOW_CONNECT='TRUE';
    'VSS1435':
      PIN_NUMBER='(0,0,0,0,0,0,0,0,0,0,0,0,0,0,0,0,0,0,0,0,0,0,0,0,0,0,0,0,0,0,E~
J50,0,0,0,0,0,0,0,0,0,0,0)';
      PINUSE='POWER';
      NO_LOAD_CHECK='Both';
      NO_IO_CHECK='Both';
      NO_ASSERT_CHECK='TRUE';
      NO_DIR_CHECK='TRUE';
      ALLOW_CONNECT='TRUE';
    'VSS1434':
      PIN_NUMBER='(0,0,0,0,0,0,0,0,0,0,0,0,0,0,0,0,0,0,0,0,0,0,0,0,0,0,0,0,0,0,E~
J48,0,0,0,0,0,0,0,0,0,0,0)';
      PINUSE='POWER';
      NO_LOAD_CHECK='Both';
      NO_IO_CHECK='Both';
      NO_ASSERT_CHECK='TRUE';
      NO_DIR_CHECK='TRUE';
      ALLOW_CONNECT='TRUE';
    'VSS1433':
      PIN_NUMBER='(0,0,0,0,0,0,0,0,0,0,0,0,0,0,0,0,0,0,0,0,0,0,0,0,0,0,0,0,0,0,E~
J43,0,0,0,0,0,0,0,0,0,0,0)';
      PINUSE='POWER';
      NO_LOAD_CHECK='Both';
      NO_IO_CHECK='Both';
      NO_ASSERT_CHECK='TRUE';
      NO_DIR_CHECK='TRUE';
      ALLOW_CONNECT='TRUE';
    'VSS1432':
      PIN_NUMBER='(0,0,0,0,0,0,0,0,0,0,0,0,0,0,0,0,0,0,0,0,0,0,0,0,0,0,0,0,0,0,E~
J41,0,0,0,0,0,0,0,0,0,0,0)';
      PINUSE='POWER';
      NO_LOAD_CHECK='Both';
      NO_IO_CHECK='Both';
      NO_ASSERT_CHECK='TRUE';
      NO_DIR_CHECK='TRUE';
      ALLOW_CONNECT='TRUE';
    'VSS1431':
      PIN_NUMBER='(0,0,0,0,0,0,0,0,0,0,0,0,0,0,0,0,0,0,0,0,0,0,0,0,0,0,0,0,0,0,E~
J37,0,0,0,0,0,0,0,0,0,0,0)';
      PINUSE='POWER';
      NO_LOAD_CHECK='Both';
      NO_IO_CHECK='Both';
      NO_ASSERT_CHECK='TRUE';
      NO_DIR_CHECK='TRUE';
      ALLOW_CONNECT='TRUE';
    'VSS1430':
      PIN_NUMBER='(0,0,0,0,0,0,0,0,0,0,0,0,0,0,0,0,0,0,0,0,0,0,0,0,0,0,0,0,0,0,E~
J31,0,0,0,0,0,0,0,0,0,0,0)';
      PINUSE='POWER';
      NO_LOAD_CHECK='Both';
      NO_IO_CHECK='Both';
      NO_ASSERT_CHECK='TRUE';
      NO_DIR_CHECK='TRUE';
      ALLOW_CONNECT='TRUE';
    'VSS1429':
      PIN_NUMBER='(0,0,0,0,0,0,0,0,0,0,0,0,0,0,0,0,0,0,0,0,0,0,0,0,0,0,0,0,0,0,E~
J29,0,0,0,0,0,0,0,0,0,0,0)';
      PINUSE='POWER';
      NO_LOAD_CHECK='Both';
      NO_IO_CHECK='Both';
      NO_ASSERT_CHECK='TRUE';
      NO_DIR_CHECK='TRUE';
      ALLOW_CONNECT='TRUE';
    'VSS1428':
      PIN_NUMBER='(0,0,0,0,0,0,0,0,0,0,0,0,0,0,0,0,0,0,0,0,0,0,0,0,0,0,0,0,0,0,E~
J23,0,0,0,0,0,0,0,0,0,0,0)';
      PINUSE='POWER';
      NO_LOAD_CHECK='Both';
      NO_IO_CHECK='Both';
      NO_ASSERT_CHECK='TRUE';
      NO_DIR_CHECK='TRUE';
      ALLOW_CONNECT='TRUE';
    'VSS1427':
      PIN_NUMBER='(0,0,0,0,0,0,0,0,0,0,0,0,0,0,0,0,0,0,0,0,0,0,0,0,0,0,0,0,0,0,E~
N39,0,0,0,0,0,0,0,0,0,0,0)';
      PINUSE='POWER';
      NO_LOAD_CHECK='Both';
      NO_IO_CHECK='Both';
      NO_ASSERT_CHECK='TRUE';
      NO_DIR_CHECK='TRUE';
      ALLOW_CONNECT='TRUE';
    'VSS1426':
      PIN_NUMBER='(0,0,0,0,0,0,0,0,0,0,0,0,0,0,0,0,0,0,0,0,0,0,0,0,0,0,0,0,0,0,E~
J19,0,0,0,0,0,0,0,0,0,0,0)';
      PINUSE='POWER';
      NO_LOAD_CHECK='Both';
      NO_IO_CHECK='Both';
      NO_ASSERT_CHECK='TRUE';
      NO_DIR_CHECK='TRUE';
      ALLOW_CONNECT='TRUE';
    'VSS1425':
      PIN_NUMBER='(0,0,0,0,0,0,0,0,0,0,0,0,0,0,0,0,0,0,0,0,0,0,0,0,0,0,0,0,0,0,E~
J13,0,0,0,0,0,0,0,0,0,0,0)';
      PINUSE='POWER';
      NO_LOAD_CHECK='Both';
      NO_IO_CHECK='Both';
      NO_ASSERT_CHECK='TRUE';
      NO_DIR_CHECK='TRUE';
      ALLOW_CONNECT='TRUE';
    'VSS1424':
      PIN_NUMBER='(0,0,0,0,0,0,0,0,0,0,0,0,0,0,0,0,0,0,0,0,0,0,0,0,0,0,0,0,0,0,E~
H83,0,0,0,0,0,0,0,0,0,0,0)';
      PINUSE='POWER';
      NO_LOAD_CHECK='Both';
      NO_IO_CHECK='Both';
      NO_ASSERT_CHECK='TRUE';
      NO_DIR_CHECK='TRUE';
      ALLOW_CONNECT='TRUE';
    'VSS1423':
      PIN_NUMBER='(0,0,0,0,0,0,0,0,0,0,0,0,0,0,0,0,0,0,0,0,0,0,0,0,0,0,0,0,0,0,E~
H81,0,0,0,0,0,0,0,0,0,0,0)';
      PINUSE='POWER';
      NO_LOAD_CHECK='Both';
      NO_IO_CHECK='Both';
      NO_ASSERT_CHECK='TRUE';
      NO_DIR_CHECK='TRUE';
      ALLOW_CONNECT='TRUE';
    'VSS1422':
      PIN_NUMBER='(0,0,0,0,0,0,0,0,0,0,0,0,0,0,0,0,0,0,0,0,0,0,0,0,0,0,0,0,0,0,E~
H73,0,0,0,0,0,0,0,0,0,0,0)';
      PINUSE='POWER';
      NO_LOAD_CHECK='Both';
      NO_IO_CHECK='Both';
      NO_ASSERT_CHECK='TRUE';
      NO_DIR_CHECK='TRUE';
      ALLOW_CONNECT='TRUE';
    'VSS1421':
      PIN_NUMBER='(0,0,0,0,0,0,0,0,0,0,0,0,0,0,0,0,0,0,0,0,0,0,0,0,0,0,0,0,0,0,E~
H49,0,0,0,0,0,0,0,0,0,0,0)';
      PINUSE='POWER';
      NO_LOAD_CHECK='Both';
      NO_IO_CHECK='Both';
      NO_ASSERT_CHECK='TRUE';
      NO_DIR_CHECK='TRUE';
      ALLOW_CONNECT='TRUE';
    'VSS1419':
      PIN_NUMBER='(0,0,0,0,0,0,0,0,0,0,0,0,0,0,0,0,0,0,0,0,0,0,0,0,0,0,0,0,0,0,E~
H36,0,0,0,0,0,0,0,0,0,0,0)';
      PINUSE='POWER';
      NO_LOAD_CHECK='Both';
      NO_IO_CHECK='Both';
      NO_ASSERT_CHECK='TRUE';
      NO_DIR_CHECK='TRUE';
      ALLOW_CONNECT='TRUE';
    'VSS1409':
      PIN_NUMBER='(0,0,0,0,0,0,0,0,0,0,0,0,0,0,0,0,0,0,0,0,0,0,0,0,0,0,0,0,0,0,E~
M79,0,0,0,0,0,0,0,0,0,0,0)';
      PINUSE='POWER';
      NO_LOAD_CHECK='Both';
      NO_IO_CHECK='Both';
      NO_ASSERT_CHECK='TRUE';
      NO_DIR_CHECK='TRUE';
      ALLOW_CONNECT='TRUE';
    'VSS1405':
      PIN_NUMBER='(0,0,0,0,0,0,0,0,0,0,0,0,0,0,0,0,0,0,0,0,0,0,0,0,0,0,0,0,0,0,E~
M49,0,0,0,0,0,0,0,0,0,0,0)';
      PINUSE='POWER';
      NO_LOAD_CHECK='Both';
      NO_IO_CHECK='Both';
      NO_ASSERT_CHECK='TRUE';
      NO_DIR_CHECK='TRUE';
      ALLOW_CONNECT='TRUE';
    'VSS1401':
      PIN_NUMBER='(0,0,0,0,0,0,0,0,0,0,0,0,0,0,0,0,0,0,0,0,0,0,0,0,0,0,0,0,0,0,E~
L9,0,0,0,0,0,0,0,0,0,0,0)';
      PINUSE='POWER';
      NO_LOAD_CHECK='Both';
      NO_IO_CHECK='Both';
      NO_ASSERT_CHECK='TRUE';
      NO_DIR_CHECK='TRUE';
      ALLOW_CONNECT='TRUE';
    'VSS1400':
      PIN_NUMBER='(0,0,0,0,0,0,0,0,0,0,0,0,0,0,0,0,0,0,0,0,0,0,0,0,0,0,0,0,0,0,E~
L86,0,0,0,0,0,0,0,0,0,0,0)';
      PINUSE='POWER';
      NO_LOAD_CHECK='Both';
      NO_IO_CHECK='Both';
      NO_ASSERT_CHECK='TRUE';
      NO_DIR_CHECK='TRUE';
      ALLOW_CONNECT='TRUE';
    'VSS1398':
      PIN_NUMBER='(0,0,0,0,0,0,0,0,0,0,0,0,0,0,0,0,0,0,0,0,0,0,0,0,0,0,0,0,0,0,E~
L72,0,0,0,0,0,0,0,0,0,0,0)';
      PINUSE='POWER';
      NO_LOAD_CHECK='Both';
      NO_IO_CHECK='Both';
      NO_ASSERT_CHECK='TRUE';
      NO_DIR_CHECK='TRUE';
      ALLOW_CONNECT='TRUE';
    'VSS1397':
      PIN_NUMBER='(0,0,0,0,0,0,0,0,0,0,0,0,0,0,0,0,0,0,0,0,0,0,0,0,0,0,0,0,0,0,E~
L70,0,0,0,0,0,0,0,0,0,0,0)';
      PINUSE='POWER';
      NO_LOAD_CHECK='Both';
      NO_IO_CHECK='Both';
      NO_ASSERT_CHECK='TRUE';
      NO_DIR_CHECK='TRUE';
      ALLOW_CONNECT='TRUE';
    'VSS1396':
      PIN_NUMBER='(0,0,0,0,0,0,0,0,0,0,0,0,0,0,0,0,0,0,0,0,0,0,0,0,0,0,0,0,0,0,E~
L7,0,0,0,0,0,0,0,0,0,0,0)';
      PINUSE='POWER';
      NO_LOAD_CHECK='Both';
      NO_IO_CHECK='Both';
      NO_ASSERT_CHECK='TRUE';
      NO_DIR_CHECK='TRUE';
      ALLOW_CONNECT='TRUE';
    'VSS1394':
      PIN_NUMBER='(0,0,0,0,0,0,0,0,0,0,0,0,0,0,0,0,0,0,0,0,0,0,0,0,0,0,0,0,0,0,E~
L58,0,0,0,0,0,0,0,0,0,0,0)';
      PINUSE='POWER';
      NO_LOAD_CHECK='Both';
      NO_IO_CHECK='Both';
      NO_ASSERT_CHECK='TRUE';
      NO_DIR_CHECK='TRUE';
      ALLOW_CONNECT='TRUE';
    'VSS1391':
      PIN_NUMBER='(0,0,0,0,0,0,0,0,0,0,0,0,0,0,0,0,0,0,0,0,0,0,0,0,0,0,0,0,0,0,E~
L52,0,0,0,0,0,0,0,0,0,0,0)';
      PINUSE='POWER';
      NO_LOAD_CHECK='Both';
      NO_IO_CHECK='Both';
      NO_ASSERT_CHECK='TRUE';
      NO_DIR_CHECK='TRUE';
      ALLOW_CONNECT='TRUE';
    'VSS1381':
      PIN_NUMBER='(0,0,0,0,0,0,0,0,0,0,0,0,0,0,0,0,0,0,0,0,0,0,0,0,0,0,0,0,0,0,E~
L15,0,0,0,0,0,0,0,0,0,0,0)';
      PINUSE='POWER';
      NO_LOAD_CHECK='Both';
      NO_IO_CHECK='Both';
      NO_ASSERT_CHECK='TRUE';
      NO_DIR_CHECK='TRUE';
      ALLOW_CONNECT='TRUE';
    'VSS1380':
      PIN_NUMBER='(0,0,0,0,0,0,0,0,0,0,0,0,0,0,0,0,0,0,0,0,0,0,0,0,0,0,0,0,0,0,E~
K89,0,0,0,0,0,0,0,0,0,0,0)';
      PINUSE='POWER';
      NO_LOAD_CHECK='Both';
      NO_IO_CHECK='Both';
      NO_ASSERT_CHECK='TRUE';
      NO_DIR_CHECK='TRUE';
      ALLOW_CONNECT='TRUE';
    'VSS1379':
      PIN_NUMBER='(0,0,0,0,0,0,0,0,0,0,0,0,0,0,0,0,0,0,0,0,0,0,0,0,0,0,0,0,0,0,E~
K83,0,0,0,0,0,0,0,0,0,0,0)';
      PINUSE='POWER';
      NO_LOAD_CHECK='Both';
      NO_IO_CHECK='Both';
      NO_ASSERT_CHECK='TRUE';
      NO_DIR_CHECK='TRUE';
      ALLOW_CONNECT='TRUE';
    'VSS1378':
      PIN_NUMBER='(0,0,0,0,0,0,0,0,0,0,0,0,0,0,0,0,0,0,0,0,0,0,0,0,0,0,0,0,0,0,E~
K79,0,0,0,0,0,0,0,0,0,0,0)';
      PINUSE='POWER';
      NO_LOAD_CHECK='Both';
      NO_IO_CHECK='Both';
      NO_ASSERT_CHECK='TRUE';
      NO_DIR_CHECK='TRUE';
      ALLOW_CONNECT='TRUE';
    'VSS1377':
      PIN_NUMBER='(0,0,0,0,0,0,0,0,0,0,0,0,0,0,0,0,0,0,0,0,0,0,0,0,0,0,0,0,0,0,E~
K77,0,0,0,0,0,0,0,0,0,0,0)';
      PINUSE='POWER';
      NO_LOAD_CHECK='Both';
      NO_IO_CHECK='Both';
      NO_ASSERT_CHECK='TRUE';
      NO_DIR_CHECK='TRUE';
      ALLOW_CONNECT='TRUE';
    'VSS1375':
      PIN_NUMBER='(0,0,0,0,0,0,0,0,0,0,0,0,0,0,0,0,0,0,0,0,0,0,0,0,0,0,0,0,0,0,E~
K71,0,0,0,0,0,0,0,0,0,0,0)';
      PINUSE='POWER';
      NO_LOAD_CHECK='Both';
      NO_IO_CHECK='Both';
      NO_ASSERT_CHECK='TRUE';
      NO_DIR_CHECK='TRUE';
      ALLOW_CONNECT='TRUE';
    'VSS1372':
      PIN_NUMBER='(0,0,0,0,0,0,0,0,0,0,0,0,0,0,0,0,0,0,0,0,0,0,0,0,0,0,0,0,0,0,E~
K63,0,0,0,0,0,0,0,0,0,0,0)';
      PINUSE='POWER';
      NO_LOAD_CHECK='Both';
      NO_IO_CHECK='Both';
      NO_ASSERT_CHECK='TRUE';
      NO_DIR_CHECK='TRUE';
      ALLOW_CONNECT='TRUE';
    'VSS1371':
      PIN_NUMBER='(0,0,0,0,0,0,0,0,0,0,0,0,0,0,0,0,0,0,0,0,0,0,0,0,0,0,0,0,0,0,E~
K59,0,0,0,0,0,0,0,0,0,0,0)';
      PINUSE='POWER';
      NO_LOAD_CHECK='Both';
      NO_IO_CHECK='Both';
      NO_ASSERT_CHECK='TRUE';
      NO_DIR_CHECK='TRUE';
      ALLOW_CONNECT='TRUE';
    'VSS1369':
      PIN_NUMBER='(0,0,0,0,0,0,0,0,0,0,0,0,0,0,0,0,0,0,0,0,0,0,0,0,0,0,0,0,0,0,E~
K53,0,0,0,0,0,0,0,0,0,0,0)';
      PINUSE='POWER';
      NO_LOAD_CHECK='Both';
      NO_IO_CHECK='Both';
      NO_ASSERT_CHECK='TRUE';
      NO_DIR_CHECK='TRUE';
      ALLOW_CONNECT='TRUE';
    'VSS1368':
      PIN_NUMBER='(0,0,0,0,0,0,0,0,0,0,0,0,0,0,0,0,0,0,0,0,0,0,0,0,0,0,0,0,0,0,E~
K51,0,0,0,0,0,0,0,0,0,0,0)';
      PINUSE='POWER';
      NO_LOAD_CHECK='Both';
      NO_IO_CHECK='Both';
      NO_ASSERT_CHECK='TRUE';
      NO_DIR_CHECK='TRUE';
      ALLOW_CONNECT='TRUE';
    'VSS1366':
      PIN_NUMBER='(0,0,0,0,0,0,0,0,0,0,0,0,0,0,0,0,0,0,0,0,0,0,0,0,0,0,0,0,0,0,E~
K44,0,0,0,0,0,0,0,0,0,0,0)';
      PINUSE='POWER';
      NO_LOAD_CHECK='Both';
      NO_IO_CHECK='Both';
      NO_ASSERT_CHECK='TRUE';
      NO_DIR_CHECK='TRUE';
      ALLOW_CONNECT='TRUE';
    'VSS1359':
      PIN_NUMBER='(0,0,0,0,0,0,0,0,0,0,0,0,0,0,0,0,0,0,0,0,0,0,0,0,0,0,0,0,0,0,E~
K26,0,0,0,0,0,0,0,0,0,0,0)';
      PINUSE='POWER';
      NO_LOAD_CHECK='Both';
      NO_IO_CHECK='Both';
      NO_ASSERT_CHECK='TRUE';
      NO_DIR_CHECK='TRUE';
      ALLOW_CONNECT='TRUE';
    'VSS1357':
      PIN_NUMBER='(0,0,0,0,0,0,0,0,0,0,0,0,0,0,0,0,0,0,0,0,0,0,0,0,0,0,0,0,0,0,E~
K20,0,0,0,0,0,0,0,0,0,0,0)';
      PINUSE='POWER';
      NO_LOAD_CHECK='Both';
      NO_IO_CHECK='Both';
      NO_ASSERT_CHECK='TRUE';
      NO_DIR_CHECK='TRUE';
      ALLOW_CONNECT='TRUE';
    'VSS1355':
      PIN_NUMBER='(0,0,0,0,0,0,0,0,0,0,0,0,0,0,0,0,0,0,0,0,0,0,0,0,0,0,0,0,0,0,E~
K16,0,0,0,0,0,0,0,0,0,0,0)';
      PINUSE='POWER';
      NO_LOAD_CHECK='Both';
      NO_IO_CHECK='Both';
      NO_ASSERT_CHECK='TRUE';
      NO_DIR_CHECK='TRUE';
      ALLOW_CONNECT='TRUE';
    'VSS1347':
      PIN_NUMBER='(0,0,0,0,0,0,0,0,0,0,0,0,0,0,0,0,0,0,0,0,0,0,0,0,0,0,0,0,0,0,E~
J72,0,0,0,0,0,0,0,0,0,0,0)';
      PINUSE='POWER';
      NO_LOAD_CHECK='Both';
      NO_IO_CHECK='Both';
      NO_ASSERT_CHECK='TRUE';
      NO_DIR_CHECK='TRUE';
      ALLOW_CONNECT='TRUE';
    'VSS1345':
      PIN_NUMBER='(0,0,0,0,0,0,0,0,0,0,0,0,0,0,0,0,0,0,0,0,0,0,0,0,0,0,0,0,0,0,E~
J68,0,0,0,0,0,0,0,0,0,0,0)';
      PINUSE='POWER';
      NO_LOAD_CHECK='Both';
      NO_IO_CHECK='Both';
      NO_ASSERT_CHECK='TRUE';
      NO_DIR_CHECK='TRUE';
      ALLOW_CONNECT='TRUE';
    'VSS1343':
      PIN_NUMBER='(0,0,0,0,0,0,0,0,0,0,0,0,0,0,0,0,0,0,0,0,0,0,0,0,0,0,0,0,0,0,E~
J62,0,0,0,0,0,0,0,0,0,0,0)';
      PINUSE='POWER';
      NO_LOAD_CHECK='Both';
      NO_IO_CHECK='Both';
      NO_ASSERT_CHECK='TRUE';
      NO_DIR_CHECK='TRUE';
      ALLOW_CONNECT='TRUE';
    'VSS1340':
      PIN_NUMBER='(0,0,0,0,0,0,0,0,0,0,0,0,0,0,0,0,0,0,0,0,0,0,0,0,0,0,0,0,0,0,E~
J54,0,0,0,0,0,0,0,0,0,0,0)';
      PINUSE='POWER';
      NO_LOAD_CHECK='Both';
      NO_IO_CHECK='Both';
      NO_ASSERT_CHECK='TRUE';
      NO_DIR_CHECK='TRUE';
      ALLOW_CONNECT='TRUE';
    'VSS1334':
      PIN_NUMBER='(0,0,0,0,0,0,0,0,0,0,0,0,0,0,0,0,0,0,0,0,0,0,0,0,0,0,0,0,0,0,E~
J35,0,0,0,0,0,0,0,0,0,0,0)';
      PINUSE='POWER';
      NO_LOAD_CHECK='Both';
      NO_IO_CHECK='Both';
      NO_ASSERT_CHECK='TRUE';
      NO_DIR_CHECK='TRUE';
      ALLOW_CONNECT='TRUE';
    'VSS1331':
      PIN_NUMBER='(0,0,0,0,0,0,0,0,0,0,0,0,0,0,0,0,0,0,0,0,0,0,0,0,0,0,0,0,0,0,E~
J25,0,0,0,0,0,0,0,0,0,0,0)';
      PINUSE='POWER';
      NO_LOAD_CHECK='Both';
      NO_IO_CHECK='Both';
      NO_ASSERT_CHECK='TRUE';
      NO_DIR_CHECK='TRUE';
      ALLOW_CONNECT='TRUE';
    'VSS1328':
      PIN_NUMBER='(0,0,0,0,0,0,0,0,0,0,0,0,0,0,0,0,0,0,0,0,0,0,0,0,0,0,0,0,0,0,E~
J17,0,0,0,0,0,0,0,0,0,0,0)';
      PINUSE='POWER';
      NO_LOAD_CHECK='Both';
      NO_IO_CHECK='Both';
      NO_ASSERT_CHECK='TRUE';
      NO_DIR_CHECK='TRUE';
      ALLOW_CONNECT='TRUE';
    'VSS1325':
      PIN_NUMBER='(0,0,0,0,0,0,0,0,0,0,0,0,0,0,0,0,0,0,0,0,0,0,0,0,0,0,0,0,0,0,E~
J11,0,0,0,0,0,0,0,0,0,0,0)';
      PINUSE='POWER';
      NO_LOAD_CHECK='Both';
      NO_IO_CHECK='Both';
      NO_ASSERT_CHECK='TRUE';
      NO_DIR_CHECK='TRUE';
      ALLOW_CONNECT='TRUE';
    'VSS1322':
      PIN_NUMBER='(0,0,0,0,0,0,0,0,0,0,0,0,0,0,0,0,0,0,0,0,0,0,0,0,0,0,0,0,0,0,E~
H79,0,0,0,0,0,0,0,0,0,0,0)';
      PINUSE='POWER';
      NO_LOAD_CHECK='Both';
      NO_IO_CHECK='Both';
      NO_ASSERT_CHECK='TRUE';
      NO_DIR_CHECK='TRUE';
      ALLOW_CONNECT='TRUE';
    'VSS1320':
      PIN_NUMBER='(0,0,0,0,0,0,0,0,0,0,0,0,0,0,0,0,0,0,0,0,0,0,0,0,0,0,0,0,0,0,E~
H67,0,0,0,0,0,0,0,0,0,0,0)';
      PINUSE='POWER';
      NO_LOAD_CHECK='Both';
      NO_IO_CHECK='Both';
      NO_ASSERT_CHECK='TRUE';
      NO_DIR_CHECK='TRUE';
      ALLOW_CONNECT='TRUE';
    'VSS1319':
      PIN_NUMBER='(0,0,0,0,0,0,0,0,0,0,0,0,0,0,0,0,0,0,0,0,0,0,0,0,0,0,0,0,0,0,E~
H61,0,0,0,0,0,0,0,0,0,0,0)';
      PINUSE='POWER';
      NO_LOAD_CHECK='Both';
      NO_IO_CHECK='Both';
      NO_ASSERT_CHECK='TRUE';
      NO_DIR_CHECK='TRUE';
      ALLOW_CONNECT='TRUE';
    'VSS1315':
      PIN_NUMBER='(0,0,0,0,0,0,0,0,0,0,0,0,0,0,0,0,0,0,0,0,0,0,0,0,0,0,0,0,0,0,E~
H55,0,0,0,0,0,0,0,0,0,0,0)';
      PINUSE='POWER';
      NO_LOAD_CHECK='Both';
      NO_IO_CHECK='Both';
      NO_ASSERT_CHECK='TRUE';
      NO_DIR_CHECK='TRUE';
      ALLOW_CONNECT='TRUE';
    'VSS1312':
      PIN_NUMBER='(0,0,0,0,0,0,0,0,0,0,0,0,0,0,0,0,0,0,0,0,0,0,0,0,0,0,0,0,0,0,E~
H42,0,0,0,0,0,0,0,0,0,0,0)';
      PINUSE='POWER';
      NO_LOAD_CHECK='Both';
      NO_IO_CHECK='Both';
      NO_ASSERT_CHECK='TRUE';
      NO_DIR_CHECK='TRUE';
      ALLOW_CONNECT='TRUE';
    'VSS1420':
      PIN_NUMBER='(0,0,0,0,0,0,0,0,0,0,0,0,0,0,0,0,0,0,0,0,0,0,0,0,0,0,0,0,0,0,0~
,EH4,0,0,0,0,0,0,0,0,0,0)';
      PINUSE='POWER';
      NO_LOAD_CHECK='Both';
      NO_IO_CHECK='Both';
      NO_ASSERT_CHECK='TRUE';
      NO_DIR_CHECK='TRUE';
      ALLOW_CONNECT='TRUE';
    'VSS1418':
      PIN_NUMBER='(0,0,0,0,0,0,0,0,0,0,0,0,0,0,0,0,0,0,0,0,0,0,0,0,0,0,0,0,0,0,0~
,EH30,0,0,0,0,0,0,0,0,0,0)';
      PINUSE='POWER';
      NO_LOAD_CHECK='Both';
      NO_IO_CHECK='Both';
      NO_ASSERT_CHECK='TRUE';
      NO_DIR_CHECK='TRUE';
      ALLOW_CONNECT='TRUE';
    'VSS1417':
      PIN_NUMBER='(0,0,0,0,0,0,0,0,0,0,0,0,0,0,0,0,0,0,0,0,0,0,0,0,0,0,0,0,0,0,0~
,EH24,0,0,0,0,0,0,0,0,0,0)';
      PINUSE='POWER';
      NO_LOAD_CHECK='Both';
      NO_IO_CHECK='Both';
      NO_ASSERT_CHECK='TRUE';
      NO_DIR_CHECK='TRUE';
      ALLOW_CONNECT='TRUE';
    'VSS1416':
      PIN_NUMBER='(0,0,0,0,0,0,0,0,0,0,0,0,0,0,0,0,0,0,0,0,0,0,0,0,0,0,0,0,0,0,0~
,EH16,0,0,0,0,0,0,0,0,0,0)';
      PINUSE='POWER';
      NO_LOAD_CHECK='Both';
      NO_IO_CHECK='Both';
      NO_ASSERT_CHECK='TRUE';
      NO_DIR_CHECK='TRUE';
      ALLOW_CONNECT='TRUE';
    'VSS1415':
      PIN_NUMBER='(0,0,0,0,0,0,0,0,0,0,0,0,0,0,0,0,0,0,0,0,0,0,0,0,0,0,0,0,0,0,0~
,EG90,0,0,0,0,0,0,0,0,0,0)';
      PINUSE='POWER';
      NO_LOAD_CHECK='Both';
      NO_IO_CHECK='Both';
      NO_ASSERT_CHECK='TRUE';
      NO_DIR_CHECK='TRUE';
      ALLOW_CONNECT='TRUE';
    'VSS1414':
      PIN_NUMBER='(0,0,0,0,0,0,0,0,0,0,0,0,0,0,0,0,0,0,0,0,0,0,0,0,0,0,0,0,0,0,0~
,EG9,0,0,0,0,0,0,0,0,0,0)';
      PINUSE='POWER';
      NO_LOAD_CHECK='Both';
      NO_IO_CHECK='Both';
      NO_ASSERT_CHECK='TRUE';
      NO_DIR_CHECK='TRUE';
      ALLOW_CONNECT='TRUE';
    'VSS1413':
      PIN_NUMBER='(0,0,0,0,0,0,0,0,0,0,0,0,0,0,0,0,0,0,0,0,0,0,0,0,0,0,0,0,0,0,0~
,EG88,0,0,0,0,0,0,0,0,0,0)';
      PINUSE='POWER';
      NO_LOAD_CHECK='Both';
      NO_IO_CHECK='Both';
      NO_ASSERT_CHECK='TRUE';
      NO_DIR_CHECK='TRUE';
      ALLOW_CONNECT='TRUE';
    'VSS1412':
      PIN_NUMBER='(0,0,0,0,0,0,0,0,0,0,0,0,0,0,0,0,0,0,0,0,0,0,0,0,0,0,0,0,0,0,0~
,EG86,0,0,0,0,0,0,0,0,0,0)';
      PINUSE='POWER';
      NO_LOAD_CHECK='Both';
      NO_IO_CHECK='Both';
      NO_ASSERT_CHECK='TRUE';
      NO_DIR_CHECK='TRUE';
      ALLOW_CONNECT='TRUE';
    'VSS1411':
      PIN_NUMBER='(0,0,0,0,0,0,0,0,0,0,0,0,0,0,0,0,0,0,0,0,0,0,0,0,0,0,0,0,0,0,0~
,EG84,0,0,0,0,0,0,0,0,0,0)';
      PINUSE='POWER';
      NO_LOAD_CHECK='Both';
      NO_IO_CHECK='Both';
      NO_ASSERT_CHECK='TRUE';
      NO_DIR_CHECK='TRUE';
      ALLOW_CONNECT='TRUE';
    'VSS1410':
      PIN_NUMBER='(0,0,0,0,0,0,0,0,0,0,0,0,0,0,0,0,0,0,0,0,0,0,0,0,0,0,0,0,0,0,0~
,EG82,0,0,0,0,0,0,0,0,0,0)';
      PINUSE='POWER';
      NO_LOAD_CHECK='Both';
      NO_IO_CHECK='Both';
      NO_ASSERT_CHECK='TRUE';
      NO_DIR_CHECK='TRUE';
      ALLOW_CONNECT='TRUE';
    'VSS1408':
      PIN_NUMBER='(0,0,0,0,0,0,0,0,0,0,0,0,0,0,0,0,0,0,0,0,0,0,0,0,0,0,0,0,0,0,0~
,EG39,0,0,0,0,0,0,0,0,0,0)';
      PINUSE='POWER';
      NO_LOAD_CHECK='Both';
      NO_IO_CHECK='Both';
      NO_ASSERT_CHECK='TRUE';
      NO_DIR_CHECK='TRUE';
      ALLOW_CONNECT='TRUE';
    'VSS1407':
      PIN_NUMBER='(0,0,0,0,0,0,0,0,0,0,0,0,0,0,0,0,0,0,0,0,0,0,0,0,0,0,0,0,0,0,0~
,EF87,0,0,0,0,0,0,0,0,0,0)';
      PINUSE='POWER';
      NO_LOAD_CHECK='Both';
      NO_IO_CHECK='Both';
      NO_ASSERT_CHECK='TRUE';
      NO_DIR_CHECK='TRUE';
      ALLOW_CONNECT='TRUE';
    'VSS1406':
      PIN_NUMBER='(0,0,0,0,0,0,0,0,0,0,0,0,0,0,0,0,0,0,0,0,0,0,0,0,0,0,0,0,0,0,0~
,EF85,0,0,0,0,0,0,0,0,0,0)';
      PINUSE='POWER';
      NO_LOAD_CHECK='Both';
      NO_IO_CHECK='Both';
      NO_ASSERT_CHECK='TRUE';
      NO_DIR_CHECK='TRUE';
      ALLOW_CONNECT='TRUE';
    'VSS1404':
      PIN_NUMBER='(0,0,0,0,0,0,0,0,0,0,0,0,0,0,0,0,0,0,0,0,0,0,0,0,0,0,0,0,0,0,0~
,EF8,0,0,0,0,0,0,0,0,0,0)';
      PINUSE='POWER';
      NO_LOAD_CHECK='Both';
      NO_IO_CHECK='Both';
      NO_ASSERT_CHECK='TRUE';
      NO_DIR_CHECK='TRUE';
      ALLOW_CONNECT='TRUE';
    'VSS1403':
      PIN_NUMBER='(0,0,0,0,0,0,0,0,0,0,0,0,0,0,0,0,0,0,0,0,0,0,0,0,0,0,0,0,0,0,0~
,EF77,0,0,0,0,0,0,0,0,0,0)';
      PINUSE='POWER';
      NO_LOAD_CHECK='Both';
      NO_IO_CHECK='Both';
      NO_ASSERT_CHECK='TRUE';
      NO_DIR_CHECK='TRUE';
      ALLOW_CONNECT='TRUE';
    'VSS1402':
      PIN_NUMBER='(0,0,0,0,0,0,0,0,0,0,0,0,0,0,0,0,0,0,0,0,0,0,0,0,0,0,0,0,0,0,0~
,EF71,0,0,0,0,0,0,0,0,0,0)';
      PINUSE='POWER';
      NO_LOAD_CHECK='Both';
      NO_IO_CHECK='Both';
      NO_ASSERT_CHECK='TRUE';
      NO_DIR_CHECK='TRUE';
      ALLOW_CONNECT='TRUE';
    'VSS1399':
      PIN_NUMBER='(0,0,0,0,0,0,0,0,0,0,0,0,0,0,0,0,0,0,0,0,0,0,0,0,0,0,0,0,0,0,0~
,EF69,0,0,0,0,0,0,0,0,0,0)';
      PINUSE='POWER';
      NO_LOAD_CHECK='Both';
      NO_IO_CHECK='Both';
      NO_ASSERT_CHECK='TRUE';
      NO_DIR_CHECK='TRUE';
      ALLOW_CONNECT='TRUE';
    'VSS1395':
      PIN_NUMBER='(0,0,0,0,0,0,0,0,0,0,0,0,0,0,0,0,0,0,0,0,0,0,0,0,0,0,0,0,0,0,0~
,EF67,0,0,0,0,0,0,0,0,0,0)';
      PINUSE='POWER';
      NO_LOAD_CHECK='Both';
      NO_IO_CHECK='Both';
      NO_ASSERT_CHECK='TRUE';
      NO_DIR_CHECK='TRUE';
      ALLOW_CONNECT='TRUE';
    'VSS1393':
      PIN_NUMBER='(0,0,0,0,0,0,0,0,0,0,0,0,0,0,0,0,0,0,0,0,0,0,0,0,0,0,0,0,0,0,0~
,EF65,0,0,0,0,0,0,0,0,0,0)';
      PINUSE='POWER';
      NO_LOAD_CHECK='Both';
      NO_IO_CHECK='Both';
      NO_ASSERT_CHECK='TRUE';
      NO_DIR_CHECK='TRUE';
      ALLOW_CONNECT='TRUE';
    'VSS1392':
      PIN_NUMBER='(0,0,0,0,0,0,0,0,0,0,0,0,0,0,0,0,0,0,0,0,0,0,0,0,0,0,0,0,0,0,0~
,EF63,0,0,0,0,0,0,0,0,0,0)';
      PINUSE='POWER';
      NO_LOAD_CHECK='Both';
      NO_IO_CHECK='Both';
      NO_ASSERT_CHECK='TRUE';
      NO_DIR_CHECK='TRUE';
      ALLOW_CONNECT='TRUE';
    'VSS1390':
      PIN_NUMBER='(0,0,0,0,0,0,0,0,0,0,0,0,0,0,0,0,0,0,0,0,0,0,0,0,0,0,0,0,0,0,0~
,EF61,0,0,0,0,0,0,0,0,0,0)';
      PINUSE='POWER';
      NO_LOAD_CHECK='Both';
      NO_IO_CHECK='Both';
      NO_ASSERT_CHECK='TRUE';
      NO_DIR_CHECK='TRUE';
      ALLOW_CONNECT='TRUE';
    'VSS1389':
      PIN_NUMBER='(0,0,0,0,0,0,0,0,0,0,0,0,0,0,0,0,0,0,0,0,0,0,0,0,0,0,0,0,0,0,0~
,EF59,0,0,0,0,0,0,0,0,0,0)';
      PINUSE='POWER';
      NO_LOAD_CHECK='Both';
      NO_IO_CHECK='Both';
      NO_ASSERT_CHECK='TRUE';
      NO_DIR_CHECK='TRUE';
      ALLOW_CONNECT='TRUE';
    'VSS1388':
      PIN_NUMBER='(0,0,0,0,0,0,0,0,0,0,0,0,0,0,0,0,0,0,0,0,0,0,0,0,0,0,0,0,0,0,0~
,EF57,0,0,0,0,0,0,0,0,0,0)';
      PINUSE='POWER';
      NO_LOAD_CHECK='Both';
      NO_IO_CHECK='Both';
      NO_ASSERT_CHECK='TRUE';
      NO_DIR_CHECK='TRUE';
      ALLOW_CONNECT='TRUE';
    'VSS1387':
      PIN_NUMBER='(0,0,0,0,0,0,0,0,0,0,0,0,0,0,0,0,0,0,0,0,0,0,0,0,0,0,0,0,0,0,0~
,EF55,0,0,0,0,0,0,0,0,0,0)';
      PINUSE='POWER';
      NO_LOAD_CHECK='Both';
      NO_IO_CHECK='Both';
      NO_ASSERT_CHECK='TRUE';
      NO_DIR_CHECK='TRUE';
      ALLOW_CONNECT='TRUE';
    'VSS1386':
      PIN_NUMBER='(0,0,0,0,0,0,0,0,0,0,0,0,0,0,0,0,0,0,0,0,0,0,0,0,0,0,0,0,0,0,0~
,EF53,0,0,0,0,0,0,0,0,0,0)';
      PINUSE='POWER';
      NO_LOAD_CHECK='Both';
      NO_IO_CHECK='Both';
      NO_ASSERT_CHECK='TRUE';
      NO_DIR_CHECK='TRUE';
      ALLOW_CONNECT='TRUE';
    'VSS1385':
      PIN_NUMBER='(0,0,0,0,0,0,0,0,0,0,0,0,0,0,0,0,0,0,0,0,0,0,0,0,0,0,0,0,0,0,0~
,EF49,0,0,0,0,0,0,0,0,0,0)';
      PINUSE='POWER';
      NO_LOAD_CHECK='Both';
      NO_IO_CHECK='Both';
      NO_ASSERT_CHECK='TRUE';
      NO_DIR_CHECK='TRUE';
      ALLOW_CONNECT='TRUE';
    'VSS1384':
      PIN_NUMBER='(0,0,0,0,0,0,0,0,0,0,0,0,0,0,0,0,0,0,0,0,0,0,0,0,0,0,0,0,0,0,0~
,EF47,0,0,0,0,0,0,0,0,0,0)';
      PINUSE='POWER';
      NO_LOAD_CHECK='Both';
      NO_IO_CHECK='Both';
      NO_ASSERT_CHECK='TRUE';
      NO_DIR_CHECK='TRUE';
      ALLOW_CONNECT='TRUE';
    'VSS1383':
      PIN_NUMBER='(0,0,0,0,0,0,0,0,0,0,0,0,0,0,0,0,0,0,0,0,0,0,0,0,0,0,0,0,0,0,0~
,EF44,0,0,0,0,0,0,0,0,0,0)';
      PINUSE='POWER';
      NO_LOAD_CHECK='Both';
      NO_IO_CHECK='Both';
      NO_ASSERT_CHECK='TRUE';
      NO_DIR_CHECK='TRUE';
      ALLOW_CONNECT='TRUE';
    'VSS1382':
      PIN_NUMBER='(0,0,0,0,0,0,0,0,0,0,0,0,0,0,0,0,0,0,0,0,0,0,0,0,0,0,0,0,0,0,0~
,EF42,0,0,0,0,0,0,0,0,0,0)';
      PINUSE='POWER';
      NO_LOAD_CHECK='Both';
      NO_IO_CHECK='Both';
      NO_ASSERT_CHECK='TRUE';
      NO_DIR_CHECK='TRUE';
      ALLOW_CONNECT='TRUE';
    'VSS1376':
      PIN_NUMBER='(0,0,0,0,0,0,0,0,0,0,0,0,0,0,0,0,0,0,0,0,0,0,0,0,0,0,0,0,0,0,0~
,EF40,0,0,0,0,0,0,0,0,0,0)';
      PINUSE='POWER';
      NO_LOAD_CHECK='Both';
      NO_IO_CHECK='Both';
      NO_ASSERT_CHECK='TRUE';
      NO_DIR_CHECK='TRUE';
      ALLOW_CONNECT='TRUE';
    'VSS1374':
      PIN_NUMBER='(0,0,0,0,0,0,0,0,0,0,0,0,0,0,0,0,0,0,0,0,0,0,0,0,0,0,0,0,0,0,0~
,EF4,0,0,0,0,0,0,0,0,0,0)';
      PINUSE='POWER';
      NO_LOAD_CHECK='Both';
      NO_IO_CHECK='Both';
      NO_ASSERT_CHECK='TRUE';
      NO_DIR_CHECK='TRUE';
      ALLOW_CONNECT='TRUE';
    'VSS1373':
      PIN_NUMBER='(0,0,0,0,0,0,0,0,0,0,0,0,0,0,0,0,0,0,0,0,0,0,0,0,0,0,0,0,0,0,0~
,EF38,0,0,0,0,0,0,0,0,0,0)';
      PINUSE='POWER';
      NO_LOAD_CHECK='Both';
      NO_IO_CHECK='Both';
      NO_ASSERT_CHECK='TRUE';
      NO_DIR_CHECK='TRUE';
      ALLOW_CONNECT='TRUE';
    'VSS1370':
      PIN_NUMBER='(0,0,0,0,0,0,0,0,0,0,0,0,0,0,0,0,0,0,0,0,0,0,0,0,0,0,0,0,0,0,0~
,EF36,0,0,0,0,0,0,0,0,0,0)';
      PINUSE='POWER';
      NO_LOAD_CHECK='Both';
      NO_IO_CHECK='Both';
      NO_ASSERT_CHECK='TRUE';
      NO_DIR_CHECK='TRUE';
      ALLOW_CONNECT='TRUE';
    'VSS1367':
      PIN_NUMBER='(0,0,0,0,0,0,0,0,0,0,0,0,0,0,0,0,0,0,0,0,0,0,0,0,0,0,0,0,0,0,0~
,EF34,0,0,0,0,0,0,0,0,0,0)';
      PINUSE='POWER';
      NO_LOAD_CHECK='Both';
      NO_IO_CHECK='Both';
      NO_ASSERT_CHECK='TRUE';
      NO_DIR_CHECK='TRUE';
      ALLOW_CONNECT='TRUE';
    'VSS1365':
      PIN_NUMBER='(0,0,0,0,0,0,0,0,0,0,0,0,0,0,0,0,0,0,0,0,0,0,0,0,0,0,0,0,0,0,0~
,EF32,0,0,0,0,0,0,0,0,0,0)';
      PINUSE='POWER';
      NO_LOAD_CHECK='Both';
      NO_IO_CHECK='Both';
      NO_ASSERT_CHECK='TRUE';
      NO_DIR_CHECK='TRUE';
      ALLOW_CONNECT='TRUE';
    'VSS1364':
      PIN_NUMBER='(0,0,0,0,0,0,0,0,0,0,0,0,0,0,0,0,0,0,0,0,0,0,0,0,0,0,0,0,0,0,0~
,EF30,0,0,0,0,0,0,0,0,0,0)';
      PINUSE='POWER';
      NO_LOAD_CHECK='Both';
      NO_IO_CHECK='Both';
      NO_ASSERT_CHECK='TRUE';
      NO_DIR_CHECK='TRUE';
      ALLOW_CONNECT='TRUE';
    'VSS1363':
      PIN_NUMBER='(0,0,0,0,0,0,0,0,0,0,0,0,0,0,0,0,0,0,0,0,0,0,0,0,0,0,0,0,0,0,0~
,EF28,0,0,0,0,0,0,0,0,0,0)';
      PINUSE='POWER';
      NO_LOAD_CHECK='Both';
      NO_IO_CHECK='Both';
      NO_ASSERT_CHECK='TRUE';
      NO_DIR_CHECK='TRUE';
      ALLOW_CONNECT='TRUE';
    'VSS1362':
      PIN_NUMBER='(0,0,0,0,0,0,0,0,0,0,0,0,0,0,0,0,0,0,0,0,0,0,0,0,0,0,0,0,0,0,0~
,EF26,0,0,0,0,0,0,0,0,0,0)';
      PINUSE='POWER';
      NO_LOAD_CHECK='Both';
      NO_IO_CHECK='Both';
      NO_ASSERT_CHECK='TRUE';
      NO_DIR_CHECK='TRUE';
      ALLOW_CONNECT='TRUE';
    'VSS1361':
      PIN_NUMBER='(0,0,0,0,0,0,0,0,0,0,0,0,0,0,0,0,0,0,0,0,0,0,0,0,0,0,0,0,0,0,0~
,EF24,0,0,0,0,0,0,0,0,0,0)';
      PINUSE='POWER';
      NO_LOAD_CHECK='Both';
      NO_IO_CHECK='Both';
      NO_ASSERT_CHECK='TRUE';
      NO_DIR_CHECK='TRUE';
      ALLOW_CONNECT='TRUE';
    'VSS1360':
      PIN_NUMBER='(0,0,0,0,0,0,0,0,0,0,0,0,0,0,0,0,0,0,0,0,0,0,0,0,0,0,0,0,0,0,0~
,EF22,0,0,0,0,0,0,0,0,0,0)';
      PINUSE='POWER';
      NO_LOAD_CHECK='Both';
      NO_IO_CHECK='Both';
      NO_ASSERT_CHECK='TRUE';
      NO_DIR_CHECK='TRUE';
      ALLOW_CONNECT='TRUE';
    'VSS1358':
      PIN_NUMBER='(0,0,0,0,0,0,0,0,0,0,0,0,0,0,0,0,0,0,0,0,0,0,0,0,0,0,0,0,0,0,0~
,EF20,0,0,0,0,0,0,0,0,0,0)';
      PINUSE='POWER';
      NO_LOAD_CHECK='Both';
      NO_IO_CHECK='Both';
      NO_ASSERT_CHECK='TRUE';
      NO_DIR_CHECK='TRUE';
      ALLOW_CONNECT='TRUE';
    'VSS1356':
      PIN_NUMBER='(0,0,0,0,0,0,0,0,0,0,0,0,0,0,0,0,0,0,0,0,0,0,0,0,0,0,0,0,0,0,0~
,EF2,0,0,0,0,0,0,0,0,0,0)';
      PINUSE='POWER';
      NO_LOAD_CHECK='Both';
      NO_IO_CHECK='Both';
      NO_ASSERT_CHECK='TRUE';
      NO_DIR_CHECK='TRUE';
      ALLOW_CONNECT='TRUE';
    'VSS1354':
      PIN_NUMBER='(0,0,0,0,0,0,0,0,0,0,0,0,0,0,0,0,0,0,0,0,0,0,0,0,0,0,0,0,0,0,0~
,EF18,0,0,0,0,0,0,0,0,0,0)';
      PINUSE='POWER';
      NO_LOAD_CHECK='Both';
      NO_IO_CHECK='Both';
      NO_ASSERT_CHECK='TRUE';
      NO_DIR_CHECK='TRUE';
      ALLOW_CONNECT='TRUE';
    'VSS1353':
      PIN_NUMBER='(0,0,0,0,0,0,0,0,0,0,0,0,0,0,0,0,0,0,0,0,0,0,0,0,0,0,0,0,0,0,0~
,EF16,0,0,0,0,0,0,0,0,0,0)';
      PINUSE='POWER';
      NO_LOAD_CHECK='Both';
      NO_IO_CHECK='Both';
      NO_ASSERT_CHECK='TRUE';
      NO_DIR_CHECK='TRUE';
      ALLOW_CONNECT='TRUE';
    'VSS1352':
      PIN_NUMBER='(0,0,0,0,0,0,0,0,0,0,0,0,0,0,0,0,0,0,0,0,0,0,0,0,0,0,0,0,0,0,0~
,EF12,0,0,0,0,0,0,0,0,0,0)';
      PINUSE='POWER';
      NO_LOAD_CHECK='Both';
      NO_IO_CHECK='Both';
      NO_ASSERT_CHECK='TRUE';
      NO_DIR_CHECK='TRUE';
      ALLOW_CONNECT='TRUE';
    'VSS1351':
      PIN_NUMBER='(0,0,0,0,0,0,0,0,0,0,0,0,0,0,0,0,0,0,0,0,0,0,0,0,0,0,0,0,0,0,0~
,EE88,0,0,0,0,0,0,0,0,0,0)';
      PINUSE='POWER';
      NO_LOAD_CHECK='Both';
      NO_IO_CHECK='Both';
      NO_ASSERT_CHECK='TRUE';
      NO_DIR_CHECK='TRUE';
      ALLOW_CONNECT='TRUE';
    'VSS1350':
      PIN_NUMBER='(0,0,0,0,0,0,0,0,0,0,0,0,0,0,0,0,0,0,0,0,0,0,0,0,0,0,0,0,0,0,0~
,EE80,0,0,0,0,0,0,0,0,0,0)';
      PINUSE='POWER';
      NO_LOAD_CHECK='Both';
      NO_IO_CHECK='Both';
      NO_ASSERT_CHECK='TRUE';
      NO_DIR_CHECK='TRUE';
      ALLOW_CONNECT='TRUE';
    'VSS1349':
      PIN_NUMBER='(0,0,0,0,0,0,0,0,0,0,0,0,0,0,0,0,0,0,0,0,0,0,0,0,0,0,0,0,0,0,0~
,EE78,0,0,0,0,0,0,0,0,0,0)';
      PINUSE='POWER';
      NO_LOAD_CHECK='Both';
      NO_IO_CHECK='Both';
      NO_ASSERT_CHECK='TRUE';
      NO_DIR_CHECK='TRUE';
      ALLOW_CONNECT='TRUE';
    'VSS1348':
      PIN_NUMBER='(0,0,0,0,0,0,0,0,0,0,0,0,0,0,0,0,0,0,0,0,0,0,0,0,0,0,0,0,0,0,0~
,ED8,0,0,0,0,0,0,0,0,0,0)';
      PINUSE='POWER';
      NO_LOAD_CHECK='Both';
      NO_IO_CHECK='Both';
      NO_ASSERT_CHECK='TRUE';
      NO_DIR_CHECK='TRUE';
      ALLOW_CONNECT='TRUE';
    'VSS1346':
      PIN_NUMBER='(0,0,0,0,0,0,0,0,0,0,0,0,0,0,0,0,0,0,0,0,0,0,0,0,0,0,0,0,0,0,0~
,ED49,0,0,0,0,0,0,0,0,0,0)';
      PINUSE='POWER';
      NO_LOAD_CHECK='Both';
      NO_IO_CHECK='Both';
      NO_ASSERT_CHECK='TRUE';
      NO_DIR_CHECK='TRUE';
      ALLOW_CONNECT='TRUE';
    'VSS1344':
      PIN_NUMBER='(0,0,0,0,0,0,0,0,0,0,0,0,0,0,0,0,0,0,0,0,0,0,0,0,0,0,0,0,0,0,0~
,ED4,0,0,0,0,0,0,0,0,0,0)';
      PINUSE='POWER';
      NO_LOAD_CHECK='Both';
      NO_IO_CHECK='Both';
      NO_ASSERT_CHECK='TRUE';
      NO_DIR_CHECK='TRUE';
      ALLOW_CONNECT='TRUE';
    'VSS1342':
      PIN_NUMBER='(0,0,0,0,0,0,0,0,0,0,0,0,0,0,0,0,0,0,0,0,0,0,0,0,0,0,0,0,0,0,0~
,ED36,0,0,0,0,0,0,0,0,0,0)';
      PINUSE='POWER';
      NO_LOAD_CHECK='Both';
      NO_IO_CHECK='Both';
      NO_ASSERT_CHECK='TRUE';
      NO_DIR_CHECK='TRUE';
      ALLOW_CONNECT='TRUE';
    'VSS1341':
      PIN_NUMBER='(0,0,0,0,0,0,0,0,0,0,0,0,0,0,0,0,0,0,0,0,0,0,0,0,0,0,0,0,0,0,0~
,ED30,0,0,0,0,0,0,0,0,0,0)';
      PINUSE='POWER';
      NO_LOAD_CHECK='Both';
      NO_IO_CHECK='Both';
      NO_ASSERT_CHECK='TRUE';
      NO_DIR_CHECK='TRUE';
      ALLOW_CONNECT='TRUE';
    'VSS1339':
      PIN_NUMBER='(0,0,0,0,0,0,0,0,0,0,0,0,0,0,0,0,0,0,0,0,0,0,0,0,0,0,0,0,0,0,0~
,ED24,0,0,0,0,0,0,0,0,0,0)';
      PINUSE='POWER';
      NO_LOAD_CHECK='Both';
      NO_IO_CHECK='Both';
      NO_ASSERT_CHECK='TRUE';
      NO_DIR_CHECK='TRUE';
      ALLOW_CONNECT='TRUE';
    'VSS1338':
      PIN_NUMBER='(0,0,0,0,0,0,0,0,0,0,0,0,0,0,0,0,0,0,0,0,0,0,0,0,0,0,0,0,0,0,0~
,ED16,0,0,0,0,0,0,0,0,0,0)';
      PINUSE='POWER';
      NO_LOAD_CHECK='Both';
      NO_IO_CHECK='Both';
      NO_ASSERT_CHECK='TRUE';
      NO_DIR_CHECK='TRUE';
      ALLOW_CONNECT='TRUE';
    'VSS1337':
      PIN_NUMBER='(0,0,0,0,0,0,0,0,0,0,0,0,0,0,0,0,0,0,0,0,0,0,0,0,0,0,0,0,0,0,0~
,EC9,0,0,0,0,0,0,0,0,0,0)';
      PINUSE='POWER';
      NO_LOAD_CHECK='Both';
      NO_IO_CHECK='Both';
      NO_ASSERT_CHECK='TRUE';
      NO_DIR_CHECK='TRUE';
      ALLOW_CONNECT='TRUE';
    'VSS1336':
      PIN_NUMBER='(0,0,0,0,0,0,0,0,0,0,0,0,0,0,0,0,0,0,0,0,0,0,0,0,0,0,0,0,0,0,0~
,EC88,0,0,0,0,0,0,0,0,0,0)';
      PINUSE='POWER';
      NO_LOAD_CHECK='Both';
      NO_IO_CHECK='Both';
      NO_ASSERT_CHECK='TRUE';
      NO_DIR_CHECK='TRUE';
      ALLOW_CONNECT='TRUE';
    'VSS1335':
      PIN_NUMBER='(0,0,0,0,0,0,0,0,0,0,0,0,0,0,0,0,0,0,0,0,0,0,0,0,0,0,0,0,0,0,0~
,EC84,0,0,0,0,0,0,0,0,0,0)';
      PINUSE='POWER';
      NO_LOAD_CHECK='Both';
      NO_IO_CHECK='Both';
      NO_ASSERT_CHECK='TRUE';
      NO_DIR_CHECK='TRUE';
      ALLOW_CONNECT='TRUE';
    'VSS1333':
      PIN_NUMBER='(0,0,0,0,0,0,0,0,0,0,0,0,0,0,0,0,0,0,0,0,0,0,0,0,0,0,0,0,0,0,0~
,EC82,0,0,0,0,0,0,0,0,0,0)';
      PINUSE='POWER';
      NO_LOAD_CHECK='Both';
      NO_IO_CHECK='Both';
      NO_ASSERT_CHECK='TRUE';
      NO_DIR_CHECK='TRUE';
      ALLOW_CONNECT='TRUE';
    'VSS1332':
      PIN_NUMBER='(0,0,0,0,0,0,0,0,0,0,0,0,0,0,0,0,0,0,0,0,0,0,0,0,0,0,0,0,0,0,0~
,EC74,0,0,0,0,0,0,0,0,0,0)';
      PINUSE='POWER';
      NO_LOAD_CHECK='Both';
      NO_IO_CHECK='Both';
      NO_ASSERT_CHECK='TRUE';
      NO_DIR_CHECK='TRUE';
      ALLOW_CONNECT='TRUE';
    'VSS1330':
      PIN_NUMBER='(0,0,0,0,0,0,0,0,0,0,0,0,0,0,0,0,0,0,0,0,0,0,0,0,0,0,0,0,0,0,0~
,EC72,0,0,0,0,0,0,0,0,0,0)';
      PINUSE='POWER';
      NO_LOAD_CHECK='Both';
      NO_IO_CHECK='Both';
      NO_ASSERT_CHECK='TRUE';
      NO_DIR_CHECK='TRUE';
      ALLOW_CONNECT='TRUE';
    'VSS1329':
      PIN_NUMBER='(0,0,0,0,0,0,0,0,0,0,0,0,0,0,0,0,0,0,0,0,0,0,0,0,0,0,0,0,0,0,0~
,EC66,0,0,0,0,0,0,0,0,0,0)';
      PINUSE='POWER';
      NO_LOAD_CHECK='Both';
      NO_IO_CHECK='Both';
      NO_ASSERT_CHECK='TRUE';
      NO_DIR_CHECK='TRUE';
      ALLOW_CONNECT='TRUE';
    'VSS1327':
      PIN_NUMBER='(0,0,0,0,0,0,0,0,0,0,0,0,0,0,0,0,0,0,0,0,0,0,0,0,0,0,0,0,0,0,0~
,EC56,0,0,0,0,0,0,0,0,0,0)';
      PINUSE='POWER';
      NO_LOAD_CHECK='Both';
      NO_IO_CHECK='Both';
      NO_ASSERT_CHECK='TRUE';
      NO_DIR_CHECK='TRUE';
      ALLOW_CONNECT='TRUE';
    'VSS1326':
      PIN_NUMBER='(0,0,0,0,0,0,0,0,0,0,0,0,0,0,0,0,0,0,0,0,0,0,0,0,0,0,0,0,0,0,0~
,EC50,0,0,0,0,0,0,0,0,0,0)';
      PINUSE='POWER';
      NO_LOAD_CHECK='Both';
      NO_IO_CHECK='Both';
      NO_ASSERT_CHECK='TRUE';
      NO_DIR_CHECK='TRUE';
      ALLOW_CONNECT='TRUE';
    'VSS1324':
      PIN_NUMBER='(0,0,0,0,0,0,0,0,0,0,0,0,0,0,0,0,0,0,0,0,0,0,0,0,0,0,0,0,0,0,0~
,EC48,0,0,0,0,0,0,0,0,0,0)';
      PINUSE='POWER';
      NO_LOAD_CHECK='Both';
      NO_IO_CHECK='Both';
      NO_ASSERT_CHECK='TRUE';
      NO_DIR_CHECK='TRUE';
      ALLOW_CONNECT='TRUE';
    'VSS1323':
      PIN_NUMBER='(0,0,0,0,0,0,0,0,0,0,0,0,0,0,0,0,0,0,0,0,0,0,0,0,0,0,0,0,0,0,0~
,EC43,0,0,0,0,0,0,0,0,0,0)';
      PINUSE='POWER';
      NO_LOAD_CHECK='Both';
      NO_IO_CHECK='Both';
      NO_ASSERT_CHECK='TRUE';
      NO_DIR_CHECK='TRUE';
      ALLOW_CONNECT='TRUE';
    'VSS1321':
      PIN_NUMBER='(0,0,0,0,0,0,0,0,0,0,0,0,0,0,0,0,0,0,0,0,0,0,0,0,0,0,0,0,0,0,0~
,EC41,0,0,0,0,0,0,0,0,0,0)';
      PINUSE='POWER';
      NO_LOAD_CHECK='Both';
      NO_IO_CHECK='Both';
      NO_ASSERT_CHECK='TRUE';
      NO_DIR_CHECK='TRUE';
      ALLOW_CONNECT='TRUE';
    'VSS1318':
      PIN_NUMBER='(0,0,0,0,0,0,0,0,0,0,0,0,0,0,0,0,0,0,0,0,0,0,0,0,0,0,0,0,0,0,0~
,EH6,0,0,0,0,0,0,0,0,0,0)';
      PINUSE='POWER';
      NO_LOAD_CHECK='Both';
      NO_IO_CHECK='Both';
      NO_ASSERT_CHECK='TRUE';
      NO_DIR_CHECK='TRUE';
      ALLOW_CONNECT='TRUE';
    'VSS1317':
      PIN_NUMBER='(0,0,0,0,0,0,0,0,0,0,0,0,0,0,0,0,0,0,0,0,0,0,0,0,0,0,0,0,0,0,0~
,EC37,0,0,0,0,0,0,0,0,0,0)';
      PINUSE='POWER';
      NO_LOAD_CHECK='Both';
      NO_IO_CHECK='Both';
      NO_ASSERT_CHECK='TRUE';
      NO_DIR_CHECK='TRUE';
      ALLOW_CONNECT='TRUE';
    'VSS1316':
      PIN_NUMBER='(0,0,0,0,0,0,0,0,0,0,0,0,0,0,0,0,0,0,0,0,0,0,0,0,0,0,0,0,0,0,0~
,EC31,0,0,0,0,0,0,0,0,0,0)';
      PINUSE='POWER';
      NO_LOAD_CHECK='Both';
      NO_IO_CHECK='Both';
      NO_ASSERT_CHECK='TRUE';
      NO_DIR_CHECK='TRUE';
      ALLOW_CONNECT='TRUE';
    'VSS1314':
      PIN_NUMBER='(0,0,0,0,0,0,0,0,0,0,0,0,0,0,0,0,0,0,0,0,0,0,0,0,0,0,0,0,0,0,0~
,EC29,0,0,0,0,0,0,0,0,0,0)';
      PINUSE='POWER';
      NO_LOAD_CHECK='Both';
      NO_IO_CHECK='Both';
      NO_ASSERT_CHECK='TRUE';
      NO_DIR_CHECK='TRUE';
      ALLOW_CONNECT='TRUE';
    'VSS1313':
      PIN_NUMBER='(0,0,0,0,0,0,0,0,0,0,0,0,0,0,0,0,0,0,0,0,0,0,0,0,0,0,0,0,0,0,0~
,EC23,0,0,0,0,0,0,0,0,0,0)';
      PINUSE='POWER';
      NO_LOAD_CHECK='Both';
      NO_IO_CHECK='Both';
      NO_ASSERT_CHECK='TRUE';
      NO_DIR_CHECK='TRUE';
      ALLOW_CONNECT='TRUE';
    'VSS1311':
      PIN_NUMBER='(0,0,0,0,0,0,0,0,0,0,0,0,0,0,0,0,0,0,0,0,0,0,0,0,0,0,0,0,0,0,0~
,EC19,0,0,0,0,0,0,0,0,0,0)';
      PINUSE='POWER';
      NO_LOAD_CHECK='Both';
      NO_IO_CHECK='Both';
      NO_ASSERT_CHECK='TRUE';
      NO_DIR_CHECK='TRUE';
      ALLOW_CONNECT='TRUE';
    'VSS1310':
      PIN_NUMBER='(0,0,0,0,0,0,0,0,0,0,0,0,0,0,0,0,0,0,0,0,0,0,0,0,0,0,0,0,0,0,0~
,EC13,0,0,0,0,0,0,0,0,0,0)';
      PINUSE='POWER';
      NO_LOAD_CHECK='Both';
      NO_IO_CHECK='Both';
      NO_ASSERT_CHECK='TRUE';
      NO_DIR_CHECK='TRUE';
      ALLOW_CONNECT='TRUE';
    'VSS1309':
      PIN_NUMBER='(0,0,0,0,0,0,0,0,0,0,0,0,0,0,0,0,0,0,0,0,0,0,0,0,0,0,0,0,0,0,0~
,EC1,0,0,0,0,0,0,0,0,0,0)';
      PINUSE='POWER';
      NO_LOAD_CHECK='Both';
      NO_IO_CHECK='Both';
      NO_ASSERT_CHECK='TRUE';
      NO_DIR_CHECK='TRUE';
      ALLOW_CONNECT='TRUE';
    'VSS1308':
      PIN_NUMBER='(0,0,0,0,0,0,0,0,0,0,0,0,0,0,0,0,0,0,0,0,0,0,0,0,0,0,0,0,0,0,0~
,EB87,0,0,0,0,0,0,0,0,0,0)';
      PINUSE='POWER';
      NO_LOAD_CHECK='Both';
      NO_IO_CHECK='Both';
      NO_ASSERT_CHECK='TRUE';
      NO_DIR_CHECK='TRUE';
      ALLOW_CONNECT='TRUE';
    'VSS1307':
      PIN_NUMBER='(0,0,0,0,0,0,0,0,0,0,0,0,0,0,0,0,0,0,0,0,0,0,0,0,0,0,0,0,0,0,0~
,EB83,0,0,0,0,0,0,0,0,0,0)';
      PINUSE='POWER';
      NO_LOAD_CHECK='Both';
      NO_IO_CHECK='Both';
      NO_ASSERT_CHECK='TRUE';
      NO_DIR_CHECK='TRUE';
      ALLOW_CONNECT='TRUE';
    'VSS1306':
      PIN_NUMBER='(0,0,0,0,0,0,0,0,0,0,0,0,0,0,0,0,0,0,0,0,0,0,0,0,0,0,0,0,0,0,0~
,EB8,0,0,0,0,0,0,0,0,0,0)';
      PINUSE='POWER';
      NO_LOAD_CHECK='Both';
      NO_IO_CHECK='Both';
      NO_ASSERT_CHECK='TRUE';
      NO_DIR_CHECK='TRUE';
      ALLOW_CONNECT='TRUE';
    'VSS1305':
      PIN_NUMBER='(0,0,0,0,0,0,0,0,0,0,0,0,0,0,0,0,0,0,0,0,0,0,0,0,0,0,0,0,0,0,0~
,EH18,0,0,0,0,0,0,0,0,0,0)';
      PINUSE='POWER';
      NO_LOAD_CHECK='Both';
      NO_IO_CHECK='Both';
      NO_ASSERT_CHECK='TRUE';
      NO_DIR_CHECK='TRUE';
      ALLOW_CONNECT='TRUE';
    'VSS1304':
      PIN_NUMBER='(0,0,0,0,0,0,0,0,0,0,0,0,0,0,0,0,0,0,0,0,0,0,0,0,0,0,0,0,0,0,0~
,EB79,0,0,0,0,0,0,0,0,0,0)';
      PINUSE='POWER';
      NO_LOAD_CHECK='Both';
      NO_IO_CHECK='Both';
      NO_ASSERT_CHECK='TRUE';
      NO_DIR_CHECK='TRUE';
      ALLOW_CONNECT='TRUE';
    'VSS1303':
      PIN_NUMBER='(0,0,0,0,0,0,0,0,0,0,0,0,0,0,0,0,0,0,0,0,0,0,0,0,0,0,0,0,0,0,0~
,EH14,0,0,0,0,0,0,0,0,0,0)';
      PINUSE='POWER';
      NO_LOAD_CHECK='Both';
      NO_IO_CHECK='Both';
      NO_ASSERT_CHECK='TRUE';
      NO_DIR_CHECK='TRUE';
      ALLOW_CONNECT='TRUE';
    'VSS1302':
      PIN_NUMBER='(0,0,0,0,0,0,0,0,0,0,0,0,0,0,0,0,0,0,0,0,0,0,0,0,0,0,0,0,0,0,0~
,EH12,0,0,0,0,0,0,0,0,0,0)';
      PINUSE='POWER';
      NO_LOAD_CHECK='Both';
      NO_IO_CHECK='Both';
      NO_ASSERT_CHECK='TRUE';
      NO_DIR_CHECK='TRUE';
      ALLOW_CONNECT='TRUE';
    'VSS1301':
      PIN_NUMBER='(0,0,0,0,0,0,0,0,0,0,0,0,0,0,0,0,0,0,0,0,0,0,0,0,0,0,0,0,0,0,0~
,EB75,0,0,0,0,0,0,0,0,0,0)';
      PINUSE='POWER';
      NO_LOAD_CHECK='Both';
      NO_IO_CHECK='Both';
      NO_ASSERT_CHECK='TRUE';
      NO_DIR_CHECK='TRUE';
      ALLOW_CONNECT='TRUE';
    'VSS1300':
      PIN_NUMBER='(0,0,0,0,0,0,0,0,0,0,0,0,0,0,0,0,0,0,0,0,0,0,0,0,0,0,0,0,0,0,0~
,EB71,0,0,0,0,0,0,0,0,0,0)';
      PINUSE='POWER';
      NO_LOAD_CHECK='Both';
      NO_IO_CHECK='Both';
      NO_ASSERT_CHECK='TRUE';
      NO_DIR_CHECK='TRUE';
      ALLOW_CONNECT='TRUE';
    'VSS1299':
      PIN_NUMBER='(0,0,0,0,0,0,0,0,0,0,0,0,0,0,0,0,0,0,0,0,0,0,0,0,0,0,0,0,0,0,0~
,EB69,0,0,0,0,0,0,0,0,0,0)';
      PINUSE='POWER';
      NO_LOAD_CHECK='Both';
      NO_IO_CHECK='Both';
      NO_ASSERT_CHECK='TRUE';
      NO_DIR_CHECK='TRUE';
      ALLOW_CONNECT='TRUE';
    'VSS1298':
      PIN_NUMBER='(0,0,0,0,0,0,0,0,0,0,0,0,0,0,0,0,0,0,0,0,0,0,0,0,0,0,0,0,0,0,0~
,EB65,0,0,0,0,0,0,0,0,0,0)';
      PINUSE='POWER';
      NO_LOAD_CHECK='Both';
      NO_IO_CHECK='Both';
      NO_ASSERT_CHECK='TRUE';
      NO_DIR_CHECK='TRUE';
      ALLOW_CONNECT='TRUE';
    'VSS1297':
      PIN_NUMBER='(0,0,0,0,0,0,0,0,0,0,0,0,0,0,0,0,0,0,0,0,0,0,0,0,0,0,0,0,0,0,0~
,EB57,0,0,0,0,0,0,0,0,0,0)';
      PINUSE='POWER';
      NO_LOAD_CHECK='Both';
      NO_IO_CHECK='Both';
      NO_ASSERT_CHECK='TRUE';
      NO_DIR_CHECK='TRUE';
      ALLOW_CONNECT='TRUE';
    'VSS1296':
      PIN_NUMBER='(0,0,0,0,0,0,0,0,0,0,0,0,0,0,0,0,0,0,0,0,0,0,0,0,0,0,0,0,0,0,0~
,EB47,0,0,0,0,0,0,0,0,0,0)';
      PINUSE='POWER';
      NO_LOAD_CHECK='Both';
      NO_IO_CHECK='Both';
      NO_ASSERT_CHECK='TRUE';
      NO_DIR_CHECK='TRUE';
      ALLOW_CONNECT='TRUE';
    'VSS1295':
      PIN_NUMBER='(0,0,0,0,0,0,0,0,0,0,0,0,0,0,0,0,0,0,0,0,0,0,0,0,0,0,0,0,0,0,0~
,EB40,0,0,0,0,0,0,0,0,0,0)';
      PINUSE='POWER';
      NO_LOAD_CHECK='Both';
      NO_IO_CHECK='Both';
      NO_ASSERT_CHECK='TRUE';
      NO_DIR_CHECK='TRUE';
      ALLOW_CONNECT='TRUE';
    'VSS1294':
      PIN_NUMBER='(0,0,0,0,0,0,0,0,0,0,0,0,0,0,0,0,0,0,0,0,0,0,0,0,0,0,0,0,0,0,0~
,EG7,0,0,0,0,0,0,0,0,0,0)';
      PINUSE='POWER';
      NO_LOAD_CHECK='Both';
      NO_IO_CHECK='Both';
      NO_ASSERT_CHECK='TRUE';
      NO_DIR_CHECK='TRUE';
      ALLOW_CONNECT='TRUE';
    'VSS1293':
      PIN_NUMBER='(0,0,0,0,0,0,0,0,0,0,0,0,0,0,0,0,0,0,0,0,0,0,0,0,0,0,0,0,0,0,0~
,EB38,0,0,0,0,0,0,0,0,0,0)';
      PINUSE='POWER';
      NO_LOAD_CHECK='Both';
      NO_IO_CHECK='Both';
      NO_ASSERT_CHECK='TRUE';
      NO_DIR_CHECK='TRUE';
      ALLOW_CONNECT='TRUE';
    'VSS1292':
      PIN_NUMBER='(0,0,0,0,0,0,0,0,0,0,0,0,0,0,0,0,0,0,0,0,0,0,0,0,0,0,0,0,0,0,0~
,EB32,0,0,0,0,0,0,0,0,0,0)';
      PINUSE='POWER';
      NO_LOAD_CHECK='Both';
      NO_IO_CHECK='Both';
      NO_ASSERT_CHECK='TRUE';
      NO_DIR_CHECK='TRUE';
      ALLOW_CONNECT='TRUE';
    'VSS1291':
      PIN_NUMBER='(0,0,0,0,0,0,0,0,0,0,0,0,0,0,0,0,0,0,0,0,0,0,0,0,0,0,0,0,0,0,0~
,EG52,0,0,0,0,0,0,0,0,0,0)';
      PINUSE='POWER';
      NO_LOAD_CHECK='Both';
      NO_IO_CHECK='Both';
      NO_ASSERT_CHECK='TRUE';
      NO_DIR_CHECK='TRUE';
      ALLOW_CONNECT='TRUE';
    'VSS1290':
      PIN_NUMBER='(0,0,0,0,0,0,0,0,0,0,0,0,0,0,0,0,0,0,0,0,0,0,0,0,0,0,0,0,0,0,0~
,EG5,0,0,0,0,0,0,0,0,0,0)';
      PINUSE='POWER';
      NO_LOAD_CHECK='Both';
      NO_IO_CHECK='Both';
      NO_ASSERT_CHECK='TRUE';
      NO_DIR_CHECK='TRUE';
      ALLOW_CONNECT='TRUE';
    'VSS1289':
      PIN_NUMBER='(0,0,0,0,0,0,0,0,0,0,0,0,0,0,0,0,0,0,0,0,0,0,0,0,0,0,0,0,0,0,0~
,EB28,0,0,0,0,0,0,0,0,0,0)';
      PINUSE='POWER';
      NO_LOAD_CHECK='Both';
      NO_IO_CHECK='Both';
      NO_ASSERT_CHECK='TRUE';
      NO_DIR_CHECK='TRUE';
      ALLOW_CONNECT='TRUE';
    'VSS1288':
      PIN_NUMBER='(0,0,0,0,0,0,0,0,0,0,0,0,0,0,0,0,0,0,0,0,0,0,0,0,0,0,0,0,0,0,0~
,EB22,0,0,0,0,0,0,0,0,0,0)';
      PINUSE='POWER';
      NO_LOAD_CHECK='Both';
      NO_IO_CHECK='Both';
      NO_ASSERT_CHECK='TRUE';
      NO_DIR_CHECK='TRUE';
      ALLOW_CONNECT='TRUE';
    'VSS1287':
      PIN_NUMBER='(0,0,0,0,0,0,0,0,0,0,0,0,0,0,0,0,0,0,0,0,0,0,0,0,0,0,0,0,0,0,0~
,EB12,0,0,0,0,0,0,0,0,0,0)';
      PINUSE='POWER';
      NO_LOAD_CHECK='Both';
      NO_IO_CHECK='Both';
      NO_ASSERT_CHECK='TRUE';
      NO_DIR_CHECK='TRUE';
      ALLOW_CONNECT='TRUE';
    'VSS1286':
      PIN_NUMBER='(0,0,0,0,0,0,0,0,0,0,0,0,0,0,0,0,0,0,0,0,0,0,0,0,0,0,0,0,0,0,0~
,EA88,0,0,0,0,0,0,0,0,0,0)';
      PINUSE='POWER';
      NO_LOAD_CHECK='Both';
      NO_IO_CHECK='Both';
      NO_ASSERT_CHECK='TRUE';
      NO_DIR_CHECK='TRUE';
      ALLOW_CONNECT='TRUE';
    'VSS1285':
      PIN_NUMBER='(0,0,0,0,0,0,0,0,0,0,0,0,0,0,0,0,0,0,0,0,0,0,0,0,0,0,0,0,0,0,0~
,EA84,0,0,0,0,0,0,0,0,0,0)';
      PINUSE='POWER';
      NO_LOAD_CHECK='Both';
      NO_IO_CHECK='Both';
      NO_ASSERT_CHECK='TRUE';
      NO_DIR_CHECK='TRUE';
      ALLOW_CONNECT='TRUE';
    'VSS1284':
      PIN_NUMBER='(0,0,0,0,0,0,0,0,0,0,0,0,0,0,0,0,0,0,0,0,0,0,0,0,0,0,0,0,0,0,0~
,EG13,0,0,0,0,0,0,0,0,0,0)';
      PINUSE='POWER';
      NO_LOAD_CHECK='Both';
      NO_IO_CHECK='Both';
      NO_ASSERT_CHECK='TRUE';
      NO_DIR_CHECK='TRUE';
      ALLOW_CONNECT='TRUE';
    'VSS1283':
      PIN_NUMBER='(0,0,0,0,0,0,0,0,0,0,0,0,0,0,0,0,0,0,0,0,0,0,0,0,0,0,0,0,0,0,0~
,EF89,0,0,0,0,0,0,0,0,0,0)';
      PINUSE='POWER';
      NO_LOAD_CHECK='Both';
      NO_IO_CHECK='Both';
      NO_ASSERT_CHECK='TRUE';
      NO_DIR_CHECK='TRUE';
      ALLOW_CONNECT='TRUE';
    'VSS1282':
      PIN_NUMBER='(0,0,0,0,0,0,0,0,0,0,0,0,0,0,0,0,0,0,0,0,0,0,0,0,0,0,0,0,0,0,0~
,EA80,0,0,0,0,0,0,0,0,0,0)';
      PINUSE='POWER';
      NO_LOAD_CHECK='Both';
      NO_IO_CHECK='Both';
      NO_ASSERT_CHECK='TRUE';
      NO_DIR_CHECK='TRUE';
      ALLOW_CONNECT='TRUE';
    'VSS1281':
      PIN_NUMBER='(0,0,0,0,0,0,0,0,0,0,0,0,0,0,0,0,0,0,0,0,0,0,0,0,0,0,0,0,0,0,0~
,EA78,0,0,0,0,0,0,0,0,0,0)';
      PINUSE='POWER';
      NO_LOAD_CHECK='Both';
      NO_IO_CHECK='Both';
      NO_ASSERT_CHECK='TRUE';
      NO_DIR_CHECK='TRUE';
      ALLOW_CONNECT='TRUE';
    'VSS1280':
      PIN_NUMBER='(0,0,0,0,0,0,0,0,0,0,0,0,0,0,0,0,0,0,0,0,0,0,0,0,0,0,0,0,0,0,0~
,EA76,0,0,0,0,0,0,0,0,0,0)';
      PINUSE='POWER';
      NO_LOAD_CHECK='Both';
      NO_IO_CHECK='Both';
      NO_ASSERT_CHECK='TRUE';
      NO_DIR_CHECK='TRUE';
      ALLOW_CONNECT='TRUE';
    'VSS1279':
      PIN_NUMBER='(0,0,0,0,0,0,0,0,0,0,0,0,0,0,0,0,0,0,0,0,0,0,0,0,0,0,0,0,0,0,0~
,EA70,0,0,0,0,0,0,0,0,0,0)';
      PINUSE='POWER';
      NO_LOAD_CHECK='Both';
      NO_IO_CHECK='Both';
      NO_ASSERT_CHECK='TRUE';
      NO_DIR_CHECK='TRUE';
      ALLOW_CONNECT='TRUE';
    'VSS1278':
      PIN_NUMBER='(0,0,0,0,0,0,0,0,0,0,0,0,0,0,0,0,0,0,0,0,0,0,0,0,0,0,0,0,0,0,0~
,EA33,0,0,0,0,0,0,0,0,0,0)';
      PINUSE='POWER';
      NO_LOAD_CHECK='Both';
      NO_IO_CHECK='Both';
      NO_ASSERT_CHECK='TRUE';
      NO_DIR_CHECK='TRUE';
      ALLOW_CONNECT='TRUE';
    'VSS1277':
      PIN_NUMBER='(0,0,0,0,0,0,0,0,0,0,0,0,0,0,0,0,0,0,0,0,0,0,0,0,0,0,0,0,0,0,0~
,EF75,0,0,0,0,0,0,0,0,0,0)';
      PINUSE='POWER';
      NO_LOAD_CHECK='Both';
      NO_IO_CHECK='Both';
      NO_ASSERT_CHECK='TRUE';
      NO_DIR_CHECK='TRUE';
      ALLOW_CONNECT='TRUE';
    'VSS1276':
      PIN_NUMBER='(0,0,0,0,0,0,0,0,0,0,0,0,0,0,0,0,0,0,0,0,0,0,0,0,0,0,0,0,0,0,0~
,EF73,0,0,0,0,0,0,0,0,0,0)';
      PINUSE='POWER';
      NO_LOAD_CHECK='Both';
      NO_IO_CHECK='Both';
      NO_ASSERT_CHECK='TRUE';
      NO_DIR_CHECK='TRUE';
      ALLOW_CONNECT='TRUE';
    'VSS1275':
      PIN_NUMBER='(0,0,0,0,0,0,0,0,0,0,0,0,0,0,0,0,0,0,0,0,0,0,0,0,0,0,0,0,0,0,0~
,EA27,0,0,0,0,0,0,0,0,0,0)';
      PINUSE='POWER';
      NO_LOAD_CHECK='Both';
      NO_IO_CHECK='Both';
      NO_ASSERT_CHECK='TRUE';
      NO_DIR_CHECK='TRUE';
      ALLOW_CONNECT='TRUE';
    'VSS1274':
      PIN_NUMBER='(0,0,0,0,0,0,0,0,0,0,0,0,0,0,0,0,0,0,0,0,0,0,0,0,0,0,0,0,0,0,0~
,EA21,0,0,0,0,0,0,0,0,0,0)';
      PINUSE='POWER';
      NO_LOAD_CHECK='Both';
      NO_IO_CHECK='Both';
      NO_ASSERT_CHECK='TRUE';
      NO_DIR_CHECK='TRUE';
      ALLOW_CONNECT='TRUE';
    'VSS1270':
      PIN_NUMBER='(0,0,0,0,0,0,0,0,0,0,0,0,0,0,0,0,0,0,0,0,0,0,0,0,0,0,0,0,0,0,0~
,DY8,0,0,0,0,0,0,0,0,0,0)';
      PINUSE='POWER';
      NO_LOAD_CHECK='Both';
      NO_IO_CHECK='Both';
      NO_ASSERT_CHECK='TRUE';
      NO_DIR_CHECK='TRUE';
      ALLOW_CONNECT='TRUE';
    'VSS1269':
      PIN_NUMBER='(0,0,0,0,0,0,0,0,0,0,0,0,0,0,0,0,0,0,0,0,0,0,0,0,0,0,0,0,0,0,0~
,DY77,0,0,0,0,0,0,0,0,0,0)';
      PINUSE='POWER';
      NO_LOAD_CHECK='Both';
      NO_IO_CHECK='Both';
      NO_ASSERT_CHECK='TRUE';
      NO_DIR_CHECK='TRUE';
      ALLOW_CONNECT='TRUE';
    'VSS1267':
      PIN_NUMBER='(0,0,0,0,0,0,0,0,0,0,0,0,0,0,0,0,0,0,0,0,0,0,0,0,0,0,0,0,0,0,0~
,DW88,0,0,0,0,0,0,0,0,0,0)';
      PINUSE='POWER';
      NO_LOAD_CHECK='Both';
      NO_IO_CHECK='Both';
      NO_ASSERT_CHECK='TRUE';
      NO_DIR_CHECK='TRUE';
      ALLOW_CONNECT='TRUE';
    'VSS1266':
      PIN_NUMBER='(0,0,0,0,0,0,0,0,0,0,0,0,0,0,0,0,0,0,0,0,0,0,0,0,0,0,0,0,0,0,0~
,DW84,0,0,0,0,0,0,0,0,0,0)';
      PINUSE='POWER';
      NO_LOAD_CHECK='Both';
      NO_IO_CHECK='Both';
      NO_ASSERT_CHECK='TRUE';
      NO_DIR_CHECK='TRUE';
      ALLOW_CONNECT='TRUE';
    'VSS1265':
      PIN_NUMBER='(0,0,0,0,0,0,0,0,0,0,0,0,0,0,0,0,0,0,0,0,0,0,0,0,0,0,0,0,0,0,0~
,EF51,0,0,0,0,0,0,0,0,0,0)';
      PINUSE='POWER';
      NO_LOAD_CHECK='Both';
      NO_IO_CHECK='Both';
      NO_ASSERT_CHECK='TRUE';
      NO_DIR_CHECK='TRUE';
      ALLOW_CONNECT='TRUE';
    'VSS1264':
      PIN_NUMBER='(0,0,0,0,0,0,0,0,0,0,0,0,0,0,0,0,0,0,0,0,0,0,0,0,0,0,0,0,0,0,0~
,DW82,0,0,0,0,0,0,0,0,0,0)';
      PINUSE='POWER';
      NO_LOAD_CHECK='Both';
      NO_IO_CHECK='Both';
      NO_ASSERT_CHECK='TRUE';
      NO_DIR_CHECK='TRUE';
      ALLOW_CONNECT='TRUE';
    'VSS1263':
      PIN_NUMBER='(0,0,0,0,0,0,0,0,0,0,0,0,0,0,0,0,0,0,0,0,0,0,0,0,0,0,0,0,0,0,0~
,DW80,0,0,0,0,0,0,0,0,0,0)';
      PINUSE='POWER';
      NO_LOAD_CHECK='Both';
      NO_IO_CHECK='Both';
      NO_ASSERT_CHECK='TRUE';
      NO_DIR_CHECK='TRUE';
      ALLOW_CONNECT='TRUE';
    'VSS1262':
      PIN_NUMBER='(0,0,0,0,0,0,0,0,0,0,0,0,0,0,0,0,0,0,0,0,0,0,0,0,0,0,0,0,0,0,0~
,DW76,0,0,0,0,0,0,0,0,0,0)';
      PINUSE='POWER';
      NO_LOAD_CHECK='Both';
      NO_IO_CHECK='Both';
      NO_ASSERT_CHECK='TRUE';
      NO_DIR_CHECK='TRUE';
      ALLOW_CONNECT='TRUE';
    'VSS1261':
      PIN_NUMBER='(0,0,0,0,0,0,0,0,0,0,0,0,0,0,0,0,0,0,0,0,0,0,0,0,0,0,0,0,0,0,0~
,DW74,0,0,0,0,0,0,0,0,0,0)';
      PINUSE='POWER';
      NO_LOAD_CHECK='Both';
      NO_IO_CHECK='Both';
      NO_ASSERT_CHECK='TRUE';
      NO_DIR_CHECK='TRUE';
      ALLOW_CONNECT='TRUE';
    'VSS1260':
      PIN_NUMBER='(0,0,0,0,0,0,0,0,0,0,0,0,0,0,0,0,0,0,0,0,0,0,0,0,0,0,0,0,0,0,0~
,DW72,0,0,0,0,0,0,0,0,0,0)';
      PINUSE='POWER';
      NO_LOAD_CHECK='Both';
      NO_IO_CHECK='Both';
      NO_ASSERT_CHECK='TRUE';
      NO_DIR_CHECK='TRUE';
      ALLOW_CONNECT='TRUE';
    'VSS1259':
      PIN_NUMBER='(0,0,0,0,0,0,0,0,0,0,0,0,0,0,0,0,0,0,0,0,0,0,0,0,0,0,0,0,0,0,0~
,DW70,0,0,0,0,0,0,0,0,0,0)';
      PINUSE='POWER';
      NO_LOAD_CHECK='Both';
      NO_IO_CHECK='Both';
      NO_ASSERT_CHECK='TRUE';
      NO_DIR_CHECK='TRUE';
      ALLOW_CONNECT='TRUE';
    'VSS1258':
      PIN_NUMBER='(0,0,0,0,0,0,0,0,0,0,0,0,0,0,0,0,0,0,0,0,0,0,0,0,0,0,0,0,0,0,0~
,DW68,0,0,0,0,0,0,0,0,0,0)';
      PINUSE='POWER';
      NO_LOAD_CHECK='Both';
      NO_IO_CHECK='Both';
      NO_ASSERT_CHECK='TRUE';
      NO_DIR_CHECK='TRUE';
      ALLOW_CONNECT='TRUE';
    'VSS1257':
      PIN_NUMBER='(0,0,0,0,0,0,0,0,0,0,0,0,0,0,0,0,0,0,0,0,0,0,0,0,0,0,0,0,0,0,0~
,DW66,0,0,0,0,0,0,0,0,0,0)';
      PINUSE='POWER';
      NO_LOAD_CHECK='Both';
      NO_IO_CHECK='Both';
      NO_ASSERT_CHECK='TRUE';
      NO_DIR_CHECK='TRUE';
      ALLOW_CONNECT='TRUE';
    'VSS1237':
      PIN_NUMBER='(0,0,0,0,0,0,0,0,0,0,0,0,0,0,0,0,0,0,0,0,0,0,0,0,0,0,0,0,0,0,0~
,EE52,0,0,0,0,0,0,0,0,0,0)';
      PINUSE='POWER';
      NO_LOAD_CHECK='Both';
      NO_IO_CHECK='Both';
      NO_ASSERT_CHECK='TRUE';
      NO_DIR_CHECK='TRUE';
      ALLOW_CONNECT='TRUE';
    'VSS1235':
      PIN_NUMBER='(0,0,0,0,0,0,0,0,0,0,0,0,0,0,0,0,0,0,0,0,0,0,0,0,0,0,0,0,0,0,0~
,EE39,0,0,0,0,0,0,0,0,0,0)';
      PINUSE='POWER';
      NO_LOAD_CHECK='Both';
      NO_IO_CHECK='Both';
      NO_ASSERT_CHECK='TRUE';
      NO_DIR_CHECK='TRUE';
      ALLOW_CONNECT='TRUE';
    'VSS1232':
      PIN_NUMBER='(0,0,0,0,0,0,0,0,0,0,0,0,0,0,0,0,0,0,0,0,0,0,0,0,0,0,0,0,0,0,0~
,EE17,0,0,0,0,0,0,0,0,0,0)';
      PINUSE='POWER';
      NO_LOAD_CHECK='Both';
      NO_IO_CHECK='Both';
      NO_ASSERT_CHECK='TRUE';
      NO_DIR_CHECK='TRUE';
      ALLOW_CONNECT='TRUE';
    'VSS1225':
      PIN_NUMBER='(0,0,0,0,0,0,0,0,0,0,0,0,0,0,0,0,0,0,0,0,0,0,0,0,0,0,0,0,0,0,0~
,ED73,0,0,0,0,0,0,0,0,0,0)';
      PINUSE='POWER';
      NO_LOAD_CHECK='Both';
      NO_IO_CHECK='Both';
      NO_ASSERT_CHECK='TRUE';
      NO_DIR_CHECK='TRUE';
      ALLOW_CONNECT='TRUE';
    'VSS1224':
      PIN_NUMBER='(0,0,0,0,0,0,0,0,0,0,0,0,0,0,0,0,0,0,0,0,0,0,0,0,0,0,0,0,0,0,0~
,ED67,0,0,0,0,0,0,0,0,0,0)';
      PINUSE='POWER';
      NO_LOAD_CHECK='Both';
      NO_IO_CHECK='Both';
      NO_ASSERT_CHECK='TRUE';
      NO_DIR_CHECK='TRUE';
      ALLOW_CONNECT='TRUE';
    'VSS1223':
      PIN_NUMBER='(0,0,0,0,0,0,0,0,0,0,0,0,0,0,0,0,0,0,0,0,0,0,0,0,0,0,0,0,0,0,0~
,ED61,0,0,0,0,0,0,0,0,0,0)';
      PINUSE='POWER';
      NO_LOAD_CHECK='Both';
      NO_IO_CHECK='Both';
      NO_ASSERT_CHECK='TRUE';
      NO_DIR_CHECK='TRUE';
      ALLOW_CONNECT='TRUE';
    'VSS1220':
      PIN_NUMBER='(0,0,0,0,0,0,0,0,0,0,0,0,0,0,0,0,0,0,0,0,0,0,0,0,0,0,0,0,0,0,0~
,ED55,0,0,0,0,0,0,0,0,0,0)';
      PINUSE='POWER';
      NO_LOAD_CHECK='Both';
      NO_IO_CHECK='Both';
      NO_ASSERT_CHECK='TRUE';
      NO_DIR_CHECK='TRUE';
      ALLOW_CONNECT='TRUE';
    'VSS1217':
      PIN_NUMBER='(0,0,0,0,0,0,0,0,0,0,0,0,0,0,0,0,0,0,0,0,0,0,0,0,0,0,0,0,0,0,0~
,ED42,0,0,0,0,0,0,0,0,0,0)';
      PINUSE='POWER';
      NO_LOAD_CHECK='Both';
      NO_IO_CHECK='Both';
      NO_ASSERT_CHECK='TRUE';
      NO_DIR_CHECK='TRUE';
      ALLOW_CONNECT='TRUE';
    'VSS1210':
      PIN_NUMBER='(0,0,0,0,0,0,0,0,0,0,0,0,0,0,0,0,0,0,0,0,0,0,0,0,0,0,0,0,0,0,0~
,ED18,0,0,0,0,0,0,0,0,0,0)';
      PINUSE='POWER';
      NO_LOAD_CHECK='Both';
      NO_IO_CHECK='Both';
      NO_ASSERT_CHECK='TRUE';
      NO_DIR_CHECK='TRUE';
      ALLOW_CONNECT='TRUE';
    'VSS1208':
      PIN_NUMBER='(0,0,0,0,0,0,0,0,0,0,0,0,0,0,0,0,0,0,0,0,0,0,0,0,0,0,0,0,0,0,0~
,ED12,0,0,0,0,0,0,0,0,0,0)';
      PINUSE='POWER';
      NO_LOAD_CHECK='Both';
      NO_IO_CHECK='Both';
      NO_ASSERT_CHECK='TRUE';
      NO_DIR_CHECK='TRUE';
      ALLOW_CONNECT='TRUE';
    'VSS1200':
      PIN_NUMBER='(0,0,0,0,0,0,0,0,0,0,0,0,0,0,0,0,0,0,0,0,0,0,0,0,0,0,0,0,0,0,0~
,EC68,0,0,0,0,0,0,0,0,0,0)';
      PINUSE='POWER';
      NO_LOAD_CHECK='Both';
      NO_IO_CHECK='Both';
      NO_ASSERT_CHECK='TRUE';
      NO_DIR_CHECK='TRUE';
      ALLOW_CONNECT='TRUE';
    'VSS1198':
      PIN_NUMBER='(0,0,0,0,0,0,0,0,0,0,0,0,0,0,0,0,0,0,0,0,0,0,0,0,0,0,0,0,0,0,0~
,EC62,0,0,0,0,0,0,0,0,0,0)';
      PINUSE='POWER';
      NO_LOAD_CHECK='Both';
      NO_IO_CHECK='Both';
      NO_ASSERT_CHECK='TRUE';
      NO_DIR_CHECK='TRUE';
      ALLOW_CONNECT='TRUE';
    'VSS1197':
      PIN_NUMBER='(0,0,0,0,0,0,0,0,0,0,0,0,0,0,0,0,0,0,0,0,0,0,0,0,0,0,0,0,0,0,0~
,EC60,0,0,0,0,0,0,0,0,0,0)';
      PINUSE='POWER';
      NO_LOAD_CHECK='Both';
      NO_IO_CHECK='Both';
      NO_ASSERT_CHECK='TRUE';
      NO_DIR_CHECK='TRUE';
      ALLOW_CONNECT='TRUE';
    'VSS1195':
      PIN_NUMBER='(0,0,0,0,0,0,0,0,0,0,0,0,0,0,0,0,0,0,0,0,0,0,0,0,0,0,0,0,0,0,0~
,EC54,0,0,0,0,0,0,0,0,0,0)';
      PINUSE='POWER';
      NO_LOAD_CHECK='Both';
      NO_IO_CHECK='Both';
      NO_ASSERT_CHECK='TRUE';
      NO_DIR_CHECK='TRUE';
      ALLOW_CONNECT='TRUE';
    'VSS1193':
      PIN_NUMBER='(0,0,0,0,0,0,0,0,0,0,0,0,0,0,0,0,0,0,0,0,0,0,0,0,0,0,0,0,0,0,0~
,EC5,0,0,0,0,0,0,0,0,0,0)';
      PINUSE='POWER';
      NO_LOAD_CHECK='Both';
      NO_IO_CHECK='Both';
      NO_ASSERT_CHECK='TRUE';
      NO_DIR_CHECK='TRUE';
      ALLOW_CONNECT='TRUE';
    'VSS1188':
      PIN_NUMBER='(0,0,0,0,0,0,0,0,0,0,0,0,0,0,0,0,0,0,0,0,0,0,0,0,0,0,0,0,0,0,0~
,EC35,0,0,0,0,0,0,0,0,0,0)';
      PINUSE='POWER';
      NO_LOAD_CHECK='Both';
      NO_IO_CHECK='Both';
      NO_ASSERT_CHECK='TRUE';
      NO_DIR_CHECK='TRUE';
      ALLOW_CONNECT='TRUE';
    'VSS1185':
      PIN_NUMBER='(0,0,0,0,0,0,0,0,0,0,0,0,0,0,0,0,0,0,0,0,0,0,0,0,0,0,0,0,0,0,0~
,EC25,0,0,0,0,0,0,0,0,0,0)';
      PINUSE='POWER';
      NO_LOAD_CHECK='Both';
      NO_IO_CHECK='Both';
      NO_ASSERT_CHECK='TRUE';
      NO_DIR_CHECK='TRUE';
      ALLOW_CONNECT='TRUE';
    'VSS1180':
      PIN_NUMBER='(0,0,0,0,0,0,0,0,0,0,0,0,0,0,0,0,0,0,0,0,0,0,0,0,0,0,0,0,0,0,0~
,EB91,0,0,0,0,0,0,0,0,0,0)';
      PINUSE='POWER';
      NO_LOAD_CHECK='Both';
      NO_IO_CHECK='Both';
      NO_ASSERT_CHECK='TRUE';
      NO_DIR_CHECK='TRUE';
      ALLOW_CONNECT='TRUE';
    'VSS1171':
      PIN_NUMBER='(0,0,0,0,0,0,0,0,0,0,0,0,0,0,0,0,0,0,0,0,0,0,0,0,0,0,0,0,0,0,0~
,EB63,0,0,0,0,0,0,0,0,0,0)';
      PINUSE='POWER';
      NO_LOAD_CHECK='Both';
      NO_IO_CHECK='Both';
      NO_ASSERT_CHECK='TRUE';
      NO_DIR_CHECK='TRUE';
      ALLOW_CONNECT='TRUE';
    'VSS1170':
      PIN_NUMBER='(0,0,0,0,0,0,0,0,0,0,0,0,0,0,0,0,0,0,0,0,0,0,0,0,0,0,0,0,0,0,0~
,EB59,0,0,0,0,0,0,0,0,0,0)';
      PINUSE='POWER';
      NO_LOAD_CHECK='Both';
      NO_IO_CHECK='Both';
      NO_ASSERT_CHECK='TRUE';
      NO_DIR_CHECK='TRUE';
      ALLOW_CONNECT='TRUE';
    'VSS1168':
      PIN_NUMBER='(0,0,0,0,0,0,0,0,0,0,0,0,0,0,0,0,0,0,0,0,0,0,0,0,0,0,0,0,0,0,0~
,EB53,0,0,0,0,0,0,0,0,0,0)';
      PINUSE='POWER';
      NO_LOAD_CHECK='Both';
      NO_IO_CHECK='Both';
      NO_ASSERT_CHECK='TRUE';
      NO_DIR_CHECK='TRUE';
      ALLOW_CONNECT='TRUE';
    'VSS1167':
      PIN_NUMBER='(0,0,0,0,0,0,0,0,0,0,0,0,0,0,0,0,0,0,0,0,0,0,0,0,0,0,0,0,0,0,0~
,EB51,0,0,0,0,0,0,0,0,0,0)';
      PINUSE='POWER';
      NO_LOAD_CHECK='Both';
      NO_IO_CHECK='Both';
      NO_ASSERT_CHECK='TRUE';
      NO_DIR_CHECK='TRUE';
      ALLOW_CONNECT='TRUE';
    'VSS1165':
      PIN_NUMBER='(0,0,0,0,0,0,0,0,0,0,0,0,0,0,0,0,0,0,0,0,0,0,0,0,0,0,0,0,0,0,0~
,EB44,0,0,0,0,0,0,0,0,0,0)';
      PINUSE='POWER';
      NO_LOAD_CHECK='Both';
      NO_IO_CHECK='Both';
      NO_ASSERT_CHECK='TRUE';
      NO_DIR_CHECK='TRUE';
      ALLOW_CONNECT='TRUE';
    'VSS1163':
      PIN_NUMBER='(0,0,0,0,0,0,0,0,0,0,0,0,0,0,0,0,0,0,0,0,0,0,0,0,0,0,0,0,0,0,0~
,EB4,0,0,0,0,0,0,0,0,0,0)';
      PINUSE='POWER';
      NO_LOAD_CHECK='Both';
      NO_IO_CHECK='Both';
      NO_ASSERT_CHECK='TRUE';
      NO_DIR_CHECK='TRUE';
      ALLOW_CONNECT='TRUE';
    'VSS1161':
      PIN_NUMBER='(0,0,0,0,0,0,0,0,0,0,0,0,0,0,0,0,0,0,0,0,0,0,0,0,0,0,0,0,0,0,0~
,EB34,0,0,0,0,0,0,0,0,0,0)';
      PINUSE='POWER';
      NO_LOAD_CHECK='Both';
      NO_IO_CHECK='Both';
      NO_ASSERT_CHECK='TRUE';
      NO_DIR_CHECK='TRUE';
      ALLOW_CONNECT='TRUE';
    'VSS1158':
      PIN_NUMBER='(0,0,0,0,0,0,0,0,0,0,0,0,0,0,0,0,0,0,0,0,0,0,0,0,0,0,0,0,0,0,0~
,EB26,0,0,0,0,0,0,0,0,0,0)';
      PINUSE='POWER';
      NO_LOAD_CHECK='Both';
      NO_IO_CHECK='Both';
      NO_ASSERT_CHECK='TRUE';
      NO_DIR_CHECK='TRUE';
      ALLOW_CONNECT='TRUE';
    'VSS1156':
      PIN_NUMBER='(0,0,0,0,0,0,0,0,0,0,0,0,0,0,0,0,0,0,0,0,0,0,0,0,0,0,0,0,0,0,0~
,EB20,0,0,0,0,0,0,0,0,0,0)';
      PINUSE='POWER';
      NO_LOAD_CHECK='Both';
      NO_IO_CHECK='Both';
      NO_ASSERT_CHECK='TRUE';
      NO_DIR_CHECK='TRUE';
      ALLOW_CONNECT='TRUE';
    'VSS1155':
      PIN_NUMBER='(0,0,0,0,0,0,0,0,0,0,0,0,0,0,0,0,0,0,0,0,0,0,0,0,0,0,0,0,0,0,0~
,EB16,0,0,0,0,0,0,0,0,0,0)';
      PINUSE='POWER';
      NO_LOAD_CHECK='Both';
      NO_IO_CHECK='Both';
      NO_ASSERT_CHECK='TRUE';
      NO_DIR_CHECK='TRUE';
      ALLOW_CONNECT='TRUE';
    'VSS1146':
      PIN_NUMBER='(0,0,0,0,0,0,0,0,0,0,0,0,0,0,0,0,0,0,0,0,0,0,0,0,0,0,0,0,0,0,0~
,EA64,0,0,0,0,0,0,0,0,0,0)';
      PINUSE='POWER';
      NO_LOAD_CHECK='Both';
      NO_IO_CHECK='Both';
      NO_ASSERT_CHECK='TRUE';
      NO_DIR_CHECK='TRUE';
      ALLOW_CONNECT='TRUE';
    'VSS1145':
      PIN_NUMBER='(0,0,0,0,0,0,0,0,0,0,0,0,0,0,0,0,0,0,0,0,0,0,0,0,0,0,0,0,0,0,0~
,EA58,0,0,0,0,0,0,0,0,0,0)';
      PINUSE='POWER';
      NO_LOAD_CHECK='Both';
      NO_IO_CHECK='Both';
      NO_ASSERT_CHECK='TRUE';
      NO_DIR_CHECK='TRUE';
      ALLOW_CONNECT='TRUE';
    'VSS1144':
      PIN_NUMBER='(0,0,0,0,0,0,0,0,0,0,0,0,0,0,0,0,0,0,0,0,0,0,0,0,0,0,0,0,0,0,0~
,EA52,0,0,0,0,0,0,0,0,0,0)';
      PINUSE='POWER';
      NO_LOAD_CHECK='Both';
      NO_IO_CHECK='Both';
      NO_ASSERT_CHECK='TRUE';
      NO_DIR_CHECK='TRUE';
      ALLOW_CONNECT='TRUE';
    'VSS1142':
      PIN_NUMBER='(0,0,0,0,0,0,0,0,0,0,0,0,0,0,0,0,0,0,0,0,0,0,0,0,0,0,0,0,0,0,0~
,EA45,0,0,0,0,0,0,0,0,0,0)';
      PINUSE='POWER';
      NO_LOAD_CHECK='Both';
      NO_IO_CHECK='Both';
      NO_ASSERT_CHECK='TRUE';
      NO_DIR_CHECK='TRUE';
      ALLOW_CONNECT='TRUE';
    'VSS1141':
      PIN_NUMBER='(0,0,0,0,0,0,0,0,0,0,0,0,0,0,0,0,0,0,0,0,0,0,0,0,0,0,0,0,0,0,0~
,EA39,0,0,0,0,0,0,0,0,0,0)';
      PINUSE='POWER';
      NO_LOAD_CHECK='Both';
      NO_IO_CHECK='Both';
      NO_ASSERT_CHECK='TRUE';
      NO_DIR_CHECK='TRUE';
      ALLOW_CONNECT='TRUE';
    'VSS1116':
      PIN_NUMBER='(0,0,0,0,0,0,0,0,0,0,0,0,0,0,0,0,0,0,0,0,0,0,0,0,0,0,0,0,0,0,0~
,DY42,0,0,0,0,0,0,0,0,0,0)';
      PINUSE='POWER';
      NO_LOAD_CHECK='Both';
      NO_IO_CHECK='Both';
      NO_ASSERT_CHECK='TRUE';
      NO_DIR_CHECK='TRUE';
      ALLOW_CONNECT='TRUE';
    'VSS1115':
      PIN_NUMBER='(0,0,0,0,0,0,0,0,0,0,0,0,0,0,0,0,0,0,0,0,0,0,0,0,0,0,0,0,0,0,0~
,DY4,0,0,0,0,0,0,0,0,0,0)';
      PINUSE='POWER';
      NO_LOAD_CHECK='Both';
      NO_IO_CHECK='Both';
      NO_ASSERT_CHECK='TRUE';
      NO_DIR_CHECK='TRUE';
      ALLOW_CONNECT='TRUE';
    'VSS1112':
      PIN_NUMBER='(0,0,0,0,0,0,0,0,0,0,0,0,0,0,0,0,0,0,0,0,0,0,0,0,0,0,0,0,0,0,0~
,DY16,0,0,0,0,0,0,0,0,0,0)';
      PINUSE='POWER';
      NO_LOAD_CHECK='Both';
      NO_IO_CHECK='Both';
      NO_ASSERT_CHECK='TRUE';
      NO_DIR_CHECK='TRUE';
      ALLOW_CONNECT='TRUE';
    'VSS1111':
      PIN_NUMBER='(0,0,0,0,0,0,0,0,0,0,0,0,0,0,0,0,0,0,0,0,0,0,0,0,0,0,0,0,0,0,0~
,DY12,0,0,0,0,0,0,0,0,0,0)';
      PINUSE='POWER';
      NO_LOAD_CHECK='Both';
      NO_IO_CHECK='Both';
      NO_ASSERT_CHECK='TRUE';
      NO_DIR_CHECK='TRUE';
      ALLOW_CONNECT='TRUE';
    'VSS1268':
      PIN_NUMBER='(0,0,0,0,0,0,0,0,0,0,0,0,0,0,0,0,0,0,0,0,0,0,0,0,0,0,0,0,0,0,0~
,0,DW9,0,0,0,0,0,0,0,0,0)';
      PINUSE='POWER';
      NO_LOAD_CHECK='Both';
      NO_IO_CHECK='Both';
      NO_ASSERT_CHECK='TRUE';
      NO_DIR_CHECK='TRUE';
      ALLOW_CONNECT='TRUE';
    'VSS1256':
      PIN_NUMBER='(0,0,0,0,0,0,0,0,0,0,0,0,0,0,0,0,0,0,0,0,0,0,0,0,0,0,0,0,0,0,0~
,0,DW64,0,0,0,0,0,0,0,0,0)';
      PINUSE='POWER';
      NO_LOAD_CHECK='Both';
      NO_IO_CHECK='Both';
      NO_ASSERT_CHECK='TRUE';
      NO_DIR_CHECK='TRUE';
      ALLOW_CONNECT='TRUE';
    'VSS1255':
      PIN_NUMBER='(0,0,0,0,0,0,0,0,0,0,0,0,0,0,0,0,0,0,0,0,0,0,0,0,0,0,0,0,0,0,0~
,0,DW62,0,0,0,0,0,0,0,0,0)';
      PINUSE='POWER';
      NO_LOAD_CHECK='Both';
      NO_IO_CHECK='Both';
      NO_ASSERT_CHECK='TRUE';
      NO_DIR_CHECK='TRUE';
      ALLOW_CONNECT='TRUE';
    'VSS1254':
      PIN_NUMBER='(0,0,0,0,0,0,0,0,0,0,0,0,0,0,0,0,0,0,0,0,0,0,0,0,0,0,0,0,0,0,0~
,0,DW58,0,0,0,0,0,0,0,0,0)';
      PINUSE='POWER';
      NO_LOAD_CHECK='Both';
      NO_IO_CHECK='Both';
      NO_ASSERT_CHECK='TRUE';
      NO_DIR_CHECK='TRUE';
      ALLOW_CONNECT='TRUE';
    'VSS1253':
      PIN_NUMBER='(0,0,0,0,0,0,0,0,0,0,0,0,0,0,0,0,0,0,0,0,0,0,0,0,0,0,0,0,0,0,0~
,0,DW56,0,0,0,0,0,0,0,0,0)';
      PINUSE='POWER';
      NO_LOAD_CHECK='Both';
      NO_IO_CHECK='Both';
      NO_ASSERT_CHECK='TRUE';
      NO_DIR_CHECK='TRUE';
      ALLOW_CONNECT='TRUE';
    'VSS1252':
      PIN_NUMBER='(0,0,0,0,0,0,0,0,0,0,0,0,0,0,0,0,0,0,0,0,0,0,0,0,0,0,0,0,0,0,0~
,0,DW54,0,0,0,0,0,0,0,0,0)';
      PINUSE='POWER';
      NO_LOAD_CHECK='Both';
      NO_IO_CHECK='Both';
      NO_ASSERT_CHECK='TRUE';
      NO_DIR_CHECK='TRUE';
      ALLOW_CONNECT='TRUE';
    'VSS1251':
      PIN_NUMBER='(0,0,0,0,0,0,0,0,0,0,0,0,0,0,0,0,0,0,0,0,0,0,0,0,0,0,0,0,0,0,0~
,0,DW52,0,0,0,0,0,0,0,0,0)';
      PINUSE='POWER';
      NO_LOAD_CHECK='Both';
      NO_IO_CHECK='Both';
      NO_ASSERT_CHECK='TRUE';
      NO_DIR_CHECK='TRUE';
      ALLOW_CONNECT='TRUE';
    'VSS1250':
      PIN_NUMBER='(0,0,0,0,0,0,0,0,0,0,0,0,0,0,0,0,0,0,0,0,0,0,0,0,0,0,0,0,0,0,0~
,0,DW50,0,0,0,0,0,0,0,0,0)';
      PINUSE='POWER';
      NO_LOAD_CHECK='Both';
      NO_IO_CHECK='Both';
      NO_ASSERT_CHECK='TRUE';
      NO_DIR_CHECK='TRUE';
      ALLOW_CONNECT='TRUE';
    'VSS1249':
      PIN_NUMBER='(0,0,0,0,0,0,0,0,0,0,0,0,0,0,0,0,0,0,0,0,0,0,0,0,0,0,0,0,0,0,0~
,0,DW5,0,0,0,0,0,0,0,0,0)';
      PINUSE='POWER';
      NO_LOAD_CHECK='Both';
      NO_IO_CHECK='Both';
      NO_ASSERT_CHECK='TRUE';
      NO_DIR_CHECK='TRUE';
      ALLOW_CONNECT='TRUE';
    'VSS1248':
      PIN_NUMBER='(0,0,0,0,0,0,0,0,0,0,0,0,0,0,0,0,0,0,0,0,0,0,0,0,0,0,0,0,0,0,0~
,0,DW48,0,0,0,0,0,0,0,0,0)';
      PINUSE='POWER';
      NO_LOAD_CHECK='Both';
      NO_IO_CHECK='Both';
      NO_ASSERT_CHECK='TRUE';
      NO_DIR_CHECK='TRUE';
      ALLOW_CONNECT='TRUE';
    'VSS1247':
      PIN_NUMBER='(0,0,0,0,0,0,0,0,0,0,0,0,0,0,0,0,0,0,0,0,0,0,0,0,0,0,0,0,0,0,0~
,0,DW45,0,0,0,0,0,0,0,0,0)';
      PINUSE='POWER';
      NO_LOAD_CHECK='Both';
      NO_IO_CHECK='Both';
      NO_ASSERT_CHECK='TRUE';
      NO_DIR_CHECK='TRUE';
      ALLOW_CONNECT='TRUE';
    'VSS1246':
      PIN_NUMBER='(0,0,0,0,0,0,0,0,0,0,0,0,0,0,0,0,0,0,0,0,0,0,0,0,0,0,0,0,0,0,0~
,0,DW43,0,0,0,0,0,0,0,0,0)';
      PINUSE='POWER';
      NO_LOAD_CHECK='Both';
      NO_IO_CHECK='Both';
      NO_ASSERT_CHECK='TRUE';
      NO_DIR_CHECK='TRUE';
      ALLOW_CONNECT='TRUE';
    'VSS1245':
      PIN_NUMBER='(0,0,0,0,0,0,0,0,0,0,0,0,0,0,0,0,0,0,0,0,0,0,0,0,0,0,0,0,0,0,0~
,0,DW41,0,0,0,0,0,0,0,0,0)';
      PINUSE='POWER';
      NO_LOAD_CHECK='Both';
      NO_IO_CHECK='Both';
      NO_ASSERT_CHECK='TRUE';
      NO_DIR_CHECK='TRUE';
      ALLOW_CONNECT='TRUE';
    'VSS1244':
      PIN_NUMBER='(0,0,0,0,0,0,0,0,0,0,0,0,0,0,0,0,0,0,0,0,0,0,0,0,0,0,0,0,0,0,0~
,0,DW39,0,0,0,0,0,0,0,0,0)';
      PINUSE='POWER';
      NO_LOAD_CHECK='Both';
      NO_IO_CHECK='Both';
      NO_ASSERT_CHECK='TRUE';
      NO_DIR_CHECK='TRUE';
      ALLOW_CONNECT='TRUE';
    'VSS1243':
      PIN_NUMBER='(0,0,0,0,0,0,0,0,0,0,0,0,0,0,0,0,0,0,0,0,0,0,0,0,0,0,0,0,0,0,0~
,0,DW37,0,0,0,0,0,0,0,0,0)';
      PINUSE='POWER';
      NO_LOAD_CHECK='Both';
      NO_IO_CHECK='Both';
      NO_ASSERT_CHECK='TRUE';
      NO_DIR_CHECK='TRUE';
      ALLOW_CONNECT='TRUE';
    'VSS1242':
      PIN_NUMBER='(0,0,0,0,0,0,0,0,0,0,0,0,0,0,0,0,0,0,0,0,0,0,0,0,0,0,0,0,0,0,0~
,0,DW35,0,0,0,0,0,0,0,0,0)';
      PINUSE='POWER';
      NO_LOAD_CHECK='Both';
      NO_IO_CHECK='Both';
      NO_ASSERT_CHECK='TRUE';
      NO_DIR_CHECK='TRUE';
      ALLOW_CONNECT='TRUE';
    'VSS1241':
      PIN_NUMBER='(0,0,0,0,0,0,0,0,0,0,0,0,0,0,0,0,0,0,0,0,0,0,0,0,0,0,0,0,0,0,0~
,0,DW33,0,0,0,0,0,0,0,0,0)';
      PINUSE='POWER';
      NO_LOAD_CHECK='Both';
      NO_IO_CHECK='Both';
      NO_ASSERT_CHECK='TRUE';
      NO_DIR_CHECK='TRUE';
      ALLOW_CONNECT='TRUE';
    'VSS1240':
      PIN_NUMBER='(0,0,0,0,0,0,0,0,0,0,0,0,0,0,0,0,0,0,0,0,0,0,0,0,0,0,0,0,0,0,0~
,0,DW31,0,0,0,0,0,0,0,0,0)';
      PINUSE='POWER';
      NO_LOAD_CHECK='Both';
      NO_IO_CHECK='Both';
      NO_ASSERT_CHECK='TRUE';
      NO_DIR_CHECK='TRUE';
      ALLOW_CONNECT='TRUE';
    'VSS1239':
      PIN_NUMBER='(0,0,0,0,0,0,0,0,0,0,0,0,0,0,0,0,0,0,0,0,0,0,0,0,0,0,0,0,0,0,0~
,0,DW29,0,0,0,0,0,0,0,0,0)';
      PINUSE='POWER';
      NO_LOAD_CHECK='Both';
      NO_IO_CHECK='Both';
      NO_ASSERT_CHECK='TRUE';
      NO_DIR_CHECK='TRUE';
      ALLOW_CONNECT='TRUE';
    'VSS1238':
      PIN_NUMBER='(0,0,0,0,0,0,0,0,0,0,0,0,0,0,0,0,0,0,0,0,0,0,0,0,0,0,0,0,0,0,0~
,0,DW27,0,0,0,0,0,0,0,0,0)';
      PINUSE='POWER';
      NO_LOAD_CHECK='Both';
      NO_IO_CHECK='Both';
      NO_ASSERT_CHECK='TRUE';
      NO_DIR_CHECK='TRUE';
      ALLOW_CONNECT='TRUE';
    'VSS1236':
      PIN_NUMBER='(0,0,0,0,0,0,0,0,0,0,0,0,0,0,0,0,0,0,0,0,0,0,0,0,0,0,0,0,0,0,0~
,0,DW25,0,0,0,0,0,0,0,0,0)';
      PINUSE='POWER';
      NO_LOAD_CHECK='Both';
      NO_IO_CHECK='Both';
      NO_ASSERT_CHECK='TRUE';
      NO_DIR_CHECK='TRUE';
      ALLOW_CONNECT='TRUE';
    'VSS1234':
      PIN_NUMBER='(0,0,0,0,0,0,0,0,0,0,0,0,0,0,0,0,0,0,0,0,0,0,0,0,0,0,0,0,0,0,0~
,0,DW23,0,0,0,0,0,0,0,0,0)';
      PINUSE='POWER';
      NO_LOAD_CHECK='Both';
      NO_IO_CHECK='Both';
      NO_ASSERT_CHECK='TRUE';
      NO_DIR_CHECK='TRUE';
      ALLOW_CONNECT='TRUE';
    'VSS1233':
      PIN_NUMBER='(0,0,0,0,0,0,0,0,0,0,0,0,0,0,0,0,0,0,0,0,0,0,0,0,0,0,0,0,0,0,0~
,0,DW19,0,0,0,0,0,0,0,0,0)';
      PINUSE='POWER';
      NO_LOAD_CHECK='Both';
      NO_IO_CHECK='Both';
      NO_ASSERT_CHECK='TRUE';
      NO_DIR_CHECK='TRUE';
      ALLOW_CONNECT='TRUE';
    'VSS1231':
      PIN_NUMBER='(0,0,0,0,0,0,0,0,0,0,0,0,0,0,0,0,0,0,0,0,0,0,0,0,0,0,0,0,0,0,0~
,0,DW17,0,0,0,0,0,0,0,0,0)';
      PINUSE='POWER';
      NO_LOAD_CHECK='Both';
      NO_IO_CHECK='Both';
      NO_ASSERT_CHECK='TRUE';
      NO_DIR_CHECK='TRUE';
      ALLOW_CONNECT='TRUE';
    'VSS1230':
      PIN_NUMBER='(0,0,0,0,0,0,0,0,0,0,0,0,0,0,0,0,0,0,0,0,0,0,0,0,0,0,0,0,0,0,0~
,0,DW13,0,0,0,0,0,0,0,0,0)';
      PINUSE='POWER';
      NO_LOAD_CHECK='Both';
      NO_IO_CHECK='Both';
      NO_ASSERT_CHECK='TRUE';
      NO_DIR_CHECK='TRUE';
      ALLOW_CONNECT='TRUE';
    'VSS1229':
      PIN_NUMBER='(0,0,0,0,0,0,0,0,0,0,0,0,0,0,0,0,0,0,0,0,0,0,0,0,0,0,0,0,0,0,0~
,0,DW1,0,0,0,0,0,0,0,0,0)';
      PINUSE='POWER';
      NO_LOAD_CHECK='Both';
      NO_IO_CHECK='Both';
      NO_ASSERT_CHECK='TRUE';
      NO_DIR_CHECK='TRUE';
      ALLOW_CONNECT='TRUE';
    'VSS1228':
      PIN_NUMBER='(0,0,0,0,0,0,0,0,0,0,0,0,0,0,0,0,0,0,0,0,0,0,0,0,0,0,0,0,0,0,0~
,0,DV91,0,0,0,0,0,0,0,0,0)';
      PINUSE='POWER';
      NO_LOAD_CHECK='Both';
      NO_IO_CHECK='Both';
      NO_ASSERT_CHECK='TRUE';
      NO_DIR_CHECK='TRUE';
      ALLOW_CONNECT='TRUE';
    'VSS1227':
      PIN_NUMBER='(0,0,0,0,0,0,0,0,0,0,0,0,0,0,0,0,0,0,0,0,0,0,0,0,0,0,0,0,0,0,0~
,0,DV87,0,0,0,0,0,0,0,0,0)';
      PINUSE='POWER';
      NO_LOAD_CHECK='Both';
      NO_IO_CHECK='Both';
      NO_ASSERT_CHECK='TRUE';
      NO_DIR_CHECK='TRUE';
      ALLOW_CONNECT='TRUE';
    'VSS1226':
      PIN_NUMBER='(0,0,0,0,0,0,0,0,0,0,0,0,0,0,0,0,0,0,0,0,0,0,0,0,0,0,0,0,0,0,0~
,0,DV83,0,0,0,0,0,0,0,0,0)';
      PINUSE='POWER';
      NO_LOAD_CHECK='Both';
      NO_IO_CHECK='Both';
      NO_ASSERT_CHECK='TRUE';
      NO_DIR_CHECK='TRUE';
      ALLOW_CONNECT='TRUE';
    'VSS1222':
      PIN_NUMBER='(0,0,0,0,0,0,0,0,0,0,0,0,0,0,0,0,0,0,0,0,0,0,0,0,0,0,0,0,0,0,0~
,0,DV81,0,0,0,0,0,0,0,0,0)';
      PINUSE='POWER';
      NO_LOAD_CHECK='Both';
      NO_IO_CHECK='Both';
      NO_ASSERT_CHECK='TRUE';
      NO_DIR_CHECK='TRUE';
      ALLOW_CONNECT='TRUE';
    'VSS1221':
      PIN_NUMBER='(0,0,0,0,0,0,0,0,0,0,0,0,0,0,0,0,0,0,0,0,0,0,0,0,0,0,0,0,0,0,0~
,0,DV8,0,0,0,0,0,0,0,0,0)';
      PINUSE='POWER';
      NO_LOAD_CHECK='Both';
      NO_IO_CHECK='Both';
      NO_ASSERT_CHECK='TRUE';
      NO_DIR_CHECK='TRUE';
      ALLOW_CONNECT='TRUE';
    'VSS1219':
      PIN_NUMBER='(0,0,0,0,0,0,0,0,0,0,0,0,0,0,0,0,0,0,0,0,0,0,0,0,0,0,0,0,0,0,0~
,0,DV79,0,0,0,0,0,0,0,0,0)';
      PINUSE='POWER';
      NO_LOAD_CHECK='Both';
      NO_IO_CHECK='Both';
      NO_ASSERT_CHECK='TRUE';
      NO_DIR_CHECK='TRUE';
      ALLOW_CONNECT='TRUE';
    'VSS1218':
      PIN_NUMBER='(0,0,0,0,0,0,0,0,0,0,0,0,0,0,0,0,0,0,0,0,0,0,0,0,0,0,0,0,0,0,0~
,0,DV77,0,0,0,0,0,0,0,0,0)';
      PINUSE='POWER';
      NO_LOAD_CHECK='Both';
      NO_IO_CHECK='Both';
      NO_ASSERT_CHECK='TRUE';
      NO_DIR_CHECK='TRUE';
      ALLOW_CONNECT='TRUE';
    'VSS1216':
      PIN_NUMBER='(0,0,0,0,0,0,0,0,0,0,0,0,0,0,0,0,0,0,0,0,0,0,0,0,0,0,0,0,0,0,0~
,0,DU88,0,0,0,0,0,0,0,0,0)';
      PINUSE='POWER';
      NO_LOAD_CHECK='Both';
      NO_IO_CHECK='Both';
      NO_ASSERT_CHECK='TRUE';
      NO_DIR_CHECK='TRUE';
      ALLOW_CONNECT='TRUE';
    'VSS1215':
      PIN_NUMBER='(0,0,0,0,0,0,0,0,0,0,0,0,0,0,0,0,0,0,0,0,0,0,0,0,0,0,0,0,0,0,0~
,0,DU84,0,0,0,0,0,0,0,0,0)';
      PINUSE='POWER';
      NO_LOAD_CHECK='Both';
      NO_IO_CHECK='Both';
      NO_ASSERT_CHECK='TRUE';
      NO_DIR_CHECK='TRUE';
      ALLOW_CONNECT='TRUE';
    'VSS1214':
      PIN_NUMBER='(0,0,0,0,0,0,0,0,0,0,0,0,0,0,0,0,0,0,0,0,0,0,0,0,0,0,0,0,0,0,0~
,0,DU78,0,0,0,0,0,0,0,0,0)';
      PINUSE='POWER';
      NO_LOAD_CHECK='Both';
      NO_IO_CHECK='Both';
      NO_ASSERT_CHECK='TRUE';
      NO_DIR_CHECK='TRUE';
      ALLOW_CONNECT='TRUE';
    'VSS1213':
      PIN_NUMBER='(0,0,0,0,0,0,0,0,0,0,0,0,0,0,0,0,0,0,0,0,0,0,0,0,0,0,0,0,0,0,0~
,0,DU76,0,0,0,0,0,0,0,0,0)';
      PINUSE='POWER';
      NO_LOAD_CHECK='Both';
      NO_IO_CHECK='Both';
      NO_ASSERT_CHECK='TRUE';
      NO_DIR_CHECK='TRUE';
      ALLOW_CONNECT='TRUE';
    'VSS1212':
      PIN_NUMBER='(0,0,0,0,0,0,0,0,0,0,0,0,0,0,0,0,0,0,0,0,0,0,0,0,0,0,0,0,0,0,0~
,0,DU33,0,0,0,0,0,0,0,0,0)';
      PINUSE='POWER';
      NO_LOAD_CHECK='Both';
      NO_IO_CHECK='Both';
      NO_ASSERT_CHECK='TRUE';
      NO_DIR_CHECK='TRUE';
      ALLOW_CONNECT='TRUE';
    'VSS1211':
      PIN_NUMBER='(0,0,0,0,0,0,0,0,0,0,0,0,0,0,0,0,0,0,0,0,0,0,0,0,0,0,0,0,0,0,0~
,0,DU27,0,0,0,0,0,0,0,0,0)';
      PINUSE='POWER';
      NO_LOAD_CHECK='Both';
      NO_IO_CHECK='Both';
      NO_ASSERT_CHECK='TRUE';
      NO_DIR_CHECK='TRUE';
      ALLOW_CONNECT='TRUE';
    'VSS1209':
      PIN_NUMBER='(0,0,0,0,0,0,0,0,0,0,0,0,0,0,0,0,0,0,0,0,0,0,0,0,0,0,0,0,0,0,0~
,0,DU21,0,0,0,0,0,0,0,0,0)';
      PINUSE='POWER';
      NO_LOAD_CHECK='Both';
      NO_IO_CHECK='Both';
      NO_ASSERT_CHECK='TRUE';
      NO_DIR_CHECK='TRUE';
      ALLOW_CONNECT='TRUE';
    'VSS1207':
      PIN_NUMBER='(0,0,0,0,0,0,0,0,0,0,0,0,0,0,0,0,0,0,0,0,0,0,0,0,0,0,0,0,0,0,0~
,0,DT8,0,0,0,0,0,0,0,0,0)';
      PINUSE='POWER';
      NO_LOAD_CHECK='Both';
      NO_IO_CHECK='Both';
      NO_ASSERT_CHECK='TRUE';
      NO_DIR_CHECK='TRUE';
      ALLOW_CONNECT='TRUE';
    'VSS1206':
      PIN_NUMBER='(0,0,0,0,0,0,0,0,0,0,0,0,0,0,0,0,0,0,0,0,0,0,0,0,0,0,0,0,0,0,0~
,0,DT75,0,0,0,0,0,0,0,0,0)';
      PINUSE='POWER';
      NO_LOAD_CHECK='Both';
      NO_IO_CHECK='Both';
      NO_ASSERT_CHECK='TRUE';
      NO_DIR_CHECK='TRUE';
      ALLOW_CONNECT='TRUE';
    'VSS1205':
      PIN_NUMBER='(0,0,0,0,0,0,0,0,0,0,0,0,0,0,0,0,0,0,0,0,0,0,0,0,0,0,0,0,0,0,0~
,0,DT71,0,0,0,0,0,0,0,0,0)';
      PINUSE='POWER';
      NO_LOAD_CHECK='Both';
      NO_IO_CHECK='Both';
      NO_ASSERT_CHECK='TRUE';
      NO_DIR_CHECK='TRUE';
      ALLOW_CONNECT='TRUE';
    'VSS1204':
      PIN_NUMBER='(0,0,0,0,0,0,0,0,0,0,0,0,0,0,0,0,0,0,0,0,0,0,0,0,0,0,0,0,0,0,0~
,0,DT69,0,0,0,0,0,0,0,0,0)';
      PINUSE='POWER';
      NO_LOAD_CHECK='Both';
      NO_IO_CHECK='Both';
      NO_ASSERT_CHECK='TRUE';
      NO_DIR_CHECK='TRUE';
      ALLOW_CONNECT='TRUE';
    'VSS1203':
      PIN_NUMBER='(0,0,0,0,0,0,0,0,0,0,0,0,0,0,0,0,0,0,0,0,0,0,0,0,0,0,0,0,0,0,0~
,0,DT65,0,0,0,0,0,0,0,0,0)';
      PINUSE='POWER';
      NO_LOAD_CHECK='Both';
      NO_IO_CHECK='Both';
      NO_ASSERT_CHECK='TRUE';
      NO_DIR_CHECK='TRUE';
      ALLOW_CONNECT='TRUE';
    'VSS1202':
      PIN_NUMBER='(0,0,0,0,0,0,0,0,0,0,0,0,0,0,0,0,0,0,0,0,0,0,0,0,0,0,0,0,0,0,0~
,0,DT57,0,0,0,0,0,0,0,0,0)';
      PINUSE='POWER';
      NO_LOAD_CHECK='Both';
      NO_IO_CHECK='Both';
      NO_ASSERT_CHECK='TRUE';
      NO_DIR_CHECK='TRUE';
      ALLOW_CONNECT='TRUE';
    'VSS1201':
      PIN_NUMBER='(0,0,0,0,0,0,0,0,0,0,0,0,0,0,0,0,0,0,0,0,0,0,0,0,0,0,0,0,0,0,0~
,0,DT47,0,0,0,0,0,0,0,0,0)';
      PINUSE='POWER';
      NO_LOAD_CHECK='Both';
      NO_IO_CHECK='Both';
      NO_ASSERT_CHECK='TRUE';
      NO_DIR_CHECK='TRUE';
      ALLOW_CONNECT='TRUE';
    'VSS1199':
      PIN_NUMBER='(0,0,0,0,0,0,0,0,0,0,0,0,0,0,0,0,0,0,0,0,0,0,0,0,0,0,0,0,0,0,0~
,0,DT40,0,0,0,0,0,0,0,0,0)';
      PINUSE='POWER';
      NO_LOAD_CHECK='Both';
      NO_IO_CHECK='Both';
      NO_ASSERT_CHECK='TRUE';
      NO_DIR_CHECK='TRUE';
      ALLOW_CONNECT='TRUE';
    'VSS1196':
      PIN_NUMBER='(0,0,0,0,0,0,0,0,0,0,0,0,0,0,0,0,0,0,0,0,0,0,0,0,0,0,0,0,0,0,0~
,0,DT38,0,0,0,0,0,0,0,0,0)';
      PINUSE='POWER';
      NO_LOAD_CHECK='Both';
      NO_IO_CHECK='Both';
      NO_ASSERT_CHECK='TRUE';
      NO_DIR_CHECK='TRUE';
      ALLOW_CONNECT='TRUE';
    'VSS1194':
      PIN_NUMBER='(0,0,0,0,0,0,0,0,0,0,0,0,0,0,0,0,0,0,0,0,0,0,0,0,0,0,0,0,0,0,0~
,0,DT34,0,0,0,0,0,0,0,0,0)';
      PINUSE='POWER';
      NO_LOAD_CHECK='Both';
      NO_IO_CHECK='Both';
      NO_ASSERT_CHECK='TRUE';
      NO_DIR_CHECK='TRUE';
      ALLOW_CONNECT='TRUE';
    'VSS1192':
      PIN_NUMBER='(0,0,0,0,0,0,0,0,0,0,0,0,0,0,0,0,0,0,0,0,0,0,0,0,0,0,0,0,0,0,0~
,0,DT32,0,0,0,0,0,0,0,0,0)';
      PINUSE='POWER';
      NO_LOAD_CHECK='Both';
      NO_IO_CHECK='Both';
      NO_ASSERT_CHECK='TRUE';
      NO_DIR_CHECK='TRUE';
      ALLOW_CONNECT='TRUE';
    'VSS1191':
      PIN_NUMBER='(0,0,0,0,0,0,0,0,0,0,0,0,0,0,0,0,0,0,0,0,0,0,0,0,0,0,0,0,0,0,0~
,0,DT28,0,0,0,0,0,0,0,0,0)';
      PINUSE='POWER';
      NO_LOAD_CHECK='Both';
      NO_IO_CHECK='Both';
      NO_ASSERT_CHECK='TRUE';
      NO_DIR_CHECK='TRUE';
      ALLOW_CONNECT='TRUE';
    'VSS1190':
      PIN_NUMBER='(0,0,0,0,0,0,0,0,0,0,0,0,0,0,0,0,0,0,0,0,0,0,0,0,0,0,0,0,0,0,0~
,0,DT22,0,0,0,0,0,0,0,0,0)';
      PINUSE='POWER';
      NO_LOAD_CHECK='Both';
      NO_IO_CHECK='Both';
      NO_ASSERT_CHECK='TRUE';
      NO_DIR_CHECK='TRUE';
      ALLOW_CONNECT='TRUE';
    'VSS1189':
      PIN_NUMBER='(0,0,0,0,0,0,0,0,0,0,0,0,0,0,0,0,0,0,0,0,0,0,0,0,0,0,0,0,0,0,0~
,0,DT12,0,0,0,0,0,0,0,0,0)';
      PINUSE='POWER';
      NO_LOAD_CHECK='Both';
      NO_IO_CHECK='Both';
      NO_ASSERT_CHECK='TRUE';
      NO_DIR_CHECK='TRUE';
      ALLOW_CONNECT='TRUE';
    'VSS1187':
      PIN_NUMBER='(0,0,0,0,0,0,0,0,0,0,0,0,0,0,0,0,0,0,0,0,0,0,0,0,0,0,0,0,0,0,0~
,0,DR9,0,0,0,0,0,0,0,0,0)';
      PINUSE='POWER';
      NO_LOAD_CHECK='Both';
      NO_IO_CHECK='Both';
      NO_ASSERT_CHECK='TRUE';
      NO_DIR_CHECK='TRUE';
      ALLOW_CONNECT='TRUE';
    'VSS1186':
      PIN_NUMBER='(0,0,0,0,0,0,0,0,0,0,0,0,0,0,0,0,0,0,0,0,0,0,0,0,0,0,0,0,0,0,0~
,0,DR88,0,0,0,0,0,0,0,0,0)';
      PINUSE='POWER';
      NO_LOAD_CHECK='Both';
      NO_IO_CHECK='Both';
      NO_ASSERT_CHECK='TRUE';
      NO_DIR_CHECK='TRUE';
      ALLOW_CONNECT='TRUE';
    'VSS1184':
      PIN_NUMBER='(0,0,0,0,0,0,0,0,0,0,0,0,0,0,0,0,0,0,0,0,0,0,0,0,0,0,0,0,0,0,0~
,0,DR84,0,0,0,0,0,0,0,0,0)';
      PINUSE='POWER';
      NO_LOAD_CHECK='Both';
      NO_IO_CHECK='Both';
      NO_ASSERT_CHECK='TRUE';
      NO_DIR_CHECK='TRUE';
      ALLOW_CONNECT='TRUE';
    'VSS1183':
      PIN_NUMBER='(0,0,0,0,0,0,0,0,0,0,0,0,0,0,0,0,0,0,0,0,0,0,0,0,0,0,0,0,0,0,0~
,0,DR78,0,0,0,0,0,0,0,0,0)';
      PINUSE='POWER';
      NO_LOAD_CHECK='Both';
      NO_IO_CHECK='Both';
      NO_ASSERT_CHECK='TRUE';
      NO_DIR_CHECK='TRUE';
      ALLOW_CONNECT='TRUE';
    'VSS1182':
      PIN_NUMBER='(0,0,0,0,0,0,0,0,0,0,0,0,0,0,0,0,0,0,0,0,0,0,0,0,0,0,0,0,0,0,0~
,0,DR74,0,0,0,0,0,0,0,0,0)';
      PINUSE='POWER';
      NO_LOAD_CHECK='Both';
      NO_IO_CHECK='Both';
      NO_ASSERT_CHECK='TRUE';
      NO_DIR_CHECK='TRUE';
      ALLOW_CONNECT='TRUE';
    'VSS1181':
      PIN_NUMBER='(0,0,0,0,0,0,0,0,0,0,0,0,0,0,0,0,0,0,0,0,0,0,0,0,0,0,0,0,0,0,0~
,0,DR66,0,0,0,0,0,0,0,0,0)';
      PINUSE='POWER';
      NO_LOAD_CHECK='Both';
      NO_IO_CHECK='Both';
      NO_ASSERT_CHECK='TRUE';
      NO_DIR_CHECK='TRUE';
      ALLOW_CONNECT='TRUE';
    'VSS1179':
      PIN_NUMBER='(0,0,0,0,0,0,0,0,0,0,0,0,0,0,0,0,0,0,0,0,0,0,0,0,0,0,0,0,0,0,0~
,0,DR56,0,0,0,0,0,0,0,0,0)';
      PINUSE='POWER';
      NO_LOAD_CHECK='Both';
      NO_IO_CHECK='Both';
      NO_ASSERT_CHECK='TRUE';
      NO_DIR_CHECK='TRUE';
      ALLOW_CONNECT='TRUE';
    'VSS1178':
      PIN_NUMBER='(0,0,0,0,0,0,0,0,0,0,0,0,0,0,0,0,0,0,0,0,0,0,0,0,0,0,0,0,0,0,0~
,0,DR50,0,0,0,0,0,0,0,0,0)';
      PINUSE='POWER';
      NO_LOAD_CHECK='Both';
      NO_IO_CHECK='Both';
      NO_ASSERT_CHECK='TRUE';
      NO_DIR_CHECK='TRUE';
      ALLOW_CONNECT='TRUE';
    'VSS1177':
      PIN_NUMBER='(0,0,0,0,0,0,0,0,0,0,0,0,0,0,0,0,0,0,0,0,0,0,0,0,0,0,0,0,0,0,0~
,0,DR48,0,0,0,0,0,0,0,0,0)';
      PINUSE='POWER';
      NO_LOAD_CHECK='Both';
      NO_IO_CHECK='Both';
      NO_ASSERT_CHECK='TRUE';
      NO_DIR_CHECK='TRUE';
      ALLOW_CONNECT='TRUE';
    'VSS1176':
      PIN_NUMBER='(0,0,0,0,0,0,0,0,0,0,0,0,0,0,0,0,0,0,0,0,0,0,0,0,0,0,0,0,0,0,0~
,0,DR43,0,0,0,0,0,0,0,0,0)';
      PINUSE='POWER';
      NO_LOAD_CHECK='Both';
      NO_IO_CHECK='Both';
      NO_ASSERT_CHECK='TRUE';
      NO_DIR_CHECK='TRUE';
      ALLOW_CONNECT='TRUE';
    'VSS1175':
      PIN_NUMBER='(0,0,0,0,0,0,0,0,0,0,0,0,0,0,0,0,0,0,0,0,0,0,0,0,0,0,0,0,0,0,0~
,0,DR41,0,0,0,0,0,0,0,0,0)';
      PINUSE='POWER';
      NO_LOAD_CHECK='Both';
      NO_IO_CHECK='Both';
      NO_ASSERT_CHECK='TRUE';
      NO_DIR_CHECK='TRUE';
      ALLOW_CONNECT='TRUE';
    'VSS1174':
      PIN_NUMBER='(0,0,0,0,0,0,0,0,0,0,0,0,0,0,0,0,0,0,0,0,0,0,0,0,0,0,0,0,0,0,0~
,0,DR37,0,0,0,0,0,0,0,0,0)';
      PINUSE='POWER';
      NO_LOAD_CHECK='Both';
      NO_IO_CHECK='Both';
      NO_ASSERT_CHECK='TRUE';
      NO_DIR_CHECK='TRUE';
      ALLOW_CONNECT='TRUE';
    'VSS1173':
      PIN_NUMBER='(0,0,0,0,0,0,0,0,0,0,0,0,0,0,0,0,0,0,0,0,0,0,0,0,0,0,0,0,0,0,0~
,0,DR31,0,0,0,0,0,0,0,0,0)';
      PINUSE='POWER';
      NO_LOAD_CHECK='Both';
      NO_IO_CHECK='Both';
      NO_ASSERT_CHECK='TRUE';
      NO_DIR_CHECK='TRUE';
      ALLOW_CONNECT='TRUE';
    'VSS1172':
      PIN_NUMBER='(0,0,0,0,0,0,0,0,0,0,0,0,0,0,0,0,0,0,0,0,0,0,0,0,0,0,0,0,0,0,0~
,0,DR29,0,0,0,0,0,0,0,0,0)';
      PINUSE='POWER';
      NO_LOAD_CHECK='Both';
      NO_IO_CHECK='Both';
      NO_ASSERT_CHECK='TRUE';
      NO_DIR_CHECK='TRUE';
      ALLOW_CONNECT='TRUE';
    'VSS1169':
      PIN_NUMBER='(0,0,0,0,0,0,0,0,0,0,0,0,0,0,0,0,0,0,0,0,0,0,0,0,0,0,0,0,0,0,0~
,0,DR23,0,0,0,0,0,0,0,0,0)';
      PINUSE='POWER';
      NO_LOAD_CHECK='Both';
      NO_IO_CHECK='Both';
      NO_ASSERT_CHECK='TRUE';
      NO_DIR_CHECK='TRUE';
      ALLOW_CONNECT='TRUE';
    'VSS1166':
      PIN_NUMBER='(0,0,0,0,0,0,0,0,0,0,0,0,0,0,0,0,0,0,0,0,0,0,0,0,0,0,0,0,0,0,0~
,0,DR19,0,0,0,0,0,0,0,0,0)';
      PINUSE='POWER';
      NO_LOAD_CHECK='Both';
      NO_IO_CHECK='Both';
      NO_ASSERT_CHECK='TRUE';
      NO_DIR_CHECK='TRUE';
      ALLOW_CONNECT='TRUE';
    'VSS1164':
      PIN_NUMBER='(0,0,0,0,0,0,0,0,0,0,0,0,0,0,0,0,0,0,0,0,0,0,0,0,0,0,0,0,0,0,0~
,0,DR13,0,0,0,0,0,0,0,0,0)';
      PINUSE='POWER';
      NO_LOAD_CHECK='Both';
      NO_IO_CHECK='Both';
      NO_ASSERT_CHECK='TRUE';
      NO_DIR_CHECK='TRUE';
      ALLOW_CONNECT='TRUE';
    'VSS1162':
      PIN_NUMBER='(0,0,0,0,0,0,0,0,0,0,0,0,0,0,0,0,0,0,0,0,0,0,0,0,0,0,0,0,0,0,0~
,0,DR1,0,0,0,0,0,0,0,0,0)';
      PINUSE='POWER';
      NO_LOAD_CHECK='Both';
      NO_IO_CHECK='Both';
      NO_ASSERT_CHECK='TRUE';
      NO_DIR_CHECK='TRUE';
      ALLOW_CONNECT='TRUE';
    'VSS1160':
      PIN_NUMBER='(0,0,0,0,0,0,0,0,0,0,0,0,0,0,0,0,0,0,0,0,0,0,0,0,0,0,0,0,0,0,0~
,0,DP87,0,0,0,0,0,0,0,0,0)';
      PINUSE='POWER';
      NO_LOAD_CHECK='Both';
      NO_IO_CHECK='Both';
      NO_ASSERT_CHECK='TRUE';
      NO_DIR_CHECK='TRUE';
      ALLOW_CONNECT='TRUE';
    'VSS1159':
      PIN_NUMBER='(0,0,0,0,0,0,0,0,0,0,0,0,0,0,0,0,0,0,0,0,0,0,0,0,0,0,0,0,0,0,0~
,0,DP81,0,0,0,0,0,0,0,0,0)';
      PINUSE='POWER';
      NO_LOAD_CHECK='Both';
      NO_IO_CHECK='Both';
      NO_ASSERT_CHECK='TRUE';
      NO_DIR_CHECK='TRUE';
      ALLOW_CONNECT='TRUE';
    'VSS1157':
      PIN_NUMBER='(0,0,0,0,0,0,0,0,0,0,0,0,0,0,0,0,0,0,0,0,0,0,0,0,0,0,0,0,0,0,0~
,0,DP8,0,0,0,0,0,0,0,0,0)';
      PINUSE='POWER';
      NO_LOAD_CHECK='Both';
      NO_IO_CHECK='Both';
      NO_ASSERT_CHECK='TRUE';
      NO_DIR_CHECK='TRUE';
      ALLOW_CONNECT='TRUE';
    'VSS1154':
      PIN_NUMBER='(0,0,0,0,0,0,0,0,0,0,0,0,0,0,0,0,0,0,0,0,0,0,0,0,0,0,0,0,0,0,0~
,0,DP73,0,0,0,0,0,0,0,0,0)';
      PINUSE='POWER';
      NO_LOAD_CHECK='Both';
      NO_IO_CHECK='Both';
      NO_ASSERT_CHECK='TRUE';
      NO_DIR_CHECK='TRUE';
      ALLOW_CONNECT='TRUE';
    'VSS1153':
      PIN_NUMBER='(0,0,0,0,0,0,0,0,0,0,0,0,0,0,0,0,0,0,0,0,0,0,0,0,0,0,0,0,0,0,0~
,0,DP49,0,0,0,0,0,0,0,0,0)';
      PINUSE='POWER';
      NO_LOAD_CHECK='Both';
      NO_IO_CHECK='Both';
      NO_ASSERT_CHECK='TRUE';
      NO_DIR_CHECK='TRUE';
      ALLOW_CONNECT='TRUE';
    'VSS1152':
      PIN_NUMBER='(0,0,0,0,0,0,0,0,0,0,0,0,0,0,0,0,0,0,0,0,0,0,0,0,0,0,0,0,0,0,0~
,0,DP4,0,0,0,0,0,0,0,0,0)';
      PINUSE='POWER';
      NO_LOAD_CHECK='Both';
      NO_IO_CHECK='Both';
      NO_ASSERT_CHECK='TRUE';
      NO_DIR_CHECK='TRUE';
      ALLOW_CONNECT='TRUE';
    'VSS1151':
      PIN_NUMBER='(0,0,0,0,0,0,0,0,0,0,0,0,0,0,0,0,0,0,0,0,0,0,0,0,0,0,0,0,0,0,0~
,0,DP36,0,0,0,0,0,0,0,0,0)';
      PINUSE='POWER';
      NO_LOAD_CHECK='Both';
      NO_IO_CHECK='Both';
      NO_ASSERT_CHECK='TRUE';
      NO_DIR_CHECK='TRUE';
      ALLOW_CONNECT='TRUE';
    'VSS1150':
      PIN_NUMBER='(0,0,0,0,0,0,0,0,0,0,0,0,0,0,0,0,0,0,0,0,0,0,0,0,0,0,0,0,0,0,0~
,0,DP30,0,0,0,0,0,0,0,0,0)';
      PINUSE='POWER';
      NO_LOAD_CHECK='Both';
      NO_IO_CHECK='Both';
      NO_ASSERT_CHECK='TRUE';
      NO_DIR_CHECK='TRUE';
      ALLOW_CONNECT='TRUE';
    'VSS1149':
      PIN_NUMBER='(0,0,0,0,0,0,0,0,0,0,0,0,0,0,0,0,0,0,0,0,0,0,0,0,0,0,0,0,0,0,0~
,0,DP16,0,0,0,0,0,0,0,0,0)';
      PINUSE='POWER';
      NO_LOAD_CHECK='Both';
      NO_IO_CHECK='Both';
      NO_ASSERT_CHECK='TRUE';
      NO_DIR_CHECK='TRUE';
      ALLOW_CONNECT='TRUE';
    'VSS1148':
      PIN_NUMBER='(0,0,0,0,0,0,0,0,0,0,0,0,0,0,0,0,0,0,0,0,0,0,0,0,0,0,0,0,0,0,0~
,0,DN88,0,0,0,0,0,0,0,0,0)';
      PINUSE='POWER';
      NO_LOAD_CHECK='Both';
      NO_IO_CHECK='Both';
      NO_ASSERT_CHECK='TRUE';
      NO_DIR_CHECK='TRUE';
      ALLOW_CONNECT='TRUE';
    'VSS1147':
      PIN_NUMBER='(0,0,0,0,0,0,0,0,0,0,0,0,0,0,0,0,0,0,0,0,0,0,0,0,0,0,0,0,0,0,0~
,0,DN84,0,0,0,0,0,0,0,0,0)';
      PINUSE='POWER';
      NO_LOAD_CHECK='Both';
      NO_IO_CHECK='Both';
      NO_ASSERT_CHECK='TRUE';
      NO_DIR_CHECK='TRUE';
      ALLOW_CONNECT='TRUE';
    'VSS1143':
      PIN_NUMBER='(0,0,0,0,0,0,0,0,0,0,0,0,0,0,0,0,0,0,0,0,0,0,0,0,0,0,0,0,0,0,0~
,0,DN78,0,0,0,0,0,0,0,0,0)';
      PINUSE='POWER';
      NO_LOAD_CHECK='Both';
      NO_IO_CHECK='Both';
      NO_ASSERT_CHECK='TRUE';
      NO_DIR_CHECK='TRUE';
      ALLOW_CONNECT='TRUE';
    'VSS1140':
      PIN_NUMBER='(0,0,0,0,0,0,0,0,0,0,0,0,0,0,0,0,0,0,0,0,0,0,0,0,0,0,0,0,0,0,0~
,0,DM8,0,0,0,0,0,0,0,0,0)';
      PINUSE='POWER';
      NO_LOAD_CHECK='Both';
      NO_IO_CHECK='Both';
      NO_ASSERT_CHECK='TRUE';
      NO_DIR_CHECK='TRUE';
      ALLOW_CONNECT='TRUE';
    'VSS1139':
      PIN_NUMBER='(0,0,0,0,0,0,0,0,0,0,0,0,0,0,0,0,0,0,0,0,0,0,0,0,0,0,0,0,0,0,0~
,0,DM79,0,0,0,0,0,0,0,0,0)';
      PINUSE='POWER';
      NO_LOAD_CHECK='Both';
      NO_IO_CHECK='Both';
      NO_ASSERT_CHECK='TRUE';
      NO_DIR_CHECK='TRUE';
      ALLOW_CONNECT='TRUE';
    'VSS1138':
      PIN_NUMBER='(0,0,0,0,0,0,0,0,0,0,0,0,0,0,0,0,0,0,0,0,0,0,0,0,0,0,0,0,0,0,0~
,0,DM77,0,0,0,0,0,0,0,0,0)';
      PINUSE='POWER';
      NO_LOAD_CHECK='Both';
      NO_IO_CHECK='Both';
      NO_ASSERT_CHECK='TRUE';
      NO_DIR_CHECK='TRUE';
      ALLOW_CONNECT='TRUE';
    'VSS1137':
      PIN_NUMBER='(0,0,0,0,0,0,0,0,0,0,0,0,0,0,0,0,0,0,0,0,0,0,0,0,0,0,0,0,0,0,0~
,0,DM75,0,0,0,0,0,0,0,0,0)';
      PINUSE='POWER';
      NO_LOAD_CHECK='Both';
      NO_IO_CHECK='Both';
      NO_ASSERT_CHECK='TRUE';
      NO_DIR_CHECK='TRUE';
      ALLOW_CONNECT='TRUE';
    'VSS1136':
      PIN_NUMBER='(0,0,0,0,0,0,0,0,0,0,0,0,0,0,0,0,0,0,0,0,0,0,0,0,0,0,0,0,0,0,0~
,0,DM71,0,0,0,0,0,0,0,0,0)';
      PINUSE='POWER';
      NO_LOAD_CHECK='Both';
      NO_IO_CHECK='Both';
      NO_ASSERT_CHECK='TRUE';
      NO_DIR_CHECK='TRUE';
      ALLOW_CONNECT='TRUE';
    'VSS1135':
      PIN_NUMBER='(0,0,0,0,0,0,0,0,0,0,0,0,0,0,0,0,0,0,0,0,0,0,0,0,0,0,0,0,0,0,0~
,0,DM69,0,0,0,0,0,0,0,0,0)';
      PINUSE='POWER';
      NO_LOAD_CHECK='Both';
      NO_IO_CHECK='Both';
      NO_ASSERT_CHECK='TRUE';
      NO_DIR_CHECK='TRUE';
      ALLOW_CONNECT='TRUE';
    'VSS1134':
      PIN_NUMBER='(0,0,0,0,0,0,0,0,0,0,0,0,0,0,0,0,0,0,0,0,0,0,0,0,0,0,0,0,0,0,0~
,0,DM67,0,0,0,0,0,0,0,0,0)';
      PINUSE='POWER';
      NO_LOAD_CHECK='Both';
      NO_IO_CHECK='Both';
      NO_ASSERT_CHECK='TRUE';
      NO_DIR_CHECK='TRUE';
      ALLOW_CONNECT='TRUE';
    'VSS1133':
      PIN_NUMBER='(0,0,0,0,0,0,0,0,0,0,0,0,0,0,0,0,0,0,0,0,0,0,0,0,0,0,0,0,0,0,0~
,0,DM65,0,0,0,0,0,0,0,0,0)';
      PINUSE='POWER';
      NO_LOAD_CHECK='Both';
      NO_IO_CHECK='Both';
      NO_ASSERT_CHECK='TRUE';
      NO_DIR_CHECK='TRUE';
      ALLOW_CONNECT='TRUE';
    'VSS1132':
      PIN_NUMBER='(0,0,0,0,0,0,0,0,0,0,0,0,0,0,0,0,0,0,0,0,0,0,0,0,0,0,0,0,0,0,0~
,0,DM63,0,0,0,0,0,0,0,0,0)';
      PINUSE='POWER';
      NO_LOAD_CHECK='Both';
      NO_IO_CHECK='Both';
      NO_ASSERT_CHECK='TRUE';
      NO_DIR_CHECK='TRUE';
      ALLOW_CONNECT='TRUE';
    'VSS1130':
      PIN_NUMBER='(0,0,0,0,0,0,0,0,0,0,0,0,0,0,0,0,0,0,0,0,0,0,0,0,0,0,0,0,0,0,0~
,0,DM61,0,0,0,0,0,0,0,0,0)';
      PINUSE='POWER';
      NO_LOAD_CHECK='Both';
      NO_IO_CHECK='Both';
      NO_ASSERT_CHECK='TRUE';
      NO_DIR_CHECK='TRUE';
      ALLOW_CONNECT='TRUE';
    'VSS1128':
      PIN_NUMBER='(0,0,0,0,0,0,0,0,0,0,0,0,0,0,0,0,0,0,0,0,0,0,0,0,0,0,0,0,0,0,0~
,0,DM59,0,0,0,0,0,0,0,0,0)';
      PINUSE='POWER';
      NO_LOAD_CHECK='Both';
      NO_IO_CHECK='Both';
      NO_ASSERT_CHECK='TRUE';
      NO_DIR_CHECK='TRUE';
      ALLOW_CONNECT='TRUE';
    'VSS1127':
      PIN_NUMBER='(0,0,0,0,0,0,0,0,0,0,0,0,0,0,0,0,0,0,0,0,0,0,0,0,0,0,0,0,0,0,0~
,0,DM57,0,0,0,0,0,0,0,0,0)';
      PINUSE='POWER';
      NO_LOAD_CHECK='Both';
      NO_IO_CHECK='Both';
      NO_ASSERT_CHECK='TRUE';
      NO_DIR_CHECK='TRUE';
      ALLOW_CONNECT='TRUE';
    'VSS1124':
      PIN_NUMBER='(0,0,0,0,0,0,0,0,0,0,0,0,0,0,0,0,0,0,0,0,0,0,0,0,0,0,0,0,0,0,0~
,0,DM55,0,0,0,0,0,0,0,0,0)';
      PINUSE='POWER';
      NO_LOAD_CHECK='Both';
      NO_IO_CHECK='Both';
      NO_ASSERT_CHECK='TRUE';
      NO_DIR_CHECK='TRUE';
      ALLOW_CONNECT='TRUE';
    'VSS1123':
      PIN_NUMBER='(0,0,0,0,0,0,0,0,0,0,0,0,0,0,0,0,0,0,0,0,0,0,0,0,0,0,0,0,0,0,0~
,0,DM53,0,0,0,0,0,0,0,0,0)';
      PINUSE='POWER';
      NO_LOAD_CHECK='Both';
      NO_IO_CHECK='Both';
      NO_ASSERT_CHECK='TRUE';
      NO_DIR_CHECK='TRUE';
      ALLOW_CONNECT='TRUE';
    'VSS1122':
      PIN_NUMBER='(0,0,0,0,0,0,0,0,0,0,0,0,0,0,0,0,0,0,0,0,0,0,0,0,0,0,0,0,0,0,0~
,0,DM49,0,0,0,0,0,0,0,0,0)';
      PINUSE='POWER';
      NO_LOAD_CHECK='Both';
      NO_IO_CHECK='Both';
      NO_ASSERT_CHECK='TRUE';
      NO_DIR_CHECK='TRUE';
      ALLOW_CONNECT='TRUE';
    'VSS1121':
      PIN_NUMBER='(0,0,0,0,0,0,0,0,0,0,0,0,0,0,0,0,0,0,0,0,0,0,0,0,0,0,0,0,0,0,0~
,0,DM47,0,0,0,0,0,0,0,0,0)';
      PINUSE='POWER';
      NO_LOAD_CHECK='Both';
      NO_IO_CHECK='Both';
      NO_ASSERT_CHECK='TRUE';
      NO_DIR_CHECK='TRUE';
      ALLOW_CONNECT='TRUE';
    'VSS1120':
      PIN_NUMBER='(0,0,0,0,0,0,0,0,0,0,0,0,0,0,0,0,0,0,0,0,0,0,0,0,0,0,0,0,0,0,0~
,0,DM44,0,0,0,0,0,0,0,0,0)';
      PINUSE='POWER';
      NO_LOAD_CHECK='Both';
      NO_IO_CHECK='Both';
      NO_ASSERT_CHECK='TRUE';
      NO_DIR_CHECK='TRUE';
      ALLOW_CONNECT='TRUE';
    'VSS1119':
      PIN_NUMBER='(0,0,0,0,0,0,0,0,0,0,0,0,0,0,0,0,0,0,0,0,0,0,0,0,0,0,0,0,0,0,0~
,0,DM42,0,0,0,0,0,0,0,0,0)';
      PINUSE='POWER';
      NO_LOAD_CHECK='Both';
      NO_IO_CHECK='Both';
      NO_ASSERT_CHECK='TRUE';
      NO_DIR_CHECK='TRUE';
      ALLOW_CONNECT='TRUE';
    'VSS1118':
      PIN_NUMBER='(0,0,0,0,0,0,0,0,0,0,0,0,0,0,0,0,0,0,0,0,0,0,0,0,0,0,0,0,0,0,0~
,0,DM40,0,0,0,0,0,0,0,0,0)';
      PINUSE='POWER';
      NO_LOAD_CHECK='Both';
      NO_IO_CHECK='Both';
      NO_ASSERT_CHECK='TRUE';
      NO_DIR_CHECK='TRUE';
      ALLOW_CONNECT='TRUE';
    'VSS1117':
      PIN_NUMBER='(0,0,0,0,0,0,0,0,0,0,0,0,0,0,0,0,0,0,0,0,0,0,0,0,0,0,0,0,0,0,0~
,0,DM4,0,0,0,0,0,0,0,0,0)';
      PINUSE='POWER';
      NO_LOAD_CHECK='Both';
      NO_IO_CHECK='Both';
      NO_ASSERT_CHECK='TRUE';
      NO_DIR_CHECK='TRUE';
      ALLOW_CONNECT='TRUE';
    'VSS1114':
      PIN_NUMBER='(0,0,0,0,0,0,0,0,0,0,0,0,0,0,0,0,0,0,0,0,0,0,0,0,0,0,0,0,0,0,0~
,0,DM38,0,0,0,0,0,0,0,0,0)';
      PINUSE='POWER';
      NO_LOAD_CHECK='Both';
      NO_IO_CHECK='Both';
      NO_ASSERT_CHECK='TRUE';
      NO_DIR_CHECK='TRUE';
      ALLOW_CONNECT='TRUE';
    'VSS1113':
      PIN_NUMBER='(0,0,0,0,0,0,0,0,0,0,0,0,0,0,0,0,0,0,0,0,0,0,0,0,0,0,0,0,0,0,0~
,0,DM36,0,0,0,0,0,0,0,0,0)';
      PINUSE='POWER';
      NO_LOAD_CHECK='Both';
      NO_IO_CHECK='Both';
      NO_ASSERT_CHECK='TRUE';
      NO_DIR_CHECK='TRUE';
      ALLOW_CONNECT='TRUE';
    'VSS1110':
      PIN_NUMBER='(0,0,0,0,0,0,0,0,0,0,0,0,0,0,0,0,0,0,0,0,0,0,0,0,0,0,0,0,0,0,0~
,0,DM34,0,0,0,0,0,0,0,0,0)';
      PINUSE='POWER';
      NO_LOAD_CHECK='Both';
      NO_IO_CHECK='Both';
      NO_ASSERT_CHECK='TRUE';
      NO_DIR_CHECK='TRUE';
      ALLOW_CONNECT='TRUE';
    'VSS1109':
      PIN_NUMBER='(0,0,0,0,0,0,0,0,0,0,0,0,0,0,0,0,0,0,0,0,0,0,0,0,0,0,0,0,0,0,0~
,0,DM32,0,0,0,0,0,0,0,0,0)';
      PINUSE='POWER';
      NO_LOAD_CHECK='Both';
      NO_IO_CHECK='Both';
      NO_ASSERT_CHECK='TRUE';
      NO_DIR_CHECK='TRUE';
      ALLOW_CONNECT='TRUE';
    'VSS1108':
      PIN_NUMBER='(0,0,0,0,0,0,0,0,0,0,0,0,0,0,0,0,0,0,0,0,0,0,0,0,0,0,0,0,0,0,0~
,0,DM30,0,0,0,0,0,0,0,0,0)';
      PINUSE='POWER';
      NO_LOAD_CHECK='Both';
      NO_IO_CHECK='Both';
      NO_ASSERT_CHECK='TRUE';
      NO_DIR_CHECK='TRUE';
      ALLOW_CONNECT='TRUE';
    'VSS1107':
      PIN_NUMBER='(0,0,0,0,0,0,0,0,0,0,0,0,0,0,0,0,0,0,0,0,0,0,0,0,0,0,0,0,0,0,0~
,0,DM28,0,0,0,0,0,0,0,0,0)';
      PINUSE='POWER';
      NO_LOAD_CHECK='Both';
      NO_IO_CHECK='Both';
      NO_ASSERT_CHECK='TRUE';
      NO_DIR_CHECK='TRUE';
      ALLOW_CONNECT='TRUE';
    'VSS1106':
      PIN_NUMBER='(0,0,0,0,0,0,0,0,0,0,0,0,0,0,0,0,0,0,0,0,0,0,0,0,0,0,0,0,0,0,0~
,0,DM26,0,0,0,0,0,0,0,0,0)';
      PINUSE='POWER';
      NO_LOAD_CHECK='Both';
      NO_IO_CHECK='Both';
      NO_ASSERT_CHECK='TRUE';
      NO_DIR_CHECK='TRUE';
      ALLOW_CONNECT='TRUE';
    'VSS1105':
      PIN_NUMBER='(0,0,0,0,0,0,0,0,0,0,0,0,0,0,0,0,0,0,0,0,0,0,0,0,0,0,0,0,0,0,0~
,0,DM24,0,0,0,0,0,0,0,0,0)';
      PINUSE='POWER';
      NO_LOAD_CHECK='Both';
      NO_IO_CHECK='Both';
      NO_ASSERT_CHECK='TRUE';
      NO_DIR_CHECK='TRUE';
      ALLOW_CONNECT='TRUE';
    'VSS1104':
      PIN_NUMBER='(0,0,0,0,0,0,0,0,0,0,0,0,0,0,0,0,0,0,0,0,0,0,0,0,0,0,0,0,0,0,0~
,0,DM22,0,0,0,0,0,0,0,0,0)';
      PINUSE='POWER';
      NO_LOAD_CHECK='Both';
      NO_IO_CHECK='Both';
      NO_ASSERT_CHECK='TRUE';
      NO_DIR_CHECK='TRUE';
      ALLOW_CONNECT='TRUE';
    'VSS1103':
      PIN_NUMBER='(0,0,0,0,0,0,0,0,0,0,0,0,0,0,0,0,0,0,0,0,0,0,0,0,0,0,0,0,0,0,0~
,0,DM20,0,0,0,0,0,0,0,0,0)';
      PINUSE='POWER';
      NO_LOAD_CHECK='Both';
      NO_IO_CHECK='Both';
      NO_ASSERT_CHECK='TRUE';
      NO_DIR_CHECK='TRUE';
      ALLOW_CONNECT='TRUE';
    'VSS1102':
      PIN_NUMBER='(0,0,0,0,0,0,0,0,0,0,0,0,0,0,0,0,0,0,0,0,0,0,0,0,0,0,0,0,0,0,0~
,0,DM18,0,0,0,0,0,0,0,0,0)';
      PINUSE='POWER';
      NO_LOAD_CHECK='Both';
      NO_IO_CHECK='Both';
      NO_ASSERT_CHECK='TRUE';
      NO_DIR_CHECK='TRUE';
      ALLOW_CONNECT='TRUE';
    'VSS1101':
      PIN_NUMBER='(0,0,0,0,0,0,0,0,0,0,0,0,0,0,0,0,0,0,0,0,0,0,0,0,0,0,0,0,0,0,0~
,0,DM16,0,0,0,0,0,0,0,0,0)';
      PINUSE='POWER';
      NO_LOAD_CHECK='Both';
      NO_IO_CHECK='Both';
      NO_ASSERT_CHECK='TRUE';
      NO_DIR_CHECK='TRUE';
      ALLOW_CONNECT='TRUE';
    'VSS1100':
      PIN_NUMBER='(0,0,0,0,0,0,0,0,0,0,0,0,0,0,0,0,0,0,0,0,0,0,0,0,0,0,0,0,0,0,0~
,0,DM12,0,0,0,0,0,0,0,0,0)';
      PINUSE='POWER';
      NO_LOAD_CHECK='Both';
      NO_IO_CHECK='Both';
      NO_ASSERT_CHECK='TRUE';
      NO_DIR_CHECK='TRUE';
      ALLOW_CONNECT='TRUE';
    'VSS1097':
      PIN_NUMBER='(0,0,0,0,0,0,0,0,0,0,0,0,0,0,0,0,0,0,0,0,0,0,0,0,0,0,0,0,0,0,0~
,0,DW60,0,0,0,0,0,0,0,0,0)';
      PINUSE='POWER';
      NO_LOAD_CHECK='Both';
      NO_IO_CHECK='Both';
      NO_ASSERT_CHECK='TRUE';
      NO_DIR_CHECK='TRUE';
      ALLOW_CONNECT='TRUE';
    'VSS1077':
      PIN_NUMBER='(0,0,0,0,0,0,0,0,0,0,0,0,0,0,0,0,0,0,0,0,0,0,0,0,0,0,0,0,0,0,0~
,0,DW21,0,0,0,0,0,0,0,0,0)';
      PINUSE='POWER';
      NO_LOAD_CHECK='Both';
      NO_IO_CHECK='Both';
      NO_ASSERT_CHECK='TRUE';
      NO_DIR_CHECK='TRUE';
      ALLOW_CONNECT='TRUE';
    'VSS1064':
      PIN_NUMBER='(0,0,0,0,0,0,0,0,0,0,0,0,0,0,0,0,0,0,0,0,0,0,0,0,0,0,0,0,0,0,0~
,0,DV42,0,0,0,0,0,0,0,0,0)';
      PINUSE='POWER';
      NO_LOAD_CHECK='Both';
      NO_IO_CHECK='Both';
      NO_ASSERT_CHECK='TRUE';
      NO_DIR_CHECK='TRUE';
      ALLOW_CONNECT='TRUE';
    'VSS1063':
      PIN_NUMBER='(0,0,0,0,0,0,0,0,0,0,0,0,0,0,0,0,0,0,0,0,0,0,0,0,0,0,0,0,0,0,0~
,0,DV4,0,0,0,0,0,0,0,0,0)';
      PINUSE='POWER';
      NO_LOAD_CHECK='Both';
      NO_IO_CHECK='Both';
      NO_ASSERT_CHECK='TRUE';
      NO_DIR_CHECK='TRUE';
      ALLOW_CONNECT='TRUE';
    'VSS1060':
      PIN_NUMBER='(0,0,0,0,0,0,0,0,0,0,0,0,0,0,0,0,0,0,0,0,0,0,0,0,0,0,0,0,0,0,0~
,0,DV16,0,0,0,0,0,0,0,0,0)';
      PINUSE='POWER';
      NO_LOAD_CHECK='Both';
      NO_IO_CHECK='Both';
      NO_ASSERT_CHECK='TRUE';
      NO_DIR_CHECK='TRUE';
      ALLOW_CONNECT='TRUE';
    'VSS1059':
      PIN_NUMBER='(0,0,0,0,0,0,0,0,0,0,0,0,0,0,0,0,0,0,0,0,0,0,0,0,0,0,0,0,0,0,0~
,0,DV12,0,0,0,0,0,0,0,0,0)';
      PINUSE='POWER';
      NO_LOAD_CHECK='Both';
      NO_IO_CHECK='Both';
      NO_ASSERT_CHECK='TRUE';
      NO_DIR_CHECK='TRUE';
      ALLOW_CONNECT='TRUE';
    'VSS1054':
      PIN_NUMBER='(0,0,0,0,0,0,0,0,0,0,0,0,0,0,0,0,0,0,0,0,0,0,0,0,0,0,0,0,0,0,0~
,0,DU70,0,0,0,0,0,0,0,0,0)';
      PINUSE='POWER';
      NO_LOAD_CHECK='Both';
      NO_IO_CHECK='Both';
      NO_ASSERT_CHECK='TRUE';
      NO_DIR_CHECK='TRUE';
      ALLOW_CONNECT='TRUE';
    'VSS1052':
      PIN_NUMBER='(0,0,0,0,0,0,0,0,0,0,0,0,0,0,0,0,0,0,0,0,0,0,0,0,0,0,0,0,0,0,0~
,0,DU64,0,0,0,0,0,0,0,0,0)';
      PINUSE='POWER';
      NO_LOAD_CHECK='Both';
      NO_IO_CHECK='Both';
      NO_ASSERT_CHECK='TRUE';
      NO_DIR_CHECK='TRUE';
      ALLOW_CONNECT='TRUE';
    'VSS1051':
      PIN_NUMBER='(0,0,0,0,0,0,0,0,0,0,0,0,0,0,0,0,0,0,0,0,0,0,0,0,0,0,0,0,0,0,0~
,0,DU58,0,0,0,0,0,0,0,0,0)';
      PINUSE='POWER';
      NO_LOAD_CHECK='Both';
      NO_IO_CHECK='Both';
      NO_ASSERT_CHECK='TRUE';
      NO_DIR_CHECK='TRUE';
      ALLOW_CONNECT='TRUE';
    'VSS1050':
      PIN_NUMBER='(0,0,0,0,0,0,0,0,0,0,0,0,0,0,0,0,0,0,0,0,0,0,0,0,0,0,0,0,0,0,0~
,0,DU52,0,0,0,0,0,0,0,0,0)';
      PINUSE='POWER';
      NO_LOAD_CHECK='Both';
      NO_IO_CHECK='Both';
      NO_ASSERT_CHECK='TRUE';
      NO_DIR_CHECK='TRUE';
      ALLOW_CONNECT='TRUE';
    'VSS1048':
      PIN_NUMBER='(0,0,0,0,0,0,0,0,0,0,0,0,0,0,0,0,0,0,0,0,0,0,0,0,0,0,0,0,0,0,0~
,0,DU45,0,0,0,0,0,0,0,0,0)';
      PINUSE='POWER';
      NO_LOAD_CHECK='Both';
      NO_IO_CHECK='Both';
      NO_ASSERT_CHECK='TRUE';
      NO_DIR_CHECK='TRUE';
      ALLOW_CONNECT='TRUE';
    'VSS1047':
      PIN_NUMBER='(0,0,0,0,0,0,0,0,0,0,0,0,0,0,0,0,0,0,0,0,0,0,0,0,0,0,0,0,0,0,0~
,0,DU39,0,0,0,0,0,0,0,0,0)';
      PINUSE='POWER';
      NO_LOAD_CHECK='Both';
      NO_IO_CHECK='Both';
      NO_ASSERT_CHECK='TRUE';
      NO_DIR_CHECK='TRUE';
      ALLOW_CONNECT='TRUE';
    'VSS1036':
      PIN_NUMBER='(0,0,0,0,0,0,0,0,0,0,0,0,0,0,0,0,0,0,0,0,0,0,0,0,0,0,0,0,0,0,0~
,0,DT83,0,0,0,0,0,0,0,0,0)';
      PINUSE='POWER';
      NO_LOAD_CHECK='Both';
      NO_IO_CHECK='Both';
      NO_ASSERT_CHECK='TRUE';
      NO_DIR_CHECK='TRUE';
      ALLOW_CONNECT='TRUE';
    'VSS1029':
      PIN_NUMBER='(0,0,0,0,0,0,0,0,0,0,0,0,0,0,0,0,0,0,0,0,0,0,0,0,0,0,0,0,0,0,0~
,0,DT63,0,0,0,0,0,0,0,0,0)';
      PINUSE='POWER';
      NO_LOAD_CHECK='Both';
      NO_IO_CHECK='Both';
      NO_ASSERT_CHECK='TRUE';
      NO_DIR_CHECK='TRUE';
      ALLOW_CONNECT='TRUE';
    'VSS1028':
      PIN_NUMBER='(0,0,0,0,0,0,0,0,0,0,0,0,0,0,0,0,0,0,0,0,0,0,0,0,0,0,0,0,0,0,0~
,0,DT59,0,0,0,0,0,0,0,0,0)';
      PINUSE='POWER';
      NO_LOAD_CHECK='Both';
      NO_IO_CHECK='Both';
      NO_ASSERT_CHECK='TRUE';
      NO_DIR_CHECK='TRUE';
      ALLOW_CONNECT='TRUE';
    'VSS1026':
      PIN_NUMBER='(0,0,0,0,0,0,0,0,0,0,0,0,0,0,0,0,0,0,0,0,0,0,0,0,0,0,0,0,0,0,0~
,0,DT53,0,0,0,0,0,0,0,0,0)';
      PINUSE='POWER';
      NO_LOAD_CHECK='Both';
      NO_IO_CHECK='Both';
      NO_ASSERT_CHECK='TRUE';
      NO_DIR_CHECK='TRUE';
      ALLOW_CONNECT='TRUE';
    'VSS1025':
      PIN_NUMBER='(0,0,0,0,0,0,0,0,0,0,0,0,0,0,0,0,0,0,0,0,0,0,0,0,0,0,0,0,0,0,0~
,0,DT51,0,0,0,0,0,0,0,0,0)';
      PINUSE='POWER';
      NO_LOAD_CHECK='Both';
      NO_IO_CHECK='Both';
      NO_ASSERT_CHECK='TRUE';
      NO_DIR_CHECK='TRUE';
      ALLOW_CONNECT='TRUE';
    'VSS1023':
      PIN_NUMBER='(0,0,0,0,0,0,0,0,0,0,0,0,0,0,0,0,0,0,0,0,0,0,0,0,0,0,0,0,0,0,0~
,0,DT44,0,0,0,0,0,0,0,0,0)';
      PINUSE='POWER';
      NO_LOAD_CHECK='Both';
      NO_IO_CHECK='Both';
      NO_ASSERT_CHECK='TRUE';
      NO_DIR_CHECK='TRUE';
      ALLOW_CONNECT='TRUE';
    'VSS1021':
      PIN_NUMBER='(0,0,0,0,0,0,0,0,0,0,0,0,0,0,0,0,0,0,0,0,0,0,0,0,0,0,0,0,0,0,0~
,0,DT4,0,0,0,0,0,0,0,0,0)';
      PINUSE='POWER';
      NO_LOAD_CHECK='Both';
      NO_IO_CHECK='Both';
      NO_ASSERT_CHECK='TRUE';
      NO_DIR_CHECK='TRUE';
      ALLOW_CONNECT='TRUE';
    'VSS1016':
      PIN_NUMBER='(0,0,0,0,0,0,0,0,0,0,0,0,0,0,0,0,0,0,0,0,0,0,0,0,0,0,0,0,0,0,0~
,0,DT26,0,0,0,0,0,0,0,0,0)';
      PINUSE='POWER';
      NO_LOAD_CHECK='Both';
      NO_IO_CHECK='Both';
      NO_ASSERT_CHECK='TRUE';
      NO_DIR_CHECK='TRUE';
      ALLOW_CONNECT='TRUE';
    'VSS1014':
      PIN_NUMBER='(0,0,0,0,0,0,0,0,0,0,0,0,0,0,0,0,0,0,0,0,0,0,0,0,0,0,0,0,0,0,0~
,0,DT20,0,0,0,0,0,0,0,0,0)';
      PINUSE='POWER';
      NO_LOAD_CHECK='Both';
      NO_IO_CHECK='Both';
      NO_ASSERT_CHECK='TRUE';
      NO_DIR_CHECK='TRUE';
      ALLOW_CONNECT='TRUE';
    'VSS1013':
      PIN_NUMBER='(0,0,0,0,0,0,0,0,0,0,0,0,0,0,0,0,0,0,0,0,0,0,0,0,0,0,0,0,0,0,0~
,0,DT16,0,0,0,0,0,0,0,0,0)';
      PINUSE='POWER';
      NO_LOAD_CHECK='Both';
      NO_IO_CHECK='Both';
      NO_ASSERT_CHECK='TRUE';
      NO_DIR_CHECK='TRUE';
      ALLOW_CONNECT='TRUE';
    'VSS1006':
      PIN_NUMBER='(0,0,0,0,0,0,0,0,0,0,0,0,0,0,0,0,0,0,0,0,0,0,0,0,0,0,0,0,0,0,0~
,0,DR72,0,0,0,0,0,0,0,0,0)';
      PINUSE='POWER';
      NO_LOAD_CHECK='Both';
      NO_IO_CHECK='Both';
      NO_ASSERT_CHECK='TRUE';
      NO_DIR_CHECK='TRUE';
      ALLOW_CONNECT='TRUE';
    'VSS1005':
      PIN_NUMBER='(0,0,0,0,0,0,0,0,0,0,0,0,0,0,0,0,0,0,0,0,0,0,0,0,0,0,0,0,0,0,0~
,0,DR68,0,0,0,0,0,0,0,0,0)';
      PINUSE='POWER';
      NO_LOAD_CHECK='Both';
      NO_IO_CHECK='Both';
      NO_ASSERT_CHECK='TRUE';
      NO_DIR_CHECK='TRUE';
      ALLOW_CONNECT='TRUE';
    'VSS1003':
      PIN_NUMBER='(0,0,0,0,0,0,0,0,0,0,0,0,0,0,0,0,0,0,0,0,0,0,0,0,0,0,0,0,0,0,0~
,0,DR62,0,0,0,0,0,0,0,0,0)';
      PINUSE='POWER';
      NO_LOAD_CHECK='Both';
      NO_IO_CHECK='Both';
      NO_ASSERT_CHECK='TRUE';
      NO_DIR_CHECK='TRUE';
      ALLOW_CONNECT='TRUE';
    'VSS1002':
      PIN_NUMBER='(0,0,0,0,0,0,0,0,0,0,0,0,0,0,0,0,0,0,0,0,0,0,0,0,0,0,0,0,0,0,0~
,0,DR60,0,0,0,0,0,0,0,0,0)';
      PINUSE='POWER';
      NO_LOAD_CHECK='Both';
      NO_IO_CHECK='Both';
      NO_ASSERT_CHECK='TRUE';
      NO_DIR_CHECK='TRUE';
      ALLOW_CONNECT='TRUE';
    'VSS1000':
      PIN_NUMBER='(0,0,0,0,0,0,0,0,0,0,0,0,0,0,0,0,0,0,0,0,0,0,0,0,0,0,0,0,0,0,0~
,0,DR54,0,0,0,0,0,0,0,0,0)';
      PINUSE='POWER';
      NO_LOAD_CHECK='Both';
      NO_IO_CHECK='Both';
      NO_ASSERT_CHECK='TRUE';
      NO_DIR_CHECK='TRUE';
      ALLOW_CONNECT='TRUE';
    'VSS998':
      PIN_NUMBER='(0,0,0,0,0,0,0,0,0,0,0,0,0,0,0,0,0,0,0,0,0,0,0,0,0,0,0,0,0,0,0~
,0,DR5,0,0,0,0,0,0,0,0,0)';
      PINUSE='POWER';
      NO_LOAD_CHECK='Both';
      NO_IO_CHECK='Both';
      NO_ASSERT_CHECK='TRUE';
      NO_DIR_CHECK='TRUE';
      ALLOW_CONNECT='TRUE';
    'VSS993':
      PIN_NUMBER='(0,0,0,0,0,0,0,0,0,0,0,0,0,0,0,0,0,0,0,0,0,0,0,0,0,0,0,0,0,0,0~
,0,DR35,0,0,0,0,0,0,0,0,0)';
      PINUSE='POWER';
      NO_LOAD_CHECK='Both';
      NO_IO_CHECK='Both';
      NO_ASSERT_CHECK='TRUE';
      NO_DIR_CHECK='TRUE';
      ALLOW_CONNECT='TRUE';
    'VSS990':
      PIN_NUMBER='(0,0,0,0,0,0,0,0,0,0,0,0,0,0,0,0,0,0,0,0,0,0,0,0,0,0,0,0,0,0,0~
,0,DR25,0,0,0,0,0,0,0,0,0)';
      PINUSE='POWER';
      NO_LOAD_CHECK='Both';
      NO_IO_CHECK='Both';
      NO_ASSERT_CHECK='TRUE';
      NO_DIR_CHECK='TRUE';
      ALLOW_CONNECT='TRUE';
    'VSS985':
      PIN_NUMBER='(0,0,0,0,0,0,0,0,0,0,0,0,0,0,0,0,0,0,0,0,0,0,0,0,0,0,0,0,0,0,0~
,0,DP91,0,0,0,0,0,0,0,0,0)';
      PINUSE='POWER';
      NO_LOAD_CHECK='Both';
      NO_IO_CHECK='Both';
      NO_ASSERT_CHECK='TRUE';
      NO_DIR_CHECK='TRUE';
      ALLOW_CONNECT='TRUE';
    'VSS980':
      PIN_NUMBER='(0,0,0,0,0,0,0,0,0,0,0,0,0,0,0,0,0,0,0,0,0,0,0,0,0,0,0,0,0,0,0~
,0,DP67,0,0,0,0,0,0,0,0,0)';
      PINUSE='POWER';
      NO_LOAD_CHECK='Both';
      NO_IO_CHECK='Both';
      NO_ASSERT_CHECK='TRUE';
      NO_DIR_CHECK='TRUE';
      ALLOW_CONNECT='TRUE';
    'VSS979':
      PIN_NUMBER='(0,0,0,0,0,0,0,0,0,0,0,0,0,0,0,0,0,0,0,0,0,0,0,0,0,0,0,0,0,0,0~
,0,DP61,0,0,0,0,0,0,0,0,0)';
      PINUSE='POWER';
      NO_LOAD_CHECK='Both';
      NO_IO_CHECK='Both';
      NO_ASSERT_CHECK='TRUE';
      NO_DIR_CHECK='TRUE';
      ALLOW_CONNECT='TRUE';
    'VSS976':
      PIN_NUMBER='(0,0,0,0,0,0,0,0,0,0,0,0,0,0,0,0,0,0,0,0,0,0,0,0,0,0,0,0,0,0,0~
,0,DP55,0,0,0,0,0,0,0,0,0)';
      PINUSE='POWER';
      NO_LOAD_CHECK='Both';
      NO_IO_CHECK='Both';
      NO_ASSERT_CHECK='TRUE';
      NO_DIR_CHECK='TRUE';
      ALLOW_CONNECT='TRUE';
    'VSS973':
      PIN_NUMBER='(0,0,0,0,0,0,0,0,0,0,0,0,0,0,0,0,0,0,0,0,0,0,0,0,0,0,0,0,0,0,0~
,0,DP42,0,0,0,0,0,0,0,0,0)';
      PINUSE='POWER';
      NO_LOAD_CHECK='Both';
      NO_IO_CHECK='Both';
      NO_ASSERT_CHECK='TRUE';
      NO_DIR_CHECK='TRUE';
      ALLOW_CONNECT='TRUE';
    'VSS969':
      PIN_NUMBER='(0,0,0,0,0,0,0,0,0,0,0,0,0,0,0,0,0,0,0,0,0,0,0,0,0,0,0,0,0,0,0~
,0,DP24,0,0,0,0,0,0,0,0,0)';
      PINUSE='POWER';
      NO_LOAD_CHECK='Both';
      NO_IO_CHECK='Both';
      NO_ASSERT_CHECK='TRUE';
      NO_DIR_CHECK='TRUE';
      ALLOW_CONNECT='TRUE';
    'VSS968':
      PIN_NUMBER='(0,0,0,0,0,0,0,0,0,0,0,0,0,0,0,0,0,0,0,0,0,0,0,0,0,0,0,0,0,0,0~
,0,DP18,0,0,0,0,0,0,0,0,0)';
      PINUSE='POWER';
      NO_LOAD_CHECK='Both';
      NO_IO_CHECK='Both';
      NO_ASSERT_CHECK='TRUE';
      NO_DIR_CHECK='TRUE';
      ALLOW_CONNECT='TRUE';
    'VSS966':
      PIN_NUMBER='(0,0,0,0,0,0,0,0,0,0,0,0,0,0,0,0,0,0,0,0,0,0,0,0,0,0,0,0,0,0,0~
,0,DP12,0,0,0,0,0,0,0,0,0)';
      PINUSE='POWER';
      NO_LOAD_CHECK='Both';
      NO_IO_CHECK='Both';
      NO_ASSERT_CHECK='TRUE';
      NO_DIR_CHECK='TRUE';
      ALLOW_CONNECT='TRUE';
    'VSS959':
      PIN_NUMBER='(0,0,0,0,0,0,0,0,0,0,0,0,0,0,0,0,0,0,0,0,0,0,0,0,0,0,0,0,0,0,0~
,0,DN52,0,0,0,0,0,0,0,0,0)';
      PINUSE='POWER';
      NO_LOAD_CHECK='Both';
      NO_IO_CHECK='Both';
      NO_ASSERT_CHECK='TRUE';
      NO_DIR_CHECK='TRUE';
      ALLOW_CONNECT='TRUE';
    'VSS957':
      PIN_NUMBER='(0,0,0,0,0,0,0,0,0,0,0,0,0,0,0,0,0,0,0,0,0,0,0,0,0,0,0,0,0,0,0~
,0,DN39,0,0,0,0,0,0,0,0,0)';
      PINUSE='POWER';
      NO_LOAD_CHECK='Both';
      NO_IO_CHECK='Both';
      NO_ASSERT_CHECK='TRUE';
      NO_DIR_CHECK='TRUE';
      ALLOW_CONNECT='TRUE';
    'VSS955':
      PIN_NUMBER='(0,0,0,0,0,0,0,0,0,0,0,0,0,0,0,0,0,0,0,0,0,0,0,0,0,0,0,0,0,0,0~
,0,DN17,0,0,0,0,0,0,0,0,0)';
      PINUSE='POWER';
      NO_LOAD_CHECK='Both';
      NO_IO_CHECK='Both';
      NO_ASSERT_CHECK='TRUE';
      NO_DIR_CHECK='TRUE';
      ALLOW_CONNECT='TRUE';
    'VSS945':
      PIN_NUMBER='(0,0,0,0,0,0,0,0,0,0,0,0,0,0,0,0,0,0,0,0,0,0,0,0,0,0,0,0,0,0,0~
,0,DM73,0,0,0,0,0,0,0,0,0)';
      PINUSE='POWER';
      NO_LOAD_CHECK='Both';
      NO_IO_CHECK='Both';
      NO_ASSERT_CHECK='TRUE';
      NO_DIR_CHECK='TRUE';
      ALLOW_CONNECT='TRUE';
    'VSS934':
      PIN_NUMBER='(0,0,0,0,0,0,0,0,0,0,0,0,0,0,0,0,0,0,0,0,0,0,0,0,0,0,0,0,0,0,0~
,0,DM51,0,0,0,0,0,0,0,0,0)';
      PINUSE='POWER';
      NO_LOAD_CHECK='Both';
      NO_IO_CHECK='Both';
      NO_ASSERT_CHECK='TRUE';
      NO_DIR_CHECK='TRUE';
      ALLOW_CONNECT='TRUE';
    'VSS1099':
      PIN_NUMBER='(0,0,0,0,0,0,0,0,0,0,0,0,0,0,0,0,0,0,0,0,0,0,0,0,0,0,0,0,0,0,0~
,0,0,DL9,0,0,0,0,0,0,0,0)';
      PINUSE='POWER';
      NO_LOAD_CHECK='Both';
      NO_IO_CHECK='Both';
      NO_ASSERT_CHECK='TRUE';
      NO_DIR_CHECK='TRUE';
      ALLOW_CONNECT='TRUE';
    'VSS1098':
      PIN_NUMBER='(0,0,0,0,0,0,0,0,0,0,0,0,0,0,0,0,0,0,0,0,0,0,0,0,0,0,0,0,0,0,0~
,0,0,DL88,0,0,0,0,0,0,0,0)';
      PINUSE='POWER';
      NO_LOAD_CHECK='Both';
      NO_IO_CHECK='Both';
      NO_ASSERT_CHECK='TRUE';
      NO_DIR_CHECK='TRUE';
      ALLOW_CONNECT='TRUE';
    'VSS1096':
      PIN_NUMBER='(0,0,0,0,0,0,0,0,0,0,0,0,0,0,0,0,0,0,0,0,0,0,0,0,0,0,0,0,0,0,0~
,0,0,DL84,0,0,0,0,0,0,0,0)';
      PINUSE='POWER';
      NO_LOAD_CHECK='Both';
      NO_IO_CHECK='Both';
      NO_ASSERT_CHECK='TRUE';
      NO_DIR_CHECK='TRUE';
      ALLOW_CONNECT='TRUE';
    'VSS1095':
      PIN_NUMBER='(0,0,0,0,0,0,0,0,0,0,0,0,0,0,0,0,0,0,0,0,0,0,0,0,0,0,0,0,0,0,0~
,0,0,DL39,0,0,0,0,0,0,0,0)';
      PINUSE='POWER';
      NO_LOAD_CHECK='Both';
      NO_IO_CHECK='Both';
      NO_ASSERT_CHECK='TRUE';
      NO_DIR_CHECK='TRUE';
      ALLOW_CONNECT='TRUE';
    'VSS1094':
      PIN_NUMBER='(0,0,0,0,0,0,0,0,0,0,0,0,0,0,0,0,0,0,0,0,0,0,0,0,0,0,0,0,0,0,0~
,0,0,DK91,0,0,0,0,0,0,0,0)';
      PINUSE='POWER';
      NO_LOAD_CHECK='Both';
      NO_IO_CHECK='Both';
      NO_ASSERT_CHECK='TRUE';
      NO_DIR_CHECK='TRUE';
      ALLOW_CONNECT='TRUE';
    'VSS1093':
      PIN_NUMBER='(0,0,0,0,0,0,0,0,0,0,0,0,0,0,0,0,0,0,0,0,0,0,0,0,0,0,0,0,0,0,0~
,0,0,DK87,0,0,0,0,0,0,0,0)';
      PINUSE='POWER';
      NO_LOAD_CHECK='Both';
      NO_IO_CHECK='Both';
      NO_ASSERT_CHECK='TRUE';
      NO_DIR_CHECK='TRUE';
      ALLOW_CONNECT='TRUE';
    'VSS1092':
      PIN_NUMBER='(0,0,0,0,0,0,0,0,0,0,0,0,0,0,0,0,0,0,0,0,0,0,0,0,0,0,0,0,0,0,0~
,0,0,DK83,0,0,0,0,0,0,0,0)';
      PINUSE='POWER';
      NO_LOAD_CHECK='Both';
      NO_IO_CHECK='Both';
      NO_ASSERT_CHECK='TRUE';
      NO_DIR_CHECK='TRUE';
      ALLOW_CONNECT='TRUE';
    'VSS1091':
      PIN_NUMBER='(0,0,0,0,0,0,0,0,0,0,0,0,0,0,0,0,0,0,0,0,0,0,0,0,0,0,0,0,0,0,0~
,0,0,DK81,0,0,0,0,0,0,0,0)';
      PINUSE='POWER';
      NO_LOAD_CHECK='Both';
      NO_IO_CHECK='Both';
      NO_ASSERT_CHECK='TRUE';
      NO_DIR_CHECK='TRUE';
      ALLOW_CONNECT='TRUE';
    'VSS1090':
      PIN_NUMBER='(0,0,0,0,0,0,0,0,0,0,0,0,0,0,0,0,0,0,0,0,0,0,0,0,0,0,0,0,0,0,0~
,0,0,DK8,0,0,0,0,0,0,0,0)';
      PINUSE='POWER';
      NO_LOAD_CHECK='Both';
      NO_IO_CHECK='Both';
      NO_ASSERT_CHECK='TRUE';
      NO_DIR_CHECK='TRUE';
      ALLOW_CONNECT='TRUE';
    'VSS1089':
      PIN_NUMBER='(0,0,0,0,0,0,0,0,0,0,0,0,0,0,0,0,0,0,0,0,0,0,0,0,0,0,0,0,0,0,0~
,0,0,DK79,0,0,0,0,0,0,0,0)';
      PINUSE='POWER';
      NO_LOAD_CHECK='Both';
      NO_IO_CHECK='Both';
      NO_ASSERT_CHECK='TRUE';
      NO_DIR_CHECK='TRUE';
      ALLOW_CONNECT='TRUE';
    'VSS1088':
      PIN_NUMBER='(0,0,0,0,0,0,0,0,0,0,0,0,0,0,0,0,0,0,0,0,0,0,0,0,0,0,0,0,0,0,0~
,0,0,DK77,0,0,0,0,0,0,0,0)';
      PINUSE='POWER';
      NO_LOAD_CHECK='Both';
      NO_IO_CHECK='Both';
      NO_ASSERT_CHECK='TRUE';
      NO_DIR_CHECK='TRUE';
      ALLOW_CONNECT='TRUE';
    'VSS1087':
      PIN_NUMBER='(0,0,0,0,0,0,0,0,0,0,0,0,0,0,0,0,0,0,0,0,0,0,0,0,0,0,0,0,0,0,0~
,0,0,DK73,0,0,0,0,0,0,0,0)';
      PINUSE='POWER';
      NO_LOAD_CHECK='Both';
      NO_IO_CHECK='Both';
      NO_ASSERT_CHECK='TRUE';
      NO_DIR_CHECK='TRUE';
      ALLOW_CONNECT='TRUE';
    'VSS1086':
      PIN_NUMBER='(0,0,0,0,0,0,0,0,0,0,0,0,0,0,0,0,0,0,0,0,0,0,0,0,0,0,0,0,0,0,0~
,0,0,DK49,0,0,0,0,0,0,0,0)';
      PINUSE='POWER';
      NO_LOAD_CHECK='Both';
      NO_IO_CHECK='Both';
      NO_ASSERT_CHECK='TRUE';
      NO_DIR_CHECK='TRUE';
      ALLOW_CONNECT='TRUE';
    'VSS1085':
      PIN_NUMBER='(0,0,0,0,0,0,0,0,0,0,0,0,0,0,0,0,0,0,0,0,0,0,0,0,0,0,0,0,0,0,0~
,0,0,DK4,0,0,0,0,0,0,0,0)';
      PINUSE='POWER';
      NO_LOAD_CHECK='Both';
      NO_IO_CHECK='Both';
      NO_ASSERT_CHECK='TRUE';
      NO_DIR_CHECK='TRUE';
      ALLOW_CONNECT='TRUE';
    'VSS1084':
      PIN_NUMBER='(0,0,0,0,0,0,0,0,0,0,0,0,0,0,0,0,0,0,0,0,0,0,0,0,0,0,0,0,0,0,0~
,0,0,DK36,0,0,0,0,0,0,0,0)';
      PINUSE='POWER';
      NO_LOAD_CHECK='Both';
      NO_IO_CHECK='Both';
      NO_ASSERT_CHECK='TRUE';
      NO_DIR_CHECK='TRUE';
      ALLOW_CONNECT='TRUE';
    'VSS1083':
      PIN_NUMBER='(0,0,0,0,0,0,0,0,0,0,0,0,0,0,0,0,0,0,0,0,0,0,0,0,0,0,0,0,0,0,0~
,0,0,DK30,0,0,0,0,0,0,0,0)';
      PINUSE='POWER';
      NO_LOAD_CHECK='Both';
      NO_IO_CHECK='Both';
      NO_ASSERT_CHECK='TRUE';
      NO_DIR_CHECK='TRUE';
      ALLOW_CONNECT='TRUE';
    'VSS1082':
      PIN_NUMBER='(0,0,0,0,0,0,0,0,0,0,0,0,0,0,0,0,0,0,0,0,0,0,0,0,0,0,0,0,0,0,0~
,0,0,DK16,0,0,0,0,0,0,0,0)';
      PINUSE='POWER';
      NO_LOAD_CHECK='Both';
      NO_IO_CHECK='Both';
      NO_ASSERT_CHECK='TRUE';
      NO_DIR_CHECK='TRUE';
      ALLOW_CONNECT='TRUE';
    'VSS1081':
      PIN_NUMBER='(0,0,0,0,0,0,0,0,0,0,0,0,0,0,0,0,0,0,0,0,0,0,0,0,0,0,0,0,0,0,0~
,0,0,DJ88,0,0,0,0,0,0,0,0)';
      PINUSE='POWER';
      NO_LOAD_CHECK='Both';
      NO_IO_CHECK='Both';
      NO_ASSERT_CHECK='TRUE';
      NO_DIR_CHECK='TRUE';
      ALLOW_CONNECT='TRUE';
    'VSS1080':
      PIN_NUMBER='(0,0,0,0,0,0,0,0,0,0,0,0,0,0,0,0,0,0,0,0,0,0,0,0,0,0,0,0,0,0,0~
,0,0,DJ84,0,0,0,0,0,0,0,0)';
      PINUSE='POWER';
      NO_LOAD_CHECK='Both';
      NO_IO_CHECK='Both';
      NO_ASSERT_CHECK='TRUE';
      NO_DIR_CHECK='TRUE';
      ALLOW_CONNECT='TRUE';
    'VSS1079':
      PIN_NUMBER='(0,0,0,0,0,0,0,0,0,0,0,0,0,0,0,0,0,0,0,0,0,0,0,0,0,0,0,0,0,0,0~
,0,0,DJ82,0,0,0,0,0,0,0,0)';
      PINUSE='POWER';
      NO_LOAD_CHECK='Both';
      NO_IO_CHECK='Both';
      NO_ASSERT_CHECK='TRUE';
      NO_DIR_CHECK='TRUE';
      ALLOW_CONNECT='TRUE';
    'VSS1078':
      PIN_NUMBER='(0,0,0,0,0,0,0,0,0,0,0,0,0,0,0,0,0,0,0,0,0,0,0,0,0,0,0,0,0,0,0~
,0,0,DJ80,0,0,0,0,0,0,0,0)';
      PINUSE='POWER';
      NO_LOAD_CHECK='Both';
      NO_IO_CHECK='Both';
      NO_ASSERT_CHECK='TRUE';
      NO_DIR_CHECK='TRUE';
      ALLOW_CONNECT='TRUE';
    'VSS1076':
      PIN_NUMBER='(0,0,0,0,0,0,0,0,0,0,0,0,0,0,0,0,0,0,0,0,0,0,0,0,0,0,0,0,0,0,0~
,0,0,DJ74,0,0,0,0,0,0,0,0)';
      PINUSE='POWER';
      NO_LOAD_CHECK='Both';
      NO_IO_CHECK='Both';
      NO_ASSERT_CHECK='TRUE';
      NO_DIR_CHECK='TRUE';
      ALLOW_CONNECT='TRUE';
    'VSS1075':
      PIN_NUMBER='(0,0,0,0,0,0,0,0,0,0,0,0,0,0,0,0,0,0,0,0,0,0,0,0,0,0,0,0,0,0,0~
,0,0,DJ72,0,0,0,0,0,0,0,0)';
      PINUSE='POWER';
      NO_LOAD_CHECK='Both';
      NO_IO_CHECK='Both';
      NO_ASSERT_CHECK='TRUE';
      NO_DIR_CHECK='TRUE';
      ALLOW_CONNECT='TRUE';
    'VSS1074':
      PIN_NUMBER='(0,0,0,0,0,0,0,0,0,0,0,0,0,0,0,0,0,0,0,0,0,0,0,0,0,0,0,0,0,0,0~
,0,0,DJ66,0,0,0,0,0,0,0,0)';
      PINUSE='POWER';
      NO_LOAD_CHECK='Both';
      NO_IO_CHECK='Both';
      NO_ASSERT_CHECK='TRUE';
      NO_DIR_CHECK='TRUE';
      ALLOW_CONNECT='TRUE';
    'VSS1073':
      PIN_NUMBER='(0,0,0,0,0,0,0,0,0,0,0,0,0,0,0,0,0,0,0,0,0,0,0,0,0,0,0,0,0,0,0~
,0,0,DJ60,0,0,0,0,0,0,0,0)';
      PINUSE='POWER';
      NO_LOAD_CHECK='Both';
      NO_IO_CHECK='Both';
      NO_ASSERT_CHECK='TRUE';
      NO_DIR_CHECK='TRUE';
      ALLOW_CONNECT='TRUE';
    'VSS1072':
      PIN_NUMBER='(0,0,0,0,0,0,0,0,0,0,0,0,0,0,0,0,0,0,0,0,0,0,0,0,0,0,0,0,0,0,0~
,0,0,DJ56,0,0,0,0,0,0,0,0)';
      PINUSE='POWER';
      NO_LOAD_CHECK='Both';
      NO_IO_CHECK='Both';
      NO_ASSERT_CHECK='TRUE';
      NO_DIR_CHECK='TRUE';
      ALLOW_CONNECT='TRUE';
    'VSS1071':
      PIN_NUMBER='(0,0,0,0,0,0,0,0,0,0,0,0,0,0,0,0,0,0,0,0,0,0,0,0,0,0,0,0,0,0,0~
,0,0,DJ50,0,0,0,0,0,0,0,0)';
      PINUSE='POWER';
      NO_LOAD_CHECK='Both';
      NO_IO_CHECK='Both';
      NO_ASSERT_CHECK='TRUE';
      NO_DIR_CHECK='TRUE';
      ALLOW_CONNECT='TRUE';
    'VSS1070':
      PIN_NUMBER='(0,0,0,0,0,0,0,0,0,0,0,0,0,0,0,0,0,0,0,0,0,0,0,0,0,0,0,0,0,0,0~
,0,0,DJ48,0,0,0,0,0,0,0,0)';
      PINUSE='POWER';
      NO_LOAD_CHECK='Both';
      NO_IO_CHECK='Both';
      NO_ASSERT_CHECK='TRUE';
      NO_DIR_CHECK='TRUE';
      ALLOW_CONNECT='TRUE';
    'VSS1069':
      PIN_NUMBER='(0,0,0,0,0,0,0,0,0,0,0,0,0,0,0,0,0,0,0,0,0,0,0,0,0,0,0,0,0,0,0~
,0,0,DJ43,0,0,0,0,0,0,0,0)';
      PINUSE='POWER';
      NO_LOAD_CHECK='Both';
      NO_IO_CHECK='Both';
      NO_ASSERT_CHECK='TRUE';
      NO_DIR_CHECK='TRUE';
      ALLOW_CONNECT='TRUE';
    'VSS1068':
      PIN_NUMBER='(0,0,0,0,0,0,0,0,0,0,0,0,0,0,0,0,0,0,0,0,0,0,0,0,0,0,0,0,0,0,0~
,0,0,DJ41,0,0,0,0,0,0,0,0)';
      PINUSE='POWER';
      NO_LOAD_CHECK='Both';
      NO_IO_CHECK='Both';
      NO_ASSERT_CHECK='TRUE';
      NO_DIR_CHECK='TRUE';
      ALLOW_CONNECT='TRUE';
    'VSS1067':
      PIN_NUMBER='(0,0,0,0,0,0,0,0,0,0,0,0,0,0,0,0,0,0,0,0,0,0,0,0,0,0,0,0,0,0,0~
,0,0,DJ37,0,0,0,0,0,0,0,0)';
      PINUSE='POWER';
      NO_LOAD_CHECK='Both';
      NO_IO_CHECK='Both';
      NO_ASSERT_CHECK='TRUE';
      NO_DIR_CHECK='TRUE';
      ALLOW_CONNECT='TRUE';
    'VSS1066':
      PIN_NUMBER='(0,0,0,0,0,0,0,0,0,0,0,0,0,0,0,0,0,0,0,0,0,0,0,0,0,0,0,0,0,0,0~
,0,0,DJ31,0,0,0,0,0,0,0,0)';
      PINUSE='POWER';
      NO_LOAD_CHECK='Both';
      NO_IO_CHECK='Both';
      NO_ASSERT_CHECK='TRUE';
      NO_DIR_CHECK='TRUE';
      ALLOW_CONNECT='TRUE';
    'VSS1065':
      PIN_NUMBER='(0,0,0,0,0,0,0,0,0,0,0,0,0,0,0,0,0,0,0,0,0,0,0,0,0,0,0,0,0,0,0~
,0,0,DJ29,0,0,0,0,0,0,0,0)';
      PINUSE='POWER';
      NO_LOAD_CHECK='Both';
      NO_IO_CHECK='Both';
      NO_ASSERT_CHECK='TRUE';
      NO_DIR_CHECK='TRUE';
      ALLOW_CONNECT='TRUE';
    'VSS1062':
      PIN_NUMBER='(0,0,0,0,0,0,0,0,0,0,0,0,0,0,0,0,0,0,0,0,0,0,0,0,0,0,0,0,0,0,0~
,0,0,DJ23,0,0,0,0,0,0,0,0)';
      PINUSE='POWER';
      NO_LOAD_CHECK='Both';
      NO_IO_CHECK='Both';
      NO_ASSERT_CHECK='TRUE';
      NO_DIR_CHECK='TRUE';
      ALLOW_CONNECT='TRUE';
    'VSS1061':
      PIN_NUMBER='(0,0,0,0,0,0,0,0,0,0,0,0,0,0,0,0,0,0,0,0,0,0,0,0,0,0,0,0,0,0,0~
,0,0,DJ19,0,0,0,0,0,0,0,0)';
      PINUSE='POWER';
      NO_LOAD_CHECK='Both';
      NO_IO_CHECK='Both';
      NO_ASSERT_CHECK='TRUE';
      NO_DIR_CHECK='TRUE';
      ALLOW_CONNECT='TRUE';
    'VSS1058':
      PIN_NUMBER='(0,0,0,0,0,0,0,0,0,0,0,0,0,0,0,0,0,0,0,0,0,0,0,0,0,0,0,0,0,0,0~
,0,0,DH85,0,0,0,0,0,0,0,0)';
      PINUSE='POWER';
      NO_LOAD_CHECK='Both';
      NO_IO_CHECK='Both';
      NO_ASSERT_CHECK='TRUE';
      NO_DIR_CHECK='TRUE';
      ALLOW_CONNECT='TRUE';
    'VSS1057':
      PIN_NUMBER='(0,0,0,0,0,0,0,0,0,0,0,0,0,0,0,0,0,0,0,0,0,0,0,0,0,0,0,0,0,0,0~
,0,0,DH8,0,0,0,0,0,0,0,0)';
      PINUSE='POWER';
      NO_LOAD_CHECK='Both';
      NO_IO_CHECK='Both';
      NO_ASSERT_CHECK='TRUE';
      NO_DIR_CHECK='TRUE';
      ALLOW_CONNECT='TRUE';
    'VSS1056':
      PIN_NUMBER='(0,0,0,0,0,0,0,0,0,0,0,0,0,0,0,0,0,0,0,0,0,0,0,0,0,0,0,0,0,0,0~
,0,0,DH77,0,0,0,0,0,0,0,0)';
      PINUSE='POWER';
      NO_LOAD_CHECK='Both';
      NO_IO_CHECK='Both';
      NO_ASSERT_CHECK='TRUE';
      NO_DIR_CHECK='TRUE';
      ALLOW_CONNECT='TRUE';
    'VSS1055':
      PIN_NUMBER='(0,0,0,0,0,0,0,0,0,0,0,0,0,0,0,0,0,0,0,0,0,0,0,0,0,0,0,0,0,0,0~
,0,0,DH71,0,0,0,0,0,0,0,0)';
      PINUSE='POWER';
      NO_LOAD_CHECK='Both';
      NO_IO_CHECK='Both';
      NO_ASSERT_CHECK='TRUE';
      NO_DIR_CHECK='TRUE';
      ALLOW_CONNECT='TRUE';
    'VSS1053':
      PIN_NUMBER='(0,0,0,0,0,0,0,0,0,0,0,0,0,0,0,0,0,0,0,0,0,0,0,0,0,0,0,0,0,0,0~
,0,0,DH65,0,0,0,0,0,0,0,0)';
      PINUSE='POWER';
      NO_LOAD_CHECK='Both';
      NO_IO_CHECK='Both';
      NO_ASSERT_CHECK='TRUE';
      NO_DIR_CHECK='TRUE';
      ALLOW_CONNECT='TRUE';
    'VSS1049':
      PIN_NUMBER='(0,0,0,0,0,0,0,0,0,0,0,0,0,0,0,0,0,0,0,0,0,0,0,0,0,0,0,0,0,0,0~
,0,0,DH57,0,0,0,0,0,0,0,0)';
      PINUSE='POWER';
      NO_LOAD_CHECK='Both';
      NO_IO_CHECK='Both';
      NO_ASSERT_CHECK='TRUE';
      NO_DIR_CHECK='TRUE';
      ALLOW_CONNECT='TRUE';
    'VSS1046':
      PIN_NUMBER='(0,0,0,0,0,0,0,0,0,0,0,0,0,0,0,0,0,0,0,0,0,0,0,0,0,0,0,0,0,0,0~
,0,0,DH47,0,0,0,0,0,0,0,0)';
      PINUSE='POWER';
      NO_LOAD_CHECK='Both';
      NO_IO_CHECK='Both';
      NO_ASSERT_CHECK='TRUE';
      NO_DIR_CHECK='TRUE';
      ALLOW_CONNECT='TRUE';
    'VSS1045':
      PIN_NUMBER='(0,0,0,0,0,0,0,0,0,0,0,0,0,0,0,0,0,0,0,0,0,0,0,0,0,0,0,0,0,0,0~
,0,0,DH40,0,0,0,0,0,0,0,0)';
      PINUSE='POWER';
      NO_LOAD_CHECK='Both';
      NO_IO_CHECK='Both';
      NO_ASSERT_CHECK='TRUE';
      NO_DIR_CHECK='TRUE';
      ALLOW_CONNECT='TRUE';
    'VSS1044':
      PIN_NUMBER='(0,0,0,0,0,0,0,0,0,0,0,0,0,0,0,0,0,0,0,0,0,0,0,0,0,0,0,0,0,0,0~
,0,0,DH4,0,0,0,0,0,0,0,0)';
      PINUSE='POWER';
      NO_LOAD_CHECK='Both';
      NO_IO_CHECK='Both';
      NO_ASSERT_CHECK='TRUE';
      NO_DIR_CHECK='TRUE';
      ALLOW_CONNECT='TRUE';
    'VSS1043':
      PIN_NUMBER='(0,0,0,0,0,0,0,0,0,0,0,0,0,0,0,0,0,0,0,0,0,0,0,0,0,0,0,0,0,0,0~
,0,0,DH38,0,0,0,0,0,0,0,0)';
      PINUSE='POWER';
      NO_LOAD_CHECK='Both';
      NO_IO_CHECK='Both';
      NO_ASSERT_CHECK='TRUE';
      NO_DIR_CHECK='TRUE';
      ALLOW_CONNECT='TRUE';
    'VSS1042':
      PIN_NUMBER='(0,0,0,0,0,0,0,0,0,0,0,0,0,0,0,0,0,0,0,0,0,0,0,0,0,0,0,0,0,0,0~
,0,0,DH32,0,0,0,0,0,0,0,0)';
      PINUSE='POWER';
      NO_LOAD_CHECK='Both';
      NO_IO_CHECK='Both';
      NO_ASSERT_CHECK='TRUE';
      NO_DIR_CHECK='TRUE';
      ALLOW_CONNECT='TRUE';
    'VSS1041':
      PIN_NUMBER='(0,0,0,0,0,0,0,0,0,0,0,0,0,0,0,0,0,0,0,0,0,0,0,0,0,0,0,0,0,0,0~
,0,0,DH28,0,0,0,0,0,0,0,0)';
      PINUSE='POWER';
      NO_LOAD_CHECK='Both';
      NO_IO_CHECK='Both';
      NO_ASSERT_CHECK='TRUE';
      NO_DIR_CHECK='TRUE';
      ALLOW_CONNECT='TRUE';
    'VSS1040':
      PIN_NUMBER='(0,0,0,0,0,0,0,0,0,0,0,0,0,0,0,0,0,0,0,0,0,0,0,0,0,0,0,0,0,0,0~
,0,0,DH22,0,0,0,0,0,0,0,0)';
      PINUSE='POWER';
      NO_LOAD_CHECK='Both';
      NO_IO_CHECK='Both';
      NO_ASSERT_CHECK='TRUE';
      NO_DIR_CHECK='TRUE';
      ALLOW_CONNECT='TRUE';
    'VSS1039':
      PIN_NUMBER='(0,0,0,0,0,0,0,0,0,0,0,0,0,0,0,0,0,0,0,0,0,0,0,0,0,0,0,0,0,0,0~
,0,0,DH12,0,0,0,0,0,0,0,0)';
      PINUSE='POWER';
      NO_LOAD_CHECK='Both';
      NO_IO_CHECK='Both';
      NO_ASSERT_CHECK='TRUE';
      NO_DIR_CHECK='TRUE';
      ALLOW_CONNECT='TRUE';
    'VSS1038':
      PIN_NUMBER='(0,0,0,0,0,0,0,0,0,0,0,0,0,0,0,0,0,0,0,0,0,0,0,0,0,0,0,0,0,0,0~
,0,0,DG9,0,0,0,0,0,0,0,0)';
      PINUSE='POWER';
      NO_LOAD_CHECK='Both';
      NO_IO_CHECK='Both';
      NO_ASSERT_CHECK='TRUE';
      NO_DIR_CHECK='TRUE';
      ALLOW_CONNECT='TRUE';
    'VSS1037':
      PIN_NUMBER='(0,0,0,0,0,0,0,0,0,0,0,0,0,0,0,0,0,0,0,0,0,0,0,0,0,0,0,0,0,0,0~
,0,0,DG88,0,0,0,0,0,0,0,0)';
      PINUSE='POWER';
      NO_LOAD_CHECK='Both';
      NO_IO_CHECK='Both';
      NO_ASSERT_CHECK='TRUE';
      NO_DIR_CHECK='TRUE';
      ALLOW_CONNECT='TRUE';
    'VSS1035':
      PIN_NUMBER='(0,0,0,0,0,0,0,0,0,0,0,0,0,0,0,0,0,0,0,0,0,0,0,0,0,0,0,0,0,0,0~
,0,0,DG84,0,0,0,0,0,0,0,0)';
      PINUSE='POWER';
      NO_LOAD_CHECK='Both';
      NO_IO_CHECK='Both';
      NO_ASSERT_CHECK='TRUE';
      NO_DIR_CHECK='TRUE';
      ALLOW_CONNECT='TRUE';
    'VSS1034':
      PIN_NUMBER='(0,0,0,0,0,0,0,0,0,0,0,0,0,0,0,0,0,0,0,0,0,0,0,0,0,0,0,0,0,0,0~
,0,0,DG80,0,0,0,0,0,0,0,0)';
      PINUSE='POWER';
      NO_LOAD_CHECK='Both';
      NO_IO_CHECK='Both';
      NO_ASSERT_CHECK='TRUE';
      NO_DIR_CHECK='TRUE';
      ALLOW_CONNECT='TRUE';
    'VSS1033':
      PIN_NUMBER='(0,0,0,0,0,0,0,0,0,0,0,0,0,0,0,0,0,0,0,0,0,0,0,0,0,0,0,0,0,0,0~
,0,0,DG76,0,0,0,0,0,0,0,0)';
      PINUSE='POWER';
      NO_LOAD_CHECK='Both';
      NO_IO_CHECK='Both';
      NO_ASSERT_CHECK='TRUE';
      NO_DIR_CHECK='TRUE';
      ALLOW_CONNECT='TRUE';
    'VSS1032':
      PIN_NUMBER='(0,0,0,0,0,0,0,0,0,0,0,0,0,0,0,0,0,0,0,0,0,0,0,0,0,0,0,0,0,0,0~
,0,0,DG70,0,0,0,0,0,0,0,0)';
      PINUSE='POWER';
      NO_LOAD_CHECK='Both';
      NO_IO_CHECK='Both';
      NO_ASSERT_CHECK='TRUE';
      NO_DIR_CHECK='TRUE';
      ALLOW_CONNECT='TRUE';
    'VSS1031':
      PIN_NUMBER='(0,0,0,0,0,0,0,0,0,0,0,0,0,0,0,0,0,0,0,0,0,0,0,0,0,0,0,0,0,0,0~
,0,0,DG5,0,0,0,0,0,0,0,0)';
      PINUSE='POWER';
      NO_LOAD_CHECK='Both';
      NO_IO_CHECK='Both';
      NO_ASSERT_CHECK='TRUE';
      NO_DIR_CHECK='TRUE';
      ALLOW_CONNECT='TRUE';
    'VSS1030':
      PIN_NUMBER='(0,0,0,0,0,0,0,0,0,0,0,0,0,0,0,0,0,0,0,0,0,0,0,0,0,0,0,0,0,0,0~
,0,0,DG45,0,0,0,0,0,0,0,0)';
      PINUSE='POWER';
      NO_LOAD_CHECK='Both';
      NO_IO_CHECK='Both';
      NO_ASSERT_CHECK='TRUE';
      NO_DIR_CHECK='TRUE';
      ALLOW_CONNECT='TRUE';
    'VSS1027':
      PIN_NUMBER='(0,0,0,0,0,0,0,0,0,0,0,0,0,0,0,0,0,0,0,0,0,0,0,0,0,0,0,0,0,0,0~
,0,0,DG39,0,0,0,0,0,0,0,0)';
      PINUSE='POWER';
      NO_LOAD_CHECK='Both';
      NO_IO_CHECK='Both';
      NO_ASSERT_CHECK='TRUE';
      NO_DIR_CHECK='TRUE';
      ALLOW_CONNECT='TRUE';
    'VSS1024':
      PIN_NUMBER='(0,0,0,0,0,0,0,0,0,0,0,0,0,0,0,0,0,0,0,0,0,0,0,0,0,0,0,0,0,0,0~
,0,0,DG33,0,0,0,0,0,0,0,0)';
      PINUSE='POWER';
      NO_LOAD_CHECK='Both';
      NO_IO_CHECK='Both';
      NO_ASSERT_CHECK='TRUE';
      NO_DIR_CHECK='TRUE';
      ALLOW_CONNECT='TRUE';
    'VSS1022':
      PIN_NUMBER='(0,0,0,0,0,0,0,0,0,0,0,0,0,0,0,0,0,0,0,0,0,0,0,0,0,0,0,0,0,0,0~
,0,0,DG27,0,0,0,0,0,0,0,0)';
      PINUSE='POWER';
      NO_LOAD_CHECK='Both';
      NO_IO_CHECK='Both';
      NO_ASSERT_CHECK='TRUE';
      NO_DIR_CHECK='TRUE';
      ALLOW_CONNECT='TRUE';
    'VSS1020':
      PIN_NUMBER='(0,0,0,0,0,0,0,0,0,0,0,0,0,0,0,0,0,0,0,0,0,0,0,0,0,0,0,0,0,0,0~
,0,0,DF87,0,0,0,0,0,0,0,0)';
      PINUSE='POWER';
      NO_LOAD_CHECK='Both';
      NO_IO_CHECK='Both';
      NO_ASSERT_CHECK='TRUE';
      NO_DIR_CHECK='TRUE';
      ALLOW_CONNECT='TRUE';
    'VSS1019':
      PIN_NUMBER='(0,0,0,0,0,0,0,0,0,0,0,0,0,0,0,0,0,0,0,0,0,0,0,0,0,0,0,0,0,0,0~
,0,0,DF8,0,0,0,0,0,0,0,0)';
      PINUSE='POWER';
      NO_LOAD_CHECK='Both';
      NO_IO_CHECK='Both';
      NO_ASSERT_CHECK='TRUE';
      NO_DIR_CHECK='TRUE';
      ALLOW_CONNECT='TRUE';
    'VSS1018':
      PIN_NUMBER='(0,0,0,0,0,0,0,0,0,0,0,0,0,0,0,0,0,0,0,0,0,0,0,0,0,0,0,0,0,0,0~
,0,0,DF79,0,0,0,0,0,0,0,0)';
      PINUSE='POWER';
      NO_LOAD_CHECK='Both';
      NO_IO_CHECK='Both';
      NO_ASSERT_CHECK='TRUE';
      NO_DIR_CHECK='TRUE';
      ALLOW_CONNECT='TRUE';
    'VSS1017':
      PIN_NUMBER='(0,0,0,0,0,0,0,0,0,0,0,0,0,0,0,0,0,0,0,0,0,0,0,0,0,0,0,0,0,0,0~
,0,0,DF4,0,0,0,0,0,0,0,0)';
      PINUSE='POWER';
      NO_LOAD_CHECK='Both';
      NO_IO_CHECK='Both';
      NO_ASSERT_CHECK='TRUE';
      NO_DIR_CHECK='TRUE';
      ALLOW_CONNECT='TRUE';
    'VSS1015':
      PIN_NUMBER='(0,0,0,0,0,0,0,0,0,0,0,0,0,0,0,0,0,0,0,0,0,0,0,0,0,0,0,0,0,0,0~
,0,0,DE88,0,0,0,0,0,0,0,0)';
      PINUSE='POWER';
      NO_LOAD_CHECK='Both';
      NO_IO_CHECK='Both';
      NO_ASSERT_CHECK='TRUE';
      NO_DIR_CHECK='TRUE';
      ALLOW_CONNECT='TRUE';
    'VSS1012':
      PIN_NUMBER='(0,0,0,0,0,0,0,0,0,0,0,0,0,0,0,0,0,0,0,0,0,0,0,0,0,0,0,0,0,0,0~
,0,0,DE84,0,0,0,0,0,0,0,0)';
      PINUSE='POWER';
      NO_LOAD_CHECK='Both';
      NO_IO_CHECK='Both';
      NO_ASSERT_CHECK='TRUE';
      NO_DIR_CHECK='TRUE';
      ALLOW_CONNECT='TRUE';
    'VSS1011':
      PIN_NUMBER='(0,0,0,0,0,0,0,0,0,0,0,0,0,0,0,0,0,0,0,0,0,0,0,0,0,0,0,0,0,0,0~
,0,0,DE82,0,0,0,0,0,0,0,0)';
      PINUSE='POWER';
      NO_LOAD_CHECK='Both';
      NO_IO_CHECK='Both';
      NO_ASSERT_CHECK='TRUE';
      NO_DIR_CHECK='TRUE';
      ALLOW_CONNECT='TRUE';
    'VSS1010':
      PIN_NUMBER='(0,0,0,0,0,0,0,0,0,0,0,0,0,0,0,0,0,0,0,0,0,0,0,0,0,0,0,0,0,0,0~
,0,0,DE76,0,0,0,0,0,0,0,0)';
      PINUSE='POWER';
      NO_LOAD_CHECK='Both';
      NO_IO_CHECK='Both';
      NO_ASSERT_CHECK='TRUE';
      NO_DIR_CHECK='TRUE';
      ALLOW_CONNECT='TRUE';
    'VSS1009':
      PIN_NUMBER='(0,0,0,0,0,0,0,0,0,0,0,0,0,0,0,0,0,0,0,0,0,0,0,0,0,0,0,0,0,0,0~
,0,0,DE74,0,0,0,0,0,0,0,0)';
      PINUSE='POWER';
      NO_LOAD_CHECK='Both';
      NO_IO_CHECK='Both';
      NO_ASSERT_CHECK='TRUE';
      NO_DIR_CHECK='TRUE';
      ALLOW_CONNECT='TRUE';
    'VSS1008':
      PIN_NUMBER='(0,0,0,0,0,0,0,0,0,0,0,0,0,0,0,0,0,0,0,0,0,0,0,0,0,0,0,0,0,0,0~
,0,0,DE72,0,0,0,0,0,0,0,0)';
      PINUSE='POWER';
      NO_LOAD_CHECK='Both';
      NO_IO_CHECK='Both';
      NO_ASSERT_CHECK='TRUE';
      NO_DIR_CHECK='TRUE';
      ALLOW_CONNECT='TRUE';
    'VSS1007':
      PIN_NUMBER='(0,0,0,0,0,0,0,0,0,0,0,0,0,0,0,0,0,0,0,0,0,0,0,0,0,0,0,0,0,0,0~
,0,0,DE68,0,0,0,0,0,0,0,0)';
      PINUSE='POWER';
      NO_LOAD_CHECK='Both';
      NO_IO_CHECK='Both';
      NO_ASSERT_CHECK='TRUE';
      NO_DIR_CHECK='TRUE';
      ALLOW_CONNECT='TRUE';
    'VSS1004':
      PIN_NUMBER='(0,0,0,0,0,0,0,0,0,0,0,0,0,0,0,0,0,0,0,0,0,0,0,0,0,0,0,0,0,0,0~
,0,0,DE66,0,0,0,0,0,0,0,0)';
      PINUSE='POWER';
      NO_LOAD_CHECK='Both';
      NO_IO_CHECK='Both';
      NO_ASSERT_CHECK='TRUE';
      NO_DIR_CHECK='TRUE';
      ALLOW_CONNECT='TRUE';
    'VSS1001':
      PIN_NUMBER='(0,0,0,0,0,0,0,0,0,0,0,0,0,0,0,0,0,0,0,0,0,0,0,0,0,0,0,0,0,0,0~
,0,0,DE64,0,0,0,0,0,0,0,0)';
      PINUSE='POWER';
      NO_LOAD_CHECK='Both';
      NO_IO_CHECK='Both';
      NO_ASSERT_CHECK='TRUE';
      NO_DIR_CHECK='TRUE';
      ALLOW_CONNECT='TRUE';
    'VSS999':
      PIN_NUMBER='(0,0,0,0,0,0,0,0,0,0,0,0,0,0,0,0,0,0,0,0,0,0,0,0,0,0,0,0,0,0,0~
,0,0,DE62,0,0,0,0,0,0,0,0)';
      PINUSE='POWER';
      NO_LOAD_CHECK='Both';
      NO_IO_CHECK='Both';
      NO_ASSERT_CHECK='TRUE';
      NO_DIR_CHECK='TRUE';
      ALLOW_CONNECT='TRUE';
    'VSS997':
      PIN_NUMBER='(0,0,0,0,0,0,0,0,0,0,0,0,0,0,0,0,0,0,0,0,0,0,0,0,0,0,0,0,0,0,0~
,0,0,DE60,0,0,0,0,0,0,0,0)';
      PINUSE='POWER';
      NO_LOAD_CHECK='Both';
      NO_IO_CHECK='Both';
      NO_ASSERT_CHECK='TRUE';
      NO_DIR_CHECK='TRUE';
      ALLOW_CONNECT='TRUE';
    'VSS996':
      PIN_NUMBER='(0,0,0,0,0,0,0,0,0,0,0,0,0,0,0,0,0,0,0,0,0,0,0,0,0,0,0,0,0,0,0~
,0,0,DE58,0,0,0,0,0,0,0,0)';
      PINUSE='POWER';
      NO_LOAD_CHECK='Both';
      NO_IO_CHECK='Both';
      NO_ASSERT_CHECK='TRUE';
      NO_DIR_CHECK='TRUE';
      ALLOW_CONNECT='TRUE';
    'VSS995':
      PIN_NUMBER='(0,0,0,0,0,0,0,0,0,0,0,0,0,0,0,0,0,0,0,0,0,0,0,0,0,0,0,0,0,0,0~
,0,0,DE56,0,0,0,0,0,0,0,0)';
      PINUSE='POWER';
      NO_LOAD_CHECK='Both';
      NO_IO_CHECK='Both';
      NO_ASSERT_CHECK='TRUE';
      NO_DIR_CHECK='TRUE';
      ALLOW_CONNECT='TRUE';
    'VSS994':
      PIN_NUMBER='(0,0,0,0,0,0,0,0,0,0,0,0,0,0,0,0,0,0,0,0,0,0,0,0,0,0,0,0,0,0,0~
,0,0,DE54,0,0,0,0,0,0,0,0)';
      PINUSE='POWER';
      NO_LOAD_CHECK='Both';
      NO_IO_CHECK='Both';
      NO_ASSERT_CHECK='TRUE';
      NO_DIR_CHECK='TRUE';
      ALLOW_CONNECT='TRUE';
    'VSS992':
      PIN_NUMBER='(0,0,0,0,0,0,0,0,0,0,0,0,0,0,0,0,0,0,0,0,0,0,0,0,0,0,0,0,0,0,0~
,0,0,DE52,0,0,0,0,0,0,0,0)';
      PINUSE='POWER';
      NO_LOAD_CHECK='Both';
      NO_IO_CHECK='Both';
      NO_ASSERT_CHECK='TRUE';
      NO_DIR_CHECK='TRUE';
      ALLOW_CONNECT='TRUE';
    'VSS991':
      PIN_NUMBER='(0,0,0,0,0,0,0,0,0,0,0,0,0,0,0,0,0,0,0,0,0,0,0,0,0,0,0,0,0,0,0~
,0,0,DE50,0,0,0,0,0,0,0,0)';
      PINUSE='POWER';
      NO_LOAD_CHECK='Both';
      NO_IO_CHECK='Both';
      NO_ASSERT_CHECK='TRUE';
      NO_DIR_CHECK='TRUE';
      ALLOW_CONNECT='TRUE';
    'VSS989':
      PIN_NUMBER='(0,0,0,0,0,0,0,0,0,0,0,0,0,0,0,0,0,0,0,0,0,0,0,0,0,0,0,0,0,0,0~
,0,0,DE48,0,0,0,0,0,0,0,0)';
      PINUSE='POWER';
      NO_LOAD_CHECK='Both';
      NO_IO_CHECK='Both';
      NO_ASSERT_CHECK='TRUE';
      NO_DIR_CHECK='TRUE';
      ALLOW_CONNECT='TRUE';
    'VSS988':
      PIN_NUMBER='(0,0,0,0,0,0,0,0,0,0,0,0,0,0,0,0,0,0,0,0,0,0,0,0,0,0,0,0,0,0,0~
,0,0,DE45,0,0,0,0,0,0,0,0)';
      PINUSE='POWER';
      NO_LOAD_CHECK='Both';
      NO_IO_CHECK='Both';
      NO_ASSERT_CHECK='TRUE';
      NO_DIR_CHECK='TRUE';
      ALLOW_CONNECT='TRUE';
    'VSS987':
      PIN_NUMBER='(0,0,0,0,0,0,0,0,0,0,0,0,0,0,0,0,0,0,0,0,0,0,0,0,0,0,0,0,0,0,0~
,0,0,DE43,0,0,0,0,0,0,0,0)';
      PINUSE='POWER';
      NO_LOAD_CHECK='Both';
      NO_IO_CHECK='Both';
      NO_ASSERT_CHECK='TRUE';
      NO_DIR_CHECK='TRUE';
      ALLOW_CONNECT='TRUE';
    'VSS986':
      PIN_NUMBER='(0,0,0,0,0,0,0,0,0,0,0,0,0,0,0,0,0,0,0,0,0,0,0,0,0,0,0,0,0,0,0~
,0,0,DE41,0,0,0,0,0,0,0,0)';
      PINUSE='POWER';
      NO_LOAD_CHECK='Both';
      NO_IO_CHECK='Both';
      NO_ASSERT_CHECK='TRUE';
      NO_DIR_CHECK='TRUE';
      ALLOW_CONNECT='TRUE';
    'VSS984':
      PIN_NUMBER='(0,0,0,0,0,0,0,0,0,0,0,0,0,0,0,0,0,0,0,0,0,0,0,0,0,0,0,0,0,0,0~
,0,0,DE37,0,0,0,0,0,0,0,0)';
      PINUSE='POWER';
      NO_LOAD_CHECK='Both';
      NO_IO_CHECK='Both';
      NO_ASSERT_CHECK='TRUE';
      NO_DIR_CHECK='TRUE';
      ALLOW_CONNECT='TRUE';
    'VSS983':
      PIN_NUMBER='(0,0,0,0,0,0,0,0,0,0,0,0,0,0,0,0,0,0,0,0,0,0,0,0,0,0,0,0,0,0,0~
,0,0,DE35,0,0,0,0,0,0,0,0)';
      PINUSE='POWER';
      NO_LOAD_CHECK='Both';
      NO_IO_CHECK='Both';
      NO_ASSERT_CHECK='TRUE';
      NO_DIR_CHECK='TRUE';
      ALLOW_CONNECT='TRUE';
    'VSS982':
      PIN_NUMBER='(0,0,0,0,0,0,0,0,0,0,0,0,0,0,0,0,0,0,0,0,0,0,0,0,0,0,0,0,0,0,0~
,0,0,DE33,0,0,0,0,0,0,0,0)';
      PINUSE='POWER';
      NO_LOAD_CHECK='Both';
      NO_IO_CHECK='Both';
      NO_ASSERT_CHECK='TRUE';
      NO_DIR_CHECK='TRUE';
      ALLOW_CONNECT='TRUE';
    'VSS981':
      PIN_NUMBER='(0,0,0,0,0,0,0,0,0,0,0,0,0,0,0,0,0,0,0,0,0,0,0,0,0,0,0,0,0,0,0~
,0,0,DE31,0,0,0,0,0,0,0,0)';
      PINUSE='POWER';
      NO_LOAD_CHECK='Both';
      NO_IO_CHECK='Both';
      NO_ASSERT_CHECK='TRUE';
      NO_DIR_CHECK='TRUE';
      ALLOW_CONNECT='TRUE';
    'VSS978':
      PIN_NUMBER='(0,0,0,0,0,0,0,0,0,0,0,0,0,0,0,0,0,0,0,0,0,0,0,0,0,0,0,0,0,0,0~
,0,0,DE29,0,0,0,0,0,0,0,0)';
      PINUSE='POWER';
      NO_LOAD_CHECK='Both';
      NO_IO_CHECK='Both';
      NO_ASSERT_CHECK='TRUE';
      NO_DIR_CHECK='TRUE';
      ALLOW_CONNECT='TRUE';
    'VSS977':
      PIN_NUMBER='(0,0,0,0,0,0,0,0,0,0,0,0,0,0,0,0,0,0,0,0,0,0,0,0,0,0,0,0,0,0,0~
,0,0,DE27,0,0,0,0,0,0,0,0)';
      PINUSE='POWER';
      NO_LOAD_CHECK='Both';
      NO_IO_CHECK='Both';
      NO_ASSERT_CHECK='TRUE';
      NO_DIR_CHECK='TRUE';
      ALLOW_CONNECT='TRUE';
    'VSS975':
      PIN_NUMBER='(0,0,0,0,0,0,0,0,0,0,0,0,0,0,0,0,0,0,0,0,0,0,0,0,0,0,0,0,0,0,0~
,0,0,DE25,0,0,0,0,0,0,0,0)';
      PINUSE='POWER';
      NO_LOAD_CHECK='Both';
      NO_IO_CHECK='Both';
      NO_ASSERT_CHECK='TRUE';
      NO_DIR_CHECK='TRUE';
      ALLOW_CONNECT='TRUE';
    'VSS974':
      PIN_NUMBER='(0,0,0,0,0,0,0,0,0,0,0,0,0,0,0,0,0,0,0,0,0,0,0,0,0,0,0,0,0,0,0~
,0,0,DE23,0,0,0,0,0,0,0,0)';
      PINUSE='POWER';
      NO_LOAD_CHECK='Both';
      NO_IO_CHECK='Both';
      NO_ASSERT_CHECK='TRUE';
      NO_DIR_CHECK='TRUE';
      ALLOW_CONNECT='TRUE';
    'VSS972':
      PIN_NUMBER='(0,0,0,0,0,0,0,0,0,0,0,0,0,0,0,0,0,0,0,0,0,0,0,0,0,0,0,0,0,0,0~
,0,0,DE21,0,0,0,0,0,0,0,0)';
      PINUSE='POWER';
      NO_LOAD_CHECK='Both';
      NO_IO_CHECK='Both';
      NO_ASSERT_CHECK='TRUE';
      NO_DIR_CHECK='TRUE';
      ALLOW_CONNECT='TRUE';
    'VSS971':
      PIN_NUMBER='(0,0,0,0,0,0,0,0,0,0,0,0,0,0,0,0,0,0,0,0,0,0,0,0,0,0,0,0,0,0,0~
,0,0,DE19,0,0,0,0,0,0,0,0)';
      PINUSE='POWER';
      NO_LOAD_CHECK='Both';
      NO_IO_CHECK='Both';
      NO_ASSERT_CHECK='TRUE';
      NO_DIR_CHECK='TRUE';
      ALLOW_CONNECT='TRUE';
    'VSS970':
      PIN_NUMBER='(0,0,0,0,0,0,0,0,0,0,0,0,0,0,0,0,0,0,0,0,0,0,0,0,0,0,0,0,0,0,0~
,0,0,DE17,0,0,0,0,0,0,0,0)';
      PINUSE='POWER';
      NO_LOAD_CHECK='Both';
      NO_IO_CHECK='Both';
      NO_ASSERT_CHECK='TRUE';
      NO_DIR_CHECK='TRUE';
      ALLOW_CONNECT='TRUE';
    'VSS967':
      PIN_NUMBER='(0,0,0,0,0,0,0,0,0,0,0,0,0,0,0,0,0,0,0,0,0,0,0,0,0,0,0,0,0,0,0~
,0,0,DD8,0,0,0,0,0,0,0,0)';
      PINUSE='POWER';
      NO_LOAD_CHECK='Both';
      NO_IO_CHECK='Both';
      NO_ASSERT_CHECK='TRUE';
      NO_DIR_CHECK='TRUE';
      ALLOW_CONNECT='TRUE';
    'VSS965':
      PIN_NUMBER='(0,0,0,0,0,0,0,0,0,0,0,0,0,0,0,0,0,0,0,0,0,0,0,0,0,0,0,0,0,0,0~
,0,0,DD79,0,0,0,0,0,0,0,0)';
      PINUSE='POWER';
      NO_LOAD_CHECK='Both';
      NO_IO_CHECK='Both';
      NO_ASSERT_CHECK='TRUE';
      NO_DIR_CHECK='TRUE';
      ALLOW_CONNECT='TRUE';
    'VSS964':
      PIN_NUMBER='(0,0,0,0,0,0,0,0,0,0,0,0,0,0,0,0,0,0,0,0,0,0,0,0,0,0,0,0,0,0,0~
,0,0,DD4,0,0,0,0,0,0,0,0)';
      PINUSE='POWER';
      NO_LOAD_CHECK='Both';
      NO_IO_CHECK='Both';
      NO_ASSERT_CHECK='TRUE';
      NO_DIR_CHECK='TRUE';
      ALLOW_CONNECT='TRUE';
    'VSS963':
      PIN_NUMBER='(0,0,0,0,0,0,0,0,0,0,0,0,0,0,0,0,0,0,0,0,0,0,0,0,0,0,0,0,0,0,0~
,0,0,DC9,0,0,0,0,0,0,0,0)';
      PINUSE='POWER';
      NO_LOAD_CHECK='Both';
      NO_IO_CHECK='Both';
      NO_ASSERT_CHECK='TRUE';
      NO_DIR_CHECK='TRUE';
      ALLOW_CONNECT='TRUE';
    'VSS962':
      PIN_NUMBER='(0,0,0,0,0,0,0,0,0,0,0,0,0,0,0,0,0,0,0,0,0,0,0,0,0,0,0,0,0,0,0~
,0,0,DC88,0,0,0,0,0,0,0,0)';
      PINUSE='POWER';
      NO_LOAD_CHECK='Both';
      NO_IO_CHECK='Both';
      NO_ASSERT_CHECK='TRUE';
      NO_DIR_CHECK='TRUE';
      ALLOW_CONNECT='TRUE';
    'VSS961':
      PIN_NUMBER='(0,0,0,0,0,0,0,0,0,0,0,0,0,0,0,0,0,0,0,0,0,0,0,0,0,0,0,0,0,0,0~
,0,0,DC84,0,0,0,0,0,0,0,0)';
      PINUSE='POWER';
      NO_LOAD_CHECK='Both';
      NO_IO_CHECK='Both';
      NO_ASSERT_CHECK='TRUE';
      NO_DIR_CHECK='TRUE';
      ALLOW_CONNECT='TRUE';
    'VSS960':
      PIN_NUMBER='(0,0,0,0,0,0,0,0,0,0,0,0,0,0,0,0,0,0,0,0,0,0,0,0,0,0,0,0,0,0,0~
,0,0,DC80,0,0,0,0,0,0,0,0)';
      PINUSE='POWER';
      NO_LOAD_CHECK='Both';
      NO_IO_CHECK='Both';
      NO_ASSERT_CHECK='TRUE';
      NO_DIR_CHECK='TRUE';
      ALLOW_CONNECT='TRUE';
    'VSS958':
      PIN_NUMBER='(0,0,0,0,0,0,0,0,0,0,0,0,0,0,0,0,0,0,0,0,0,0,0,0,0,0,0,0,0,0,0~
,0,0,DC78,0,0,0,0,0,0,0,0)';
      PINUSE='POWER';
      NO_LOAD_CHECK='Both';
      NO_IO_CHECK='Both';
      NO_ASSERT_CHECK='TRUE';
      NO_DIR_CHECK='TRUE';
      ALLOW_CONNECT='TRUE';
    'VSS956':
      PIN_NUMBER='(0,0,0,0,0,0,0,0,0,0,0,0,0,0,0,0,0,0,0,0,0,0,0,0,0,0,0,0,0,0,0~
,0,0,DC76,0,0,0,0,0,0,0,0)';
      PINUSE='POWER';
      NO_LOAD_CHECK='Both';
      NO_IO_CHECK='Both';
      NO_ASSERT_CHECK='TRUE';
      NO_DIR_CHECK='TRUE';
      ALLOW_CONNECT='TRUE';
    'VSS954':
      PIN_NUMBER='(0,0,0,0,0,0,0,0,0,0,0,0,0,0,0,0,0,0,0,0,0,0,0,0,0,0,0,0,0,0,0~
,0,0,DC70,0,0,0,0,0,0,0,0)';
      PINUSE='POWER';
      NO_LOAD_CHECK='Both';
      NO_IO_CHECK='Both';
      NO_ASSERT_CHECK='TRUE';
      NO_DIR_CHECK='TRUE';
      ALLOW_CONNECT='TRUE';
    'VSS953':
      PIN_NUMBER='(0,0,0,0,0,0,0,0,0,0,0,0,0,0,0,0,0,0,0,0,0,0,0,0,0,0,0,0,0,0,0~
,0,0,DC5,0,0,0,0,0,0,0,0)';
      PINUSE='POWER';
      NO_LOAD_CHECK='Both';
      NO_IO_CHECK='Both';
      NO_ASSERT_CHECK='TRUE';
      NO_DIR_CHECK='TRUE';
      ALLOW_CONNECT='TRUE';
    'VSS952':
      PIN_NUMBER='(0,0,0,0,0,0,0,0,0,0,0,0,0,0,0,0,0,0,0,0,0,0,0,0,0,0,0,0,0,0,0~
,0,0,DC45,0,0,0,0,0,0,0,0)';
      PINUSE='POWER';
      NO_LOAD_CHECK='Both';
      NO_IO_CHECK='Both';
      NO_ASSERT_CHECK='TRUE';
      NO_DIR_CHECK='TRUE';
      ALLOW_CONNECT='TRUE';
    'VSS951':
      PIN_NUMBER='(0,0,0,0,0,0,0,0,0,0,0,0,0,0,0,0,0,0,0,0,0,0,0,0,0,0,0,0,0,0,0~
,0,0,DC39,0,0,0,0,0,0,0,0)';
      PINUSE='POWER';
      NO_LOAD_CHECK='Both';
      NO_IO_CHECK='Both';
      NO_ASSERT_CHECK='TRUE';
      NO_DIR_CHECK='TRUE';
      ALLOW_CONNECT='TRUE';
    'VSS950':
      PIN_NUMBER='(0,0,0,0,0,0,0,0,0,0,0,0,0,0,0,0,0,0,0,0,0,0,0,0,0,0,0,0,0,0,0~
,0,0,DC33,0,0,0,0,0,0,0,0)';
      PINUSE='POWER';
      NO_LOAD_CHECK='Both';
      NO_IO_CHECK='Both';
      NO_ASSERT_CHECK='TRUE';
      NO_DIR_CHECK='TRUE';
      ALLOW_CONNECT='TRUE';
    'VSS949':
      PIN_NUMBER='(0,0,0,0,0,0,0,0,0,0,0,0,0,0,0,0,0,0,0,0,0,0,0,0,0,0,0,0,0,0,0~
,0,0,DC27,0,0,0,0,0,0,0,0)';
      PINUSE='POWER';
      NO_LOAD_CHECK='Both';
      NO_IO_CHECK='Both';
      NO_ASSERT_CHECK='TRUE';
      NO_DIR_CHECK='TRUE';
      ALLOW_CONNECT='TRUE';
    'VSS909':
      PIN_NUMBER='(0,0,0,0,0,0,0,0,0,0,0,0,0,0,0,0,0,0,0,0,0,0,0,0,0,0,0,0,0,0,0~
,0,0,DL52,0,0,0,0,0,0,0,0)';
      PINUSE='POWER';
      NO_LOAD_CHECK='Both';
      NO_IO_CHECK='Both';
      NO_ASSERT_CHECK='TRUE';
      NO_DIR_CHECK='TRUE';
      ALLOW_CONNECT='TRUE';
    'VSS908':
      PIN_NUMBER='(0,0,0,0,0,0,0,0,0,0,0,0,0,0,0,0,0,0,0,0,0,0,0,0,0,0,0,0,0,0,0~
,0,0,DL5,0,0,0,0,0,0,0,0)';
      PINUSE='POWER';
      NO_LOAD_CHECK='Both';
      NO_IO_CHECK='Both';
      NO_ASSERT_CHECK='TRUE';
      NO_DIR_CHECK='TRUE';
      ALLOW_CONNECT='TRUE';
    'VSS905':
      PIN_NUMBER='(0,0,0,0,0,0,0,0,0,0,0,0,0,0,0,0,0,0,0,0,0,0,0,0,0,0,0,0,0,0,0~
,0,0,DL17,0,0,0,0,0,0,0,0)';
      PINUSE='POWER';
      NO_LOAD_CHECK='Both';
      NO_IO_CHECK='Both';
      NO_ASSERT_CHECK='TRUE';
      NO_DIR_CHECK='TRUE';
      ALLOW_CONNECT='TRUE';
    'VSS904':
      PIN_NUMBER='(0,0,0,0,0,0,0,0,0,0,0,0,0,0,0,0,0,0,0,0,0,0,0,0,0,0,0,0,0,0,0~
,0,0,DL13,0,0,0,0,0,0,0,0)';
      PINUSE='POWER';
      NO_LOAD_CHECK='Both';
      NO_IO_CHECK='Both';
      NO_ASSERT_CHECK='TRUE';
      NO_DIR_CHECK='TRUE';
      ALLOW_CONNECT='TRUE';
    'VSS903':
      PIN_NUMBER='(0,0,0,0,0,0,0,0,0,0,0,0,0,0,0,0,0,0,0,0,0,0,0,0,0,0,0,0,0,0,0~
,0,0,DL1,0,0,0,0,0,0,0,0)';
      PINUSE='POWER';
      NO_LOAD_CHECK='Both';
      NO_IO_CHECK='Both';
      NO_ASSERT_CHECK='TRUE';
      NO_DIR_CHECK='TRUE';
      ALLOW_CONNECT='TRUE';
    'VSS894':
      PIN_NUMBER='(0,0,0,0,0,0,0,0,0,0,0,0,0,0,0,0,0,0,0,0,0,0,0,0,0,0,0,0,0,0,0~
,0,0,DK67,0,0,0,0,0,0,0,0)';
      PINUSE='POWER';
      NO_LOAD_CHECK='Both';
      NO_IO_CHECK='Both';
      NO_ASSERT_CHECK='TRUE';
      NO_DIR_CHECK='TRUE';
      ALLOW_CONNECT='TRUE';
    'VSS893':
      PIN_NUMBER='(0,0,0,0,0,0,0,0,0,0,0,0,0,0,0,0,0,0,0,0,0,0,0,0,0,0,0,0,0,0,0~
,0,0,DK61,0,0,0,0,0,0,0,0)';
      PINUSE='POWER';
      NO_LOAD_CHECK='Both';
      NO_IO_CHECK='Both';
      NO_ASSERT_CHECK='TRUE';
      NO_DIR_CHECK='TRUE';
      ALLOW_CONNECT='TRUE';
    'VSS890':
      PIN_NUMBER='(0,0,0,0,0,0,0,0,0,0,0,0,0,0,0,0,0,0,0,0,0,0,0,0,0,0,0,0,0,0,0~
,0,0,DK55,0,0,0,0,0,0,0,0)';
      PINUSE='POWER';
      NO_LOAD_CHECK='Both';
      NO_IO_CHECK='Both';
      NO_ASSERT_CHECK='TRUE';
      NO_DIR_CHECK='TRUE';
      ALLOW_CONNECT='TRUE';
    'VSS887':
      PIN_NUMBER='(0,0,0,0,0,0,0,0,0,0,0,0,0,0,0,0,0,0,0,0,0,0,0,0,0,0,0,0,0,0,0~
,0,0,DK42,0,0,0,0,0,0,0,0)';
      PINUSE='POWER';
      NO_LOAD_CHECK='Both';
      NO_IO_CHECK='Both';
      NO_ASSERT_CHECK='TRUE';
      NO_DIR_CHECK='TRUE';
      ALLOW_CONNECT='TRUE';
    'VSS883':
      PIN_NUMBER='(0,0,0,0,0,0,0,0,0,0,0,0,0,0,0,0,0,0,0,0,0,0,0,0,0,0,0,0,0,0,0~
,0,0,DK24,0,0,0,0,0,0,0,0)';
      PINUSE='POWER';
      NO_LOAD_CHECK='Both';
      NO_IO_CHECK='Both';
      NO_ASSERT_CHECK='TRUE';
      NO_DIR_CHECK='TRUE';
      ALLOW_CONNECT='TRUE';
    'VSS882':
      PIN_NUMBER='(0,0,0,0,0,0,0,0,0,0,0,0,0,0,0,0,0,0,0,0,0,0,0,0,0,0,0,0,0,0,0~
,0,0,DK18,0,0,0,0,0,0,0,0)';
      PINUSE='POWER';
      NO_LOAD_CHECK='Both';
      NO_IO_CHECK='Both';
      NO_ASSERT_CHECK='TRUE';
      NO_DIR_CHECK='TRUE';
      ALLOW_CONNECT='TRUE';
    'VSS880':
      PIN_NUMBER='(0,0,0,0,0,0,0,0,0,0,0,0,0,0,0,0,0,0,0,0,0,0,0,0,0,0,0,0,0,0,0~
,0,0,DK12,0,0,0,0,0,0,0,0)';
      PINUSE='POWER';
      NO_LOAD_CHECK='Both';
      NO_IO_CHECK='Both';
      NO_ASSERT_CHECK='TRUE';
      NO_DIR_CHECK='TRUE';
      ALLOW_CONNECT='TRUE';
    'VSS872':
      PIN_NUMBER='(0,0,0,0,0,0,0,0,0,0,0,0,0,0,0,0,0,0,0,0,0,0,0,0,0,0,0,0,0,0,0~
,0,0,DJ68,0,0,0,0,0,0,0,0)';
      PINUSE='POWER';
      NO_LOAD_CHECK='Both';
      NO_IO_CHECK='Both';
      NO_ASSERT_CHECK='TRUE';
      NO_DIR_CHECK='TRUE';
      ALLOW_CONNECT='TRUE';
    'VSS870':
      PIN_NUMBER='(0,0,0,0,0,0,0,0,0,0,0,0,0,0,0,0,0,0,0,0,0,0,0,0,0,0,0,0,0,0,0~
,0,0,DJ62,0,0,0,0,0,0,0,0)';
      PINUSE='POWER';
      NO_LOAD_CHECK='Both';
      NO_IO_CHECK='Both';
      NO_ASSERT_CHECK='TRUE';
      NO_DIR_CHECK='TRUE';
      ALLOW_CONNECT='TRUE';
    'VSS867':
      PIN_NUMBER='(0,0,0,0,0,0,0,0,0,0,0,0,0,0,0,0,0,0,0,0,0,0,0,0,0,0,0,0,0,0,0~
,0,0,DJ54,0,0,0,0,0,0,0,0)';
      PINUSE='POWER';
      NO_LOAD_CHECK='Both';
      NO_IO_CHECK='Both';
      NO_ASSERT_CHECK='TRUE';
      NO_DIR_CHECK='TRUE';
      ALLOW_CONNECT='TRUE';
    'VSS861':
      PIN_NUMBER='(0,0,0,0,0,0,0,0,0,0,0,0,0,0,0,0,0,0,0,0,0,0,0,0,0,0,0,0,0,0,0~
,0,0,DJ35,0,0,0,0,0,0,0,0)';
      PINUSE='POWER';
      NO_LOAD_CHECK='Both';
      NO_IO_CHECK='Both';
      NO_ASSERT_CHECK='TRUE';
      NO_DIR_CHECK='TRUE';
      ALLOW_CONNECT='TRUE';
    'VSS857':
      PIN_NUMBER='(0,0,0,0,0,0,0,0,0,0,0,0,0,0,0,0,0,0,0,0,0,0,0,0,0,0,0,0,0,0,0~
,0,0,DJ25,0,0,0,0,0,0,0,0)';
      PINUSE='POWER';
      NO_LOAD_CHECK='Both';
      NO_IO_CHECK='Both';
      NO_ASSERT_CHECK='TRUE';
      NO_DIR_CHECK='TRUE';
      ALLOW_CONNECT='TRUE';
    'VSS849':
      PIN_NUMBER='(0,0,0,0,0,0,0,0,0,0,0,0,0,0,0,0,0,0,0,0,0,0,0,0,0,0,0,0,0,0,0~
,0,0,DH75,0,0,0,0,0,0,0,0)';
      PINUSE='POWER';
      NO_LOAD_CHECK='Both';
      NO_IO_CHECK='Both';
      NO_ASSERT_CHECK='TRUE';
      NO_DIR_CHECK='TRUE';
      ALLOW_CONNECT='TRUE';
    'VSS847':
      PIN_NUMBER='(0,0,0,0,0,0,0,0,0,0,0,0,0,0,0,0,0,0,0,0,0,0,0,0,0,0,0,0,0,0,0~
,0,0,DH69,0,0,0,0,0,0,0,0)';
      PINUSE='POWER';
      NO_LOAD_CHECK='Both';
      NO_IO_CHECK='Both';
      NO_ASSERT_CHECK='TRUE';
      NO_DIR_CHECK='TRUE';
      ALLOW_CONNECT='TRUE';
    'VSS845':
      PIN_NUMBER='(0,0,0,0,0,0,0,0,0,0,0,0,0,0,0,0,0,0,0,0,0,0,0,0,0,0,0,0,0,0,0~
,0,0,DH63,0,0,0,0,0,0,0,0)';
      PINUSE='POWER';
      NO_LOAD_CHECK='Both';
      NO_IO_CHECK='Both';
      NO_ASSERT_CHECK='TRUE';
      NO_DIR_CHECK='TRUE';
      ALLOW_CONNECT='TRUE';
    'VSS844':
      PIN_NUMBER='(0,0,0,0,0,0,0,0,0,0,0,0,0,0,0,0,0,0,0,0,0,0,0,0,0,0,0,0,0,0,0~
,0,0,DH59,0,0,0,0,0,0,0,0)';
      PINUSE='POWER';
      NO_LOAD_CHECK='Both';
      NO_IO_CHECK='Both';
      NO_ASSERT_CHECK='TRUE';
      NO_DIR_CHECK='TRUE';
      ALLOW_CONNECT='TRUE';
    'VSS842':
      PIN_NUMBER='(0,0,0,0,0,0,0,0,0,0,0,0,0,0,0,0,0,0,0,0,0,0,0,0,0,0,0,0,0,0,0~
,0,0,DH53,0,0,0,0,0,0,0,0)';
      PINUSE='POWER';
      NO_LOAD_CHECK='Both';
      NO_IO_CHECK='Both';
      NO_ASSERT_CHECK='TRUE';
      NO_DIR_CHECK='TRUE';
      ALLOW_CONNECT='TRUE';
    'VSS841':
      PIN_NUMBER='(0,0,0,0,0,0,0,0,0,0,0,0,0,0,0,0,0,0,0,0,0,0,0,0,0,0,0,0,0,0,0~
,0,0,DH51,0,0,0,0,0,0,0,0)';
      PINUSE='POWER';
      NO_LOAD_CHECK='Both';
      NO_IO_CHECK='Both';
      NO_ASSERT_CHECK='TRUE';
      NO_DIR_CHECK='TRUE';
      ALLOW_CONNECT='TRUE';
    'VSS839':
      PIN_NUMBER='(0,0,0,0,0,0,0,0,0,0,0,0,0,0,0,0,0,0,0,0,0,0,0,0,0,0,0,0,0,0,0~
,0,0,DH44,0,0,0,0,0,0,0,0)';
      PINUSE='POWER';
      NO_LOAD_CHECK='Both';
      NO_IO_CHECK='Both';
      NO_ASSERT_CHECK='TRUE';
      NO_DIR_CHECK='TRUE';
      ALLOW_CONNECT='TRUE';
    'VSS835':
      PIN_NUMBER='(0,0,0,0,0,0,0,0,0,0,0,0,0,0,0,0,0,0,0,0,0,0,0,0,0,0,0,0,0,0,0~
,0,0,DH34,0,0,0,0,0,0,0,0)';
      PINUSE='POWER';
      NO_LOAD_CHECK='Both';
      NO_IO_CHECK='Both';
      NO_ASSERT_CHECK='TRUE';
      NO_DIR_CHECK='TRUE';
      ALLOW_CONNECT='TRUE';
    'VSS832':
      PIN_NUMBER='(0,0,0,0,0,0,0,0,0,0,0,0,0,0,0,0,0,0,0,0,0,0,0,0,0,0,0,0,0,0,0~
,0,0,DH26,0,0,0,0,0,0,0,0)';
      PINUSE='POWER';
      NO_LOAD_CHECK='Both';
      NO_IO_CHECK='Both';
      NO_ASSERT_CHECK='TRUE';
      NO_DIR_CHECK='TRUE';
      ALLOW_CONNECT='TRUE';
    'VSS830':
      PIN_NUMBER='(0,0,0,0,0,0,0,0,0,0,0,0,0,0,0,0,0,0,0,0,0,0,0,0,0,0,0,0,0,0,0~
,0,0,DH20,0,0,0,0,0,0,0,0)';
      PINUSE='POWER';
      NO_LOAD_CHECK='Both';
      NO_IO_CHECK='Both';
      NO_ASSERT_CHECK='TRUE';
      NO_DIR_CHECK='TRUE';
      ALLOW_CONNECT='TRUE';
    'VSS829':
      PIN_NUMBER='(0,0,0,0,0,0,0,0,0,0,0,0,0,0,0,0,0,0,0,0,0,0,0,0,0,0,0,0,0,0,0~
,0,0,DH16,0,0,0,0,0,0,0,0)';
      PINUSE='POWER';
      NO_LOAD_CHECK='Both';
      NO_IO_CHECK='Both';
      NO_ASSERT_CHECK='TRUE';
      NO_DIR_CHECK='TRUE';
      ALLOW_CONNECT='TRUE';
    'VSS821':
      PIN_NUMBER='(0,0,0,0,0,0,0,0,0,0,0,0,0,0,0,0,0,0,0,0,0,0,0,0,0,0,0,0,0,0,0~
,0,0,DG64,0,0,0,0,0,0,0,0)';
      PINUSE='POWER';
      NO_LOAD_CHECK='Both';
      NO_IO_CHECK='Both';
      NO_ASSERT_CHECK='TRUE';
      NO_DIR_CHECK='TRUE';
      ALLOW_CONNECT='TRUE';
    'VSS820':
      PIN_NUMBER='(0,0,0,0,0,0,0,0,0,0,0,0,0,0,0,0,0,0,0,0,0,0,0,0,0,0,0,0,0,0,0~
,0,0,DG58,0,0,0,0,0,0,0,0)';
      PINUSE='POWER';
      NO_LOAD_CHECK='Both';
      NO_IO_CHECK='Both';
      NO_ASSERT_CHECK='TRUE';
      NO_DIR_CHECK='TRUE';
      ALLOW_CONNECT='TRUE';
    'VSS817':
      PIN_NUMBER='(0,0,0,0,0,0,0,0,0,0,0,0,0,0,0,0,0,0,0,0,0,0,0,0,0,0,0,0,0,0,0~
,0,0,DG52,0,0,0,0,0,0,0,0)';
      PINUSE='POWER';
      NO_LOAD_CHECK='Both';
      NO_IO_CHECK='Both';
      NO_ASSERT_CHECK='TRUE';
      NO_DIR_CHECK='TRUE';
      ALLOW_CONNECT='TRUE';
    'VSS809':
      PIN_NUMBER='(0,0,0,0,0,0,0,0,0,0,0,0,0,0,0,0,0,0,0,0,0,0,0,0,0,0,0,0,0,0,0~
,0,0,DG21,0,0,0,0,0,0,0,0)';
      PINUSE='POWER';
      NO_LOAD_CHECK='Both';
      NO_IO_CHECK='Both';
      NO_ASSERT_CHECK='TRUE';
      NO_DIR_CHECK='TRUE';
      ALLOW_CONNECT='TRUE';
    'VSS808':
      PIN_NUMBER='(0,0,0,0,0,0,0,0,0,0,0,0,0,0,0,0,0,0,0,0,0,0,0,0,0,0,0,0,0,0,0~
,0,0,DG13,0,0,0,0,0,0,0,0)';
      PINUSE='POWER';
      NO_LOAD_CHECK='Both';
      NO_IO_CHECK='Both';
      NO_ASSERT_CHECK='TRUE';
      NO_DIR_CHECK='TRUE';
      ALLOW_CONNECT='TRUE';
    'VSS807':
      PIN_NUMBER='(0,0,0,0,0,0,0,0,0,0,0,0,0,0,0,0,0,0,0,0,0,0,0,0,0,0,0,0,0,0,0~
,0,0,DG1,0,0,0,0,0,0,0,0)';
      PINUSE='POWER';
      NO_LOAD_CHECK='Both';
      NO_IO_CHECK='Both';
      NO_ASSERT_CHECK='TRUE';
      NO_DIR_CHECK='TRUE';
      ALLOW_CONNECT='TRUE';
    'VSS806':
      PIN_NUMBER='(0,0,0,0,0,0,0,0,0,0,0,0,0,0,0,0,0,0,0,0,0,0,0,0,0,0,0,0,0,0,0~
,0,0,DF91,0,0,0,0,0,0,0,0)';
      PINUSE='POWER';
      NO_LOAD_CHECK='Both';
      NO_IO_CHECK='Both';
      NO_ASSERT_CHECK='TRUE';
      NO_DIR_CHECK='TRUE';
      ALLOW_CONNECT='TRUE';
    'VSS802':
      PIN_NUMBER='(0,0,0,0,0,0,0,0,0,0,0,0,0,0,0,0,0,0,0,0,0,0,0,0,0,0,0,0,0,0,0~
,0,0,DF49,0,0,0,0,0,0,0,0)';
      PINUSE='POWER';
      NO_LOAD_CHECK='Both';
      NO_IO_CHECK='Both';
      NO_ASSERT_CHECK='TRUE';
      NO_DIR_CHECK='TRUE';
      ALLOW_CONNECT='TRUE';
    'VSS799':
      PIN_NUMBER='(0,0,0,0,0,0,0,0,0,0,0,0,0,0,0,0,0,0,0,0,0,0,0,0,0,0,0,0,0,0,0~
,0,0,DF16,0,0,0,0,0,0,0,0)';
      PINUSE='POWER';
      NO_LOAD_CHECK='Both';
      NO_IO_CHECK='Both';
      NO_ASSERT_CHECK='TRUE';
      NO_DIR_CHECK='TRUE';
      ALLOW_CONNECT='TRUE';
    'VSS798':
      PIN_NUMBER='(0,0,0,0,0,0,0,0,0,0,0,0,0,0,0,0,0,0,0,0,0,0,0,0,0,0,0,0,0,0,0~
,0,0,DF12,0,0,0,0,0,0,0,0)';
      PINUSE='POWER';
      NO_LOAD_CHECK='Both';
      NO_IO_CHECK='Both';
      NO_ASSERT_CHECK='TRUE';
      NO_DIR_CHECK='TRUE';
      ALLOW_CONNECT='TRUE';
    'VSS791':
      PIN_NUMBER='(0,0,0,0,0,0,0,0,0,0,0,0,0,0,0,0,0,0,0,0,0,0,0,0,0,0,0,0,0,0,0~
,0,0,DE70,0,0,0,0,0,0,0,0)';
      PINUSE='POWER';
      NO_LOAD_CHECK='Both';
      NO_IO_CHECK='Both';
      NO_ASSERT_CHECK='TRUE';
      NO_DIR_CHECK='TRUE';
      ALLOW_CONNECT='TRUE';
    'VSS776':
      PIN_NUMBER='(0,0,0,0,0,0,0,0,0,0,0,0,0,0,0,0,0,0,0,0,0,0,0,0,0,0,0,0,0,0,0~
,0,0,DE39,0,0,0,0,0,0,0,0)';
      PINUSE='POWER';
      NO_LOAD_CHECK='Both';
      NO_IO_CHECK='Both';
      NO_ASSERT_CHECK='TRUE';
      NO_DIR_CHECK='TRUE';
      ALLOW_CONNECT='TRUE';
    'VSS753':
      PIN_NUMBER='(0,0,0,0,0,0,0,0,0,0,0,0,0,0,0,0,0,0,0,0,0,0,0,0,0,0,0,0,0,0,0~
,0,0,DD49,0,0,0,0,0,0,0,0)';
      PINUSE='POWER';
      NO_LOAD_CHECK='Both';
      NO_IO_CHECK='Both';
      NO_ASSERT_CHECK='TRUE';
      NO_DIR_CHECK='TRUE';
      ALLOW_CONNECT='TRUE';
    'VSS748':
      PIN_NUMBER='(0,0,0,0,0,0,0,0,0,0,0,0,0,0,0,0,0,0,0,0,0,0,0,0,0,0,0,0,0,0,0~
,0,0,DD16,0,0,0,0,0,0,0,0)';
      PINUSE='POWER';
      NO_LOAD_CHECK='Both';
      NO_IO_CHECK='Both';
      NO_ASSERT_CHECK='TRUE';
      NO_DIR_CHECK='TRUE';
      ALLOW_CONNECT='TRUE';
    'VSS747':
      PIN_NUMBER='(0,0,0,0,0,0,0,0,0,0,0,0,0,0,0,0,0,0,0,0,0,0,0,0,0,0,0,0,0,0,0~
,0,0,DD12,0,0,0,0,0,0,0,0)';
      PINUSE='POWER';
      NO_LOAD_CHECK='Both';
      NO_IO_CHECK='Both';
      NO_ASSERT_CHECK='TRUE';
      NO_DIR_CHECK='TRUE';
      ALLOW_CONNECT='TRUE';
    'VSS739':
      PIN_NUMBER='(0,0,0,0,0,0,0,0,0,0,0,0,0,0,0,0,0,0,0,0,0,0,0,0,0,0,0,0,0,0,0~
,0,0,DC64,0,0,0,0,0,0,0,0)';
      PINUSE='POWER';
      NO_LOAD_CHECK='Both';
      NO_IO_CHECK='Both';
      NO_ASSERT_CHECK='TRUE';
      NO_DIR_CHECK='TRUE';
      ALLOW_CONNECT='TRUE';
    'VSS738':
      PIN_NUMBER='(0,0,0,0,0,0,0,0,0,0,0,0,0,0,0,0,0,0,0,0,0,0,0,0,0,0,0,0,0,0,0~
,0,0,DC58,0,0,0,0,0,0,0,0)';
      PINUSE='POWER';
      NO_LOAD_CHECK='Both';
      NO_IO_CHECK='Both';
      NO_ASSERT_CHECK='TRUE';
      NO_DIR_CHECK='TRUE';
      ALLOW_CONNECT='TRUE';
    'VSS735':
      PIN_NUMBER='(0,0,0,0,0,0,0,0,0,0,0,0,0,0,0,0,0,0,0,0,0,0,0,0,0,0,0,0,0,0,0~
,0,0,DC52,0,0,0,0,0,0,0,0)';
      PINUSE='POWER';
      NO_LOAD_CHECK='Both';
      NO_IO_CHECK='Both';
      NO_ASSERT_CHECK='TRUE';
      NO_DIR_CHECK='TRUE';
      ALLOW_CONNECT='TRUE';
    'VSS726':
      PIN_NUMBER='(0,0,0,0,0,0,0,0,0,0,0,0,0,0,0,0,0,0,0,0,0,0,0,0,0,0,0,0,0,0,0~
,0,0,DC21,0,0,0,0,0,0,0,0)';
      PINUSE='POWER';
      NO_LOAD_CHECK='Both';
      NO_IO_CHECK='Both';
      NO_ASSERT_CHECK='TRUE';
      NO_DIR_CHECK='TRUE';
      ALLOW_CONNECT='TRUE';
    'VSS725':
      PIN_NUMBER='(0,0,0,0,0,0,0,0,0,0,0,0,0,0,0,0,0,0,0,0,0,0,0,0,0,0,0,0,0,0,0~
,0,0,DC13,0,0,0,0,0,0,0,0)';
      PINUSE='POWER';
      NO_LOAD_CHECK='Both';
      NO_IO_CHECK='Both';
      NO_ASSERT_CHECK='TRUE';
      NO_DIR_CHECK='TRUE';
      ALLOW_CONNECT='TRUE';
    'VSS724':
      PIN_NUMBER='(0,0,0,0,0,0,0,0,0,0,0,0,0,0,0,0,0,0,0,0,0,0,0,0,0,0,0,0,0,0,0~
,0,0,DC1,0,0,0,0,0,0,0,0)';
      PINUSE='POWER';
      NO_LOAD_CHECK='Both';
      NO_IO_CHECK='Both';
      NO_ASSERT_CHECK='TRUE';
      NO_DIR_CHECK='TRUE';
      ALLOW_CONNECT='TRUE';
    'VSS723':
      PIN_NUMBER='(0,0,0,0,0,0,0,0,0,0,0,0,0,0,0,0,0,0,0,0,0,0,0,0,0,0,0,0,0,0,0~
,0,0,DB91,0,0,0,0,0,0,0,0)';
      PINUSE='POWER';
      NO_LOAD_CHECK='Both';
      NO_IO_CHECK='Both';
      NO_ASSERT_CHECK='TRUE';
      NO_DIR_CHECK='TRUE';
      ALLOW_CONNECT='TRUE';
    'VSS948':
      PIN_NUMBER='(0,0,0,0,0,0,0,0,0,0,0,0,0,0,0,0,0,0,0,0,0,0,0,0,0,0,0,0,0,0,0~
,0,0,0,DB87,0,0,0,0,0,0,0)';
      PINUSE='POWER';
      NO_LOAD_CHECK='Both';
      NO_IO_CHECK='Both';
      NO_ASSERT_CHECK='TRUE';
      NO_DIR_CHECK='TRUE';
      ALLOW_CONNECT='TRUE';
    'VSS947':
      PIN_NUMBER='(0,0,0,0,0,0,0,0,0,0,0,0,0,0,0,0,0,0,0,0,0,0,0,0,0,0,0,0,0,0,0~
,0,0,0,DB8,0,0,0,0,0,0,0)';
      PINUSE='POWER';
      NO_LOAD_CHECK='Both';
      NO_IO_CHECK='Both';
      NO_ASSERT_CHECK='TRUE';
      NO_DIR_CHECK='TRUE';
      ALLOW_CONNECT='TRUE';
    'VSS946':
      PIN_NUMBER='(0,0,0,0,0,0,0,0,0,0,0,0,0,0,0,0,0,0,0,0,0,0,0,0,0,0,0,0,0,0,0~
,0,0,0,DB77,0,0,0,0,0,0,0)';
      PINUSE='POWER';
      NO_LOAD_CHECK='Both';
      NO_IO_CHECK='Both';
      NO_ASSERT_CHECK='TRUE';
      NO_DIR_CHECK='TRUE';
      ALLOW_CONNECT='TRUE';
    'VSS944':
      PIN_NUMBER='(0,0,0,0,0,0,0,0,0,0,0,0,0,0,0,0,0,0,0,0,0,0,0,0,0,0,0,0,0,0,0~
,0,0,0,DB71,0,0,0,0,0,0,0)';
      PINUSE='POWER';
      NO_LOAD_CHECK='Both';
      NO_IO_CHECK='Both';
      NO_ASSERT_CHECK='TRUE';
      NO_DIR_CHECK='TRUE';
      ALLOW_CONNECT='TRUE';
    'VSS943':
      PIN_NUMBER='(0,0,0,0,0,0,0,0,0,0,0,0,0,0,0,0,0,0,0,0,0,0,0,0,0,0,0,0,0,0,0~
,0,0,0,DB65,0,0,0,0,0,0,0)';
      PINUSE='POWER';
      NO_LOAD_CHECK='Both';
      NO_IO_CHECK='Both';
      NO_ASSERT_CHECK='TRUE';
      NO_DIR_CHECK='TRUE';
      ALLOW_CONNECT='TRUE';
    'VSS942':
      PIN_NUMBER='(0,0,0,0,0,0,0,0,0,0,0,0,0,0,0,0,0,0,0,0,0,0,0,0,0,0,0,0,0,0,0~
,0,0,0,DB57,0,0,0,0,0,0,0)';
      PINUSE='POWER';
      NO_LOAD_CHECK='Both';
      NO_IO_CHECK='Both';
      NO_ASSERT_CHECK='TRUE';
      NO_DIR_CHECK='TRUE';
      ALLOW_CONNECT='TRUE';
    'VSS941':
      PIN_NUMBER='(0,0,0,0,0,0,0,0,0,0,0,0,0,0,0,0,0,0,0,0,0,0,0,0,0,0,0,0,0,0,0~
,0,0,0,DB47,0,0,0,0,0,0,0)';
      PINUSE='POWER';
      NO_LOAD_CHECK='Both';
      NO_IO_CHECK='Both';
      NO_ASSERT_CHECK='TRUE';
      NO_DIR_CHECK='TRUE';
      ALLOW_CONNECT='TRUE';
    'VSS940':
      PIN_NUMBER='(0,0,0,0,0,0,0,0,0,0,0,0,0,0,0,0,0,0,0,0,0,0,0,0,0,0,0,0,0,0,0~
,0,0,0,DB40,0,0,0,0,0,0,0)';
      PINUSE='POWER';
      NO_LOAD_CHECK='Both';
      NO_IO_CHECK='Both';
      NO_ASSERT_CHECK='TRUE';
      NO_DIR_CHECK='TRUE';
      ALLOW_CONNECT='TRUE';
    'VSS939':
      PIN_NUMBER='(0,0,0,0,0,0,0,0,0,0,0,0,0,0,0,0,0,0,0,0,0,0,0,0,0,0,0,0,0,0,0~
,0,0,0,DB4,0,0,0,0,0,0,0)';
      PINUSE='POWER';
      NO_LOAD_CHECK='Both';
      NO_IO_CHECK='Both';
      NO_ASSERT_CHECK='TRUE';
      NO_DIR_CHECK='TRUE';
      ALLOW_CONNECT='TRUE';
    'VSS938':
      PIN_NUMBER='(0,0,0,0,0,0,0,0,0,0,0,0,0,0,0,0,0,0,0,0,0,0,0,0,0,0,0,0,0,0,0~
,0,0,0,DB38,0,0,0,0,0,0,0)';
      PINUSE='POWER';
      NO_LOAD_CHECK='Both';
      NO_IO_CHECK='Both';
      NO_ASSERT_CHECK='TRUE';
      NO_DIR_CHECK='TRUE';
      ALLOW_CONNECT='TRUE';
    'VSS937':
      PIN_NUMBER='(0,0,0,0,0,0,0,0,0,0,0,0,0,0,0,0,0,0,0,0,0,0,0,0,0,0,0,0,0,0,0~
,0,0,0,DB32,0,0,0,0,0,0,0)';
      PINUSE='POWER';
      NO_LOAD_CHECK='Both';
      NO_IO_CHECK='Both';
      NO_ASSERT_CHECK='TRUE';
      NO_DIR_CHECK='TRUE';
      ALLOW_CONNECT='TRUE';
    'VSS936':
      PIN_NUMBER='(0,0,0,0,0,0,0,0,0,0,0,0,0,0,0,0,0,0,0,0,0,0,0,0,0,0,0,0,0,0,0~
,0,0,0,DB28,0,0,0,0,0,0,0)';
      PINUSE='POWER';
      NO_LOAD_CHECK='Both';
      NO_IO_CHECK='Both';
      NO_ASSERT_CHECK='TRUE';
      NO_DIR_CHECK='TRUE';
      ALLOW_CONNECT='TRUE';
    'VSS935':
      PIN_NUMBER='(0,0,0,0,0,0,0,0,0,0,0,0,0,0,0,0,0,0,0,0,0,0,0,0,0,0,0,0,0,0,0~
,0,0,0,DB22,0,0,0,0,0,0,0)';
      PINUSE='POWER';
      NO_LOAD_CHECK='Both';
      NO_IO_CHECK='Both';
      NO_ASSERT_CHECK='TRUE';
      NO_DIR_CHECK='TRUE';
      ALLOW_CONNECT='TRUE';
    'VSS933':
      PIN_NUMBER='(0,0,0,0,0,0,0,0,0,0,0,0,0,0,0,0,0,0,0,0,0,0,0,0,0,0,0,0,0,0,0~
,0,0,0,DB12,0,0,0,0,0,0,0)';
      PINUSE='POWER';
      NO_LOAD_CHECK='Both';
      NO_IO_CHECK='Both';
      NO_ASSERT_CHECK='TRUE';
      NO_DIR_CHECK='TRUE';
      ALLOW_CONNECT='TRUE';
    'VSS932':
      PIN_NUMBER='(0,0,0,0,0,0,0,0,0,0,0,0,0,0,0,0,0,0,0,0,0,0,0,0,0,0,0,0,0,0,0~
,0,0,0,DA88,0,0,0,0,0,0,0)';
      PINUSE='POWER';
      NO_LOAD_CHECK='Both';
      NO_IO_CHECK='Both';
      NO_ASSERT_CHECK='TRUE';
      NO_DIR_CHECK='TRUE';
      ALLOW_CONNECT='TRUE';
    'VSS931':
      PIN_NUMBER='(0,0,0,0,0,0,0,0,0,0,0,0,0,0,0,0,0,0,0,0,0,0,0,0,0,0,0,0,0,0,0~
,0,0,0,DA84,0,0,0,0,0,0,0)';
      PINUSE='POWER';
      NO_LOAD_CHECK='Both';
      NO_IO_CHECK='Both';
      NO_ASSERT_CHECK='TRUE';
      NO_DIR_CHECK='TRUE';
      ALLOW_CONNECT='TRUE';
    'VSS930':
      PIN_NUMBER='(0,0,0,0,0,0,0,0,0,0,0,0,0,0,0,0,0,0,0,0,0,0,0,0,0,0,0,0,0,0,0~
,0,0,0,DA82,0,0,0,0,0,0,0)';
      PINUSE='POWER';
      NO_LOAD_CHECK='Both';
      NO_IO_CHECK='Both';
      NO_ASSERT_CHECK='TRUE';
      NO_DIR_CHECK='TRUE';
      ALLOW_CONNECT='TRUE';
    'VSS929':
      PIN_NUMBER='(0,0,0,0,0,0,0,0,0,0,0,0,0,0,0,0,0,0,0,0,0,0,0,0,0,0,0,0,0,0,0~
,0,0,0,DA80,0,0,0,0,0,0,0)';
      PINUSE='POWER';
      NO_LOAD_CHECK='Both';
      NO_IO_CHECK='Both';
      NO_ASSERT_CHECK='TRUE';
      NO_DIR_CHECK='TRUE';
      ALLOW_CONNECT='TRUE';
    'VSS928':
      PIN_NUMBER='(0,0,0,0,0,0,0,0,0,0,0,0,0,0,0,0,0,0,0,0,0,0,0,0,0,0,0,0,0,0,0~
,0,0,0,DA74,0,0,0,0,0,0,0)';
      PINUSE='POWER';
      NO_LOAD_CHECK='Both';
      NO_IO_CHECK='Both';
      NO_ASSERT_CHECK='TRUE';
      NO_DIR_CHECK='TRUE';
      ALLOW_CONNECT='TRUE';
    'VSS927':
      PIN_NUMBER='(0,0,0,0,0,0,0,0,0,0,0,0,0,0,0,0,0,0,0,0,0,0,0,0,0,0,0,0,0,0,0~
,0,0,0,DA72,0,0,0,0,0,0,0)';
      PINUSE='POWER';
      NO_LOAD_CHECK='Both';
      NO_IO_CHECK='Both';
      NO_ASSERT_CHECK='TRUE';
      NO_DIR_CHECK='TRUE';
      ALLOW_CONNECT='TRUE';
    'VSS926':
      PIN_NUMBER='(0,0,0,0,0,0,0,0,0,0,0,0,0,0,0,0,0,0,0,0,0,0,0,0,0,0,0,0,0,0,0~
,0,0,0,DA66,0,0,0,0,0,0,0)';
      PINUSE='POWER';
      NO_LOAD_CHECK='Both';
      NO_IO_CHECK='Both';
      NO_ASSERT_CHECK='TRUE';
      NO_DIR_CHECK='TRUE';
      ALLOW_CONNECT='TRUE';
    'VSS925':
      PIN_NUMBER='(0,0,0,0,0,0,0,0,0,0,0,0,0,0,0,0,0,0,0,0,0,0,0,0,0,0,0,0,0,0,0~
,0,0,0,DA62,0,0,0,0,0,0,0)';
      PINUSE='POWER';
      NO_LOAD_CHECK='Both';
      NO_IO_CHECK='Both';
      NO_ASSERT_CHECK='TRUE';
      NO_DIR_CHECK='TRUE';
      ALLOW_CONNECT='TRUE';
    'VSS924':
      PIN_NUMBER='(0,0,0,0,0,0,0,0,0,0,0,0,0,0,0,0,0,0,0,0,0,0,0,0,0,0,0,0,0,0,0~
,0,0,0,DA60,0,0,0,0,0,0,0)';
      PINUSE='POWER';
      NO_LOAD_CHECK='Both';
      NO_IO_CHECK='Both';
      NO_ASSERT_CHECK='TRUE';
      NO_DIR_CHECK='TRUE';
      ALLOW_CONNECT='TRUE';
    'VSS923':
      PIN_NUMBER='(0,0,0,0,0,0,0,0,0,0,0,0,0,0,0,0,0,0,0,0,0,0,0,0,0,0,0,0,0,0,0~
,0,0,0,DA58,0,0,0,0,0,0,0)';
      PINUSE='POWER';
      NO_LOAD_CHECK='Both';
      NO_IO_CHECK='Both';
      NO_ASSERT_CHECK='TRUE';
      NO_DIR_CHECK='TRUE';
      ALLOW_CONNECT='TRUE';
    'VSS922':
      PIN_NUMBER='(0,0,0,0,0,0,0,0,0,0,0,0,0,0,0,0,0,0,0,0,0,0,0,0,0,0,0,0,0,0,0~
,0,0,0,DA56,0,0,0,0,0,0,0)';
      PINUSE='POWER';
      NO_LOAD_CHECK='Both';
      NO_IO_CHECK='Both';
      NO_ASSERT_CHECK='TRUE';
      NO_DIR_CHECK='TRUE';
      ALLOW_CONNECT='TRUE';
    'VSS921':
      PIN_NUMBER='(0,0,0,0,0,0,0,0,0,0,0,0,0,0,0,0,0,0,0,0,0,0,0,0,0,0,0,0,0,0,0~
,0,0,0,DA54,0,0,0,0,0,0,0)';
      PINUSE='POWER';
      NO_LOAD_CHECK='Both';
      NO_IO_CHECK='Both';
      NO_ASSERT_CHECK='TRUE';
      NO_DIR_CHECK='TRUE';
      ALLOW_CONNECT='TRUE';
    'VSS920':
      PIN_NUMBER='(0,0,0,0,0,0,0,0,0,0,0,0,0,0,0,0,0,0,0,0,0,0,0,0,0,0,0,0,0,0,0~
,0,0,0,DA50,0,0,0,0,0,0,0)';
      PINUSE='POWER';
      NO_LOAD_CHECK='Both';
      NO_IO_CHECK='Both';
      NO_ASSERT_CHECK='TRUE';
      NO_DIR_CHECK='TRUE';
      ALLOW_CONNECT='TRUE';
    'VSS919':
      PIN_NUMBER='(0,0,0,0,0,0,0,0,0,0,0,0,0,0,0,0,0,0,0,0,0,0,0,0,0,0,0,0,0,0,0~
,0,0,0,DA48,0,0,0,0,0,0,0)';
      PINUSE='POWER';
      NO_LOAD_CHECK='Both';
      NO_IO_CHECK='Both';
      NO_ASSERT_CHECK='TRUE';
      NO_DIR_CHECK='TRUE';
      ALLOW_CONNECT='TRUE';
    'VSS918':
      PIN_NUMBER='(0,0,0,0,0,0,0,0,0,0,0,0,0,0,0,0,0,0,0,0,0,0,0,0,0,0,0,0,0,0,0~
,0,0,0,DA41,0,0,0,0,0,0,0)';
      PINUSE='POWER';
      NO_LOAD_CHECK='Both';
      NO_IO_CHECK='Both';
      NO_ASSERT_CHECK='TRUE';
      NO_DIR_CHECK='TRUE';
      ALLOW_CONNECT='TRUE';
    'VSS917':
      PIN_NUMBER='(0,0,0,0,0,0,0,0,0,0,0,0,0,0,0,0,0,0,0,0,0,0,0,0,0,0,0,0,0,0,0~
,0,0,0,DA37,0,0,0,0,0,0,0)';
      PINUSE='POWER';
      NO_LOAD_CHECK='Both';
      NO_IO_CHECK='Both';
      NO_ASSERT_CHECK='TRUE';
      NO_DIR_CHECK='TRUE';
      ALLOW_CONNECT='TRUE';
    'VSS916':
      PIN_NUMBER='(0,0,0,0,0,0,0,0,0,0,0,0,0,0,0,0,0,0,0,0,0,0,0,0,0,0,0,0,0,0,0~
,0,0,0,DA35,0,0,0,0,0,0,0)';
      PINUSE='POWER';
      NO_LOAD_CHECK='Both';
      NO_IO_CHECK='Both';
      NO_ASSERT_CHECK='TRUE';
      NO_DIR_CHECK='TRUE';
      ALLOW_CONNECT='TRUE';
    'VSS915':
      PIN_NUMBER='(0,0,0,0,0,0,0,0,0,0,0,0,0,0,0,0,0,0,0,0,0,0,0,0,0,0,0,0,0,0,0~
,0,0,0,DA33,0,0,0,0,0,0,0)';
      PINUSE='POWER';
      NO_LOAD_CHECK='Both';
      NO_IO_CHECK='Both';
      NO_ASSERT_CHECK='TRUE';
      NO_DIR_CHECK='TRUE';
      ALLOW_CONNECT='TRUE';
    'VSS914':
      PIN_NUMBER='(0,0,0,0,0,0,0,0,0,0,0,0,0,0,0,0,0,0,0,0,0,0,0,0,0,0,0,0,0,0,0~
,0,0,0,DA31,0,0,0,0,0,0,0)';
      PINUSE='POWER';
      NO_LOAD_CHECK='Both';
      NO_IO_CHECK='Both';
      NO_ASSERT_CHECK='TRUE';
      NO_DIR_CHECK='TRUE';
      ALLOW_CONNECT='TRUE';
    'VSS913':
      PIN_NUMBER='(0,0,0,0,0,0,0,0,0,0,0,0,0,0,0,0,0,0,0,0,0,0,0,0,0,0,0,0,0,0,0~
,0,0,0,DA29,0,0,0,0,0,0,0)';
      PINUSE='POWER';
      NO_LOAD_CHECK='Both';
      NO_IO_CHECK='Both';
      NO_ASSERT_CHECK='TRUE';
      NO_DIR_CHECK='TRUE';
      ALLOW_CONNECT='TRUE';
    'VSS912':
      PIN_NUMBER='(0,0,0,0,0,0,0,0,0,0,0,0,0,0,0,0,0,0,0,0,0,0,0,0,0,0,0,0,0,0,0~
,0,0,0,DA25,0,0,0,0,0,0,0)';
      PINUSE='POWER';
      NO_LOAD_CHECK='Both';
      NO_IO_CHECK='Both';
      NO_ASSERT_CHECK='TRUE';
      NO_DIR_CHECK='TRUE';
      ALLOW_CONNECT='TRUE';
    'VSS911':
      PIN_NUMBER='(0,0,0,0,0,0,0,0,0,0,0,0,0,0,0,0,0,0,0,0,0,0,0,0,0,0,0,0,0,0,0~
,0,0,0,DA23,0,0,0,0,0,0,0)';
      PINUSE='POWER';
      NO_LOAD_CHECK='Both';
      NO_IO_CHECK='Both';
      NO_ASSERT_CHECK='TRUE';
      NO_DIR_CHECK='TRUE';
      ALLOW_CONNECT='TRUE';
    'VSS910':
      PIN_NUMBER='(0,0,0,0,0,0,0,0,0,0,0,0,0,0,0,0,0,0,0,0,0,0,0,0,0,0,0,0,0,0,0~
,0,0,0,DA19,0,0,0,0,0,0,0)';
      PINUSE='POWER';
      NO_LOAD_CHECK='Both';
      NO_IO_CHECK='Both';
      NO_ASSERT_CHECK='TRUE';
      NO_DIR_CHECK='TRUE';
      ALLOW_CONNECT='TRUE';
    'VSS863':
      PIN_NUMBER='(0,0,0,0,0,0,0,0,0,0,0,0,0,0,0,0,0,0,0,0,0,0,0,0,0,0,0,0,0,0,0~
,0,0,0,CY83,0,0,0,0,0,0,0)';
      PINUSE='POWER';
      NO_LOAD_CHECK='Both';
      NO_IO_CHECK='Both';
      NO_ASSERT_CHECK='TRUE';
      NO_DIR_CHECK='TRUE';
      ALLOW_CONNECT='TRUE';
    'VSS862':
      PIN_NUMBER='(0,0,0,0,0,0,0,0,0,0,0,0,0,0,0,0,0,0,0,0,0,0,0,0,0,0,0,0,0,0,0~
,0,0,0,CY81,0,0,0,0,0,0,0)';
      PINUSE='POWER';
      NO_LOAD_CHECK='Both';
      NO_IO_CHECK='Both';
      NO_ASSERT_CHECK='TRUE';
      NO_DIR_CHECK='TRUE';
      ALLOW_CONNECT='TRUE';
    'VSS860':
      PIN_NUMBER='(0,0,0,0,0,0,0,0,0,0,0,0,0,0,0,0,0,0,0,0,0,0,0,0,0,0,0,0,0,0,0~
,0,0,0,CY8,0,0,0,0,0,0,0)';
      PINUSE='POWER';
      NO_LOAD_CHECK='Both';
      NO_IO_CHECK='Both';
      NO_ASSERT_CHECK='TRUE';
      NO_DIR_CHECK='TRUE';
      ALLOW_CONNECT='TRUE';
    'VSS859':
      PIN_NUMBER='(0,0,0,0,0,0,0,0,0,0,0,0,0,0,0,0,0,0,0,0,0,0,0,0,0,0,0,0,0,0,0~
,0,0,0,CY77,0,0,0,0,0,0,0)';
      PINUSE='POWER';
      NO_LOAD_CHECK='Both';
      NO_IO_CHECK='Both';
      NO_ASSERT_CHECK='TRUE';
      NO_DIR_CHECK='TRUE';
      ALLOW_CONNECT='TRUE';
    'VSS858':
      PIN_NUMBER='(0,0,0,0,0,0,0,0,0,0,0,0,0,0,0,0,0,0,0,0,0,0,0,0,0,0,0,0,0,0,0~
,0,0,0,CY73,0,0,0,0,0,0,0)';
      PINUSE='POWER';
      NO_LOAD_CHECK='Both';
      NO_IO_CHECK='Both';
      NO_ASSERT_CHECK='TRUE';
      NO_DIR_CHECK='TRUE';
      ALLOW_CONNECT='TRUE';
    'VSS856':
      PIN_NUMBER='(0,0,0,0,0,0,0,0,0,0,0,0,0,0,0,0,0,0,0,0,0,0,0,0,0,0,0,0,0,0,0~
,0,0,0,CY63,0,0,0,0,0,0,0)';
      PINUSE='POWER';
      NO_LOAD_CHECK='Both';
      NO_IO_CHECK='Both';
      NO_ASSERT_CHECK='TRUE';
      NO_DIR_CHECK='TRUE';
      ALLOW_CONNECT='TRUE';
    'VSS855':
      PIN_NUMBER='(0,0,0,0,0,0,0,0,0,0,0,0,0,0,0,0,0,0,0,0,0,0,0,0,0,0,0,0,0,0,0~
,0,0,0,CY30,0,0,0,0,0,0,0)';
      PINUSE='POWER';
      NO_LOAD_CHECK='Both';
      NO_IO_CHECK='Both';
      NO_ASSERT_CHECK='TRUE';
      NO_DIR_CHECK='TRUE';
      ALLOW_CONNECT='TRUE';
    'VSS854':
      PIN_NUMBER='(0,0,0,0,0,0,0,0,0,0,0,0,0,0,0,0,0,0,0,0,0,0,0,0,0,0,0,0,0,0,0~
,0,0,0,CY26,0,0,0,0,0,0,0)';
      PINUSE='POWER';
      NO_LOAD_CHECK='Both';
      NO_IO_CHECK='Both';
      NO_ASSERT_CHECK='TRUE';
      NO_DIR_CHECK='TRUE';
      ALLOW_CONNECT='TRUE';
    'VSS853':
      PIN_NUMBER='(0,0,0,0,0,0,0,0,0,0,0,0,0,0,0,0,0,0,0,0,0,0,0,0,0,0,0,0,0,0,0~
,0,0,0,CY18,0,0,0,0,0,0,0)';
      PINUSE='POWER';
      NO_LOAD_CHECK='Both';
      NO_IO_CHECK='Both';
      NO_ASSERT_CHECK='TRUE';
      NO_DIR_CHECK='TRUE';
      ALLOW_CONNECT='TRUE';
    'VSS852':
      PIN_NUMBER='(0,0,0,0,0,0,0,0,0,0,0,0,0,0,0,0,0,0,0,0,0,0,0,0,0,0,0,0,0,0,0~
,0,0,0,CY16,0,0,0,0,0,0,0)';
      PINUSE='POWER';
      NO_LOAD_CHECK='Both';
      NO_IO_CHECK='Both';
      NO_ASSERT_CHECK='TRUE';
      NO_DIR_CHECK='TRUE';
      ALLOW_CONNECT='TRUE';
    'VSS851':
      PIN_NUMBER='(0,0,0,0,0,0,0,0,0,0,0,0,0,0,0,0,0,0,0,0,0,0,0,0,0,0,0,0,0,0,0~
,0,0,0,CY12,0,0,0,0,0,0,0)';
      PINUSE='POWER';
      NO_LOAD_CHECK='Both';
      NO_IO_CHECK='Both';
      NO_ASSERT_CHECK='TRUE';
      NO_DIR_CHECK='TRUE';
      ALLOW_CONNECT='TRUE';
    'VSS850':
      PIN_NUMBER='(0,0,0,0,0,0,0,0,0,0,0,0,0,0,0,0,0,0,0,0,0,0,0,0,0,0,0,0,0,0,0~
,0,0,0,CW9,0,0,0,0,0,0,0)';
      PINUSE='POWER';
      NO_LOAD_CHECK='Both';
      NO_IO_CHECK='Both';
      NO_ASSERT_CHECK='TRUE';
      NO_DIR_CHECK='TRUE';
      ALLOW_CONNECT='TRUE';
    'VSS848':
      PIN_NUMBER='(0,0,0,0,0,0,0,0,0,0,0,0,0,0,0,0,0,0,0,0,0,0,0,0,0,0,0,0,0,0,0~
,0,0,0,CW88,0,0,0,0,0,0,0)';
      PINUSE='POWER';
      NO_LOAD_CHECK='Both';
      NO_IO_CHECK='Both';
      NO_ASSERT_CHECK='TRUE';
      NO_DIR_CHECK='TRUE';
      ALLOW_CONNECT='TRUE';
    'VSS846':
      PIN_NUMBER='(0,0,0,0,0,0,0,0,0,0,0,0,0,0,0,0,0,0,0,0,0,0,0,0,0,0,0,0,0,0,0~
,0,0,0,CW84,0,0,0,0,0,0,0)';
      PINUSE='POWER';
      NO_LOAD_CHECK='Both';
      NO_IO_CHECK='Both';
      NO_ASSERT_CHECK='TRUE';
      NO_DIR_CHECK='TRUE';
      ALLOW_CONNECT='TRUE';
    'VSS843':
      PIN_NUMBER='(0,0,0,0,0,0,0,0,0,0,0,0,0,0,0,0,0,0,0,0,0,0,0,0,0,0,0,0,0,0,0~
,0,0,0,CW78,0,0,0,0,0,0,0)';
      PINUSE='POWER';
      NO_LOAD_CHECK='Both';
      NO_IO_CHECK='Both';
      NO_ASSERT_CHECK='TRUE';
      NO_DIR_CHECK='TRUE';
      ALLOW_CONNECT='TRUE';
    'VSS840':
      PIN_NUMBER='(0,0,0,0,0,0,0,0,0,0,0,0,0,0,0,0,0,0,0,0,0,0,0,0,0,0,0,0,0,0,0~
,0,0,0,CW72,0,0,0,0,0,0,0)';
      PINUSE='POWER';
      NO_LOAD_CHECK='Both';
      NO_IO_CHECK='Both';
      NO_ASSERT_CHECK='TRUE';
      NO_DIR_CHECK='TRUE';
      ALLOW_CONNECT='TRUE';
    'VSS838':
      PIN_NUMBER='(0,0,0,0,0,0,0,0,0,0,0,0,0,0,0,0,0,0,0,0,0,0,0,0,0,0,0,0,0,0,0~
,0,0,0,CW5,0,0,0,0,0,0,0)';
      PINUSE='POWER';
      NO_LOAD_CHECK='Both';
      NO_IO_CHECK='Both';
      NO_ASSERT_CHECK='TRUE';
      NO_DIR_CHECK='TRUE';
      ALLOW_CONNECT='TRUE';
    'VSS837':
      PIN_NUMBER='(0,0,0,0,0,0,0,0,0,0,0,0,0,0,0,0,0,0,0,0,0,0,0,0,0,0,0,0,0,0,0~
,0,0,0,CW17,0,0,0,0,0,0,0)';
      PINUSE='POWER';
      NO_LOAD_CHECK='Both';
      NO_IO_CHECK='Both';
      NO_ASSERT_CHECK='TRUE';
      NO_DIR_CHECK='TRUE';
      ALLOW_CONNECT='TRUE';
    'VSS836':
      PIN_NUMBER='(0,0,0,0,0,0,0,0,0,0,0,0,0,0,0,0,0,0,0,0,0,0,0,0,0,0,0,0,0,0,0~
,0,0,0,CW13,0,0,0,0,0,0,0)';
      PINUSE='POWER';
      NO_LOAD_CHECK='Both';
      NO_IO_CHECK='Both';
      NO_ASSERT_CHECK='TRUE';
      NO_DIR_CHECK='TRUE';
      ALLOW_CONNECT='TRUE';
    'VSS834':
      PIN_NUMBER='(0,0,0,0,0,0,0,0,0,0,0,0,0,0,0,0,0,0,0,0,0,0,0,0,0,0,0,0,0,0,0~
,0,0,0,CW1,0,0,0,0,0,0,0)';
      PINUSE='POWER';
      NO_LOAD_CHECK='Both';
      NO_IO_CHECK='Both';
      NO_ASSERT_CHECK='TRUE';
      NO_DIR_CHECK='TRUE';
      ALLOW_CONNECT='TRUE';
    'VSS833':
      PIN_NUMBER='(0,0,0,0,0,0,0,0,0,0,0,0,0,0,0,0,0,0,0,0,0,0,0,0,0,0,0,0,0,0,0~
,0,0,0,CV91,0,0,0,0,0,0,0)';
      PINUSE='POWER';
      NO_LOAD_CHECK='Both';
      NO_IO_CHECK='Both';
      NO_ASSERT_CHECK='TRUE';
      NO_DIR_CHECK='TRUE';
      ALLOW_CONNECT='TRUE';
    'VSS831':
      PIN_NUMBER='(0,0,0,0,0,0,0,0,0,0,0,0,0,0,0,0,0,0,0,0,0,0,0,0,0,0,0,0,0,0,0~
,0,0,0,CV87,0,0,0,0,0,0,0)';
      PINUSE='POWER';
      NO_LOAD_CHECK='Both';
      NO_IO_CHECK='Both';
      NO_ASSERT_CHECK='TRUE';
      NO_DIR_CHECK='TRUE';
      ALLOW_CONNECT='TRUE';
    'VSS828':
      PIN_NUMBER='(0,0,0,0,0,0,0,0,0,0,0,0,0,0,0,0,0,0,0,0,0,0,0,0,0,0,0,0,0,0,0~
,0,0,0,CV83,0,0,0,0,0,0,0)';
      PINUSE='POWER';
      NO_LOAD_CHECK='Both';
      NO_IO_CHECK='Both';
      NO_ASSERT_CHECK='TRUE';
      NO_DIR_CHECK='TRUE';
      ALLOW_CONNECT='TRUE';
    'VSS827':
      PIN_NUMBER='(0,0,0,0,0,0,0,0,0,0,0,0,0,0,0,0,0,0,0,0,0,0,0,0,0,0,0,0,0,0,0~
,0,0,0,CV8,0,0,0,0,0,0,0)';
      PINUSE='POWER';
      NO_LOAD_CHECK='Both';
      NO_IO_CHECK='Both';
      NO_ASSERT_CHECK='TRUE';
      NO_DIR_CHECK='TRUE';
      ALLOW_CONNECT='TRUE';
    'VSS826':
      PIN_NUMBER='(0,0,0,0,0,0,0,0,0,0,0,0,0,0,0,0,0,0,0,0,0,0,0,0,0,0,0,0,0,0,0~
,0,0,0,CV75,0,0,0,0,0,0,0)';
      PINUSE='POWER';
      NO_LOAD_CHECK='Both';
      NO_IO_CHECK='Both';
      NO_ASSERT_CHECK='TRUE';
      NO_DIR_CHECK='TRUE';
      ALLOW_CONNECT='TRUE';
    'VSS825':
      PIN_NUMBER='(0,0,0,0,0,0,0,0,0,0,0,0,0,0,0,0,0,0,0,0,0,0,0,0,0,0,0,0,0,0,0~
,0,0,0,CV4,0,0,0,0,0,0,0)';
      PINUSE='POWER';
      NO_LOAD_CHECK='Both';
      NO_IO_CHECK='Both';
      NO_ASSERT_CHECK='TRUE';
      NO_DIR_CHECK='TRUE';
      ALLOW_CONNECT='TRUE';
    'VSS824':
      PIN_NUMBER='(0,0,0,0,0,0,0,0,0,0,0,0,0,0,0,0,0,0,0,0,0,0,0,0,0,0,0,0,0,0,0~
,0,0,0,CV12,0,0,0,0,0,0,0)';
      PINUSE='POWER';
      NO_LOAD_CHECK='Both';
      NO_IO_CHECK='Both';
      NO_ASSERT_CHECK='TRUE';
      NO_DIR_CHECK='TRUE';
      ALLOW_CONNECT='TRUE';
    'VSS823':
      PIN_NUMBER='(0,0,0,0,0,0,0,0,0,0,0,0,0,0,0,0,0,0,0,0,0,0,0,0,0,0,0,0,0,0,0~
,0,0,0,CU88,0,0,0,0,0,0,0)';
      PINUSE='POWER';
      NO_LOAD_CHECK='Both';
      NO_IO_CHECK='Both';
      NO_ASSERT_CHECK='TRUE';
      NO_DIR_CHECK='TRUE';
      ALLOW_CONNECT='TRUE';
    'VSS822':
      PIN_NUMBER='(0,0,0,0,0,0,0,0,0,0,0,0,0,0,0,0,0,0,0,0,0,0,0,0,0,0,0,0,0,0,0~
,0,0,0,CU84,0,0,0,0,0,0,0)';
      PINUSE='POWER';
      NO_LOAD_CHECK='Both';
      NO_IO_CHECK='Both';
      NO_ASSERT_CHECK='TRUE';
      NO_DIR_CHECK='TRUE';
      ALLOW_CONNECT='TRUE';
    'VSS819':
      PIN_NUMBER='(0,0,0,0,0,0,0,0,0,0,0,0,0,0,0,0,0,0,0,0,0,0,0,0,0,0,0,0,0,0,0~
,0,0,0,CU68,0,0,0,0,0,0,0)';
      PINUSE='POWER';
      NO_LOAD_CHECK='Both';
      NO_IO_CHECK='Both';
      NO_ASSERT_CHECK='TRUE';
      NO_DIR_CHECK='TRUE';
      ALLOW_CONNECT='TRUE';
    'VSS818':
      PIN_NUMBER='(0,0,0,0,0,0,0,0,0,0,0,0,0,0,0,0,0,0,0,0,0,0,0,0,0,0,0,0,0,0,0~
,0,0,0,CU66,0,0,0,0,0,0,0)';
      PINUSE='POWER';
      NO_LOAD_CHECK='Both';
      NO_IO_CHECK='Both';
      NO_ASSERT_CHECK='TRUE';
      NO_DIR_CHECK='TRUE';
      ALLOW_CONNECT='TRUE';
    'VSS816':
      PIN_NUMBER='(0,0,0,0,0,0,0,0,0,0,0,0,0,0,0,0,0,0,0,0,0,0,0,0,0,0,0,0,0,0,0~
,0,0,0,CU60,0,0,0,0,0,0,0)';
      PINUSE='POWER';
      NO_LOAD_CHECK='Both';
      NO_IO_CHECK='Both';
      NO_ASSERT_CHECK='TRUE';
      NO_DIR_CHECK='TRUE';
      ALLOW_CONNECT='TRUE';
    'VSS815':
      PIN_NUMBER='(0,0,0,0,0,0,0,0,0,0,0,0,0,0,0,0,0,0,0,0,0,0,0,0,0,0,0,0,0,0,0~
,0,0,0,CU23,0,0,0,0,0,0,0)';
      PINUSE='POWER';
      NO_LOAD_CHECK='Both';
      NO_IO_CHECK='Both';
      NO_ASSERT_CHECK='TRUE';
      NO_DIR_CHECK='TRUE';
      ALLOW_CONNECT='TRUE';
    'VSS814':
      PIN_NUMBER='(0,0,0,0,0,0,0,0,0,0,0,0,0,0,0,0,0,0,0,0,0,0,0,0,0,0,0,0,0,0,0~
,0,0,0,CU21,0,0,0,0,0,0,0)';
      PINUSE='POWER';
      NO_LOAD_CHECK='Both';
      NO_IO_CHECK='Both';
      NO_ASSERT_CHECK='TRUE';
      NO_DIR_CHECK='TRUE';
      ALLOW_CONNECT='TRUE';
    'VSS813':
      PIN_NUMBER='(0,0,0,0,0,0,0,0,0,0,0,0,0,0,0,0,0,0,0,0,0,0,0,0,0,0,0,0,0,0,0~
,0,0,0,CU19,0,0,0,0,0,0,0)';
      PINUSE='POWER';
      NO_LOAD_CHECK='Both';
      NO_IO_CHECK='Both';
      NO_ASSERT_CHECK='TRUE';
      NO_DIR_CHECK='TRUE';
      ALLOW_CONNECT='TRUE';
    'VSS812':
      PIN_NUMBER='(0,0,0,0,0,0,0,0,0,0,0,0,0,0,0,0,0,0,0,0,0,0,0,0,0,0,0,0,0,0,0~
,0,0,0,CT81,0,0,0,0,0,0,0)';
      PINUSE='POWER';
      NO_LOAD_CHECK='Both';
      NO_IO_CHECK='Both';
      NO_ASSERT_CHECK='TRUE';
      NO_DIR_CHECK='TRUE';
      ALLOW_CONNECT='TRUE';
    'VSS811':
      PIN_NUMBER='(0,0,0,0,0,0,0,0,0,0,0,0,0,0,0,0,0,0,0,0,0,0,0,0,0,0,0,0,0,0,0~
,0,0,0,CT73,0,0,0,0,0,0,0)';
      PINUSE='POWER';
      NO_LOAD_CHECK='Both';
      NO_IO_CHECK='Both';
      NO_ASSERT_CHECK='TRUE';
      NO_DIR_CHECK='TRUE';
      ALLOW_CONNECT='TRUE';
    'VSS810':
      PIN_NUMBER='(0,0,0,0,0,0,0,0,0,0,0,0,0,0,0,0,0,0,0,0,0,0,0,0,0,0,0,0,0,0,0~
,0,0,0,CT69,0,0,0,0,0,0,0)';
      PINUSE='POWER';
      NO_LOAD_CHECK='Both';
      NO_IO_CHECK='Both';
      NO_ASSERT_CHECK='TRUE';
      NO_DIR_CHECK='TRUE';
      ALLOW_CONNECT='TRUE';
    'VSS805':
      PIN_NUMBER='(0,0,0,0,0,0,0,0,0,0,0,0,0,0,0,0,0,0,0,0,0,0,0,0,0,0,0,0,0,0,0~
,0,0,0,CT12,0,0,0,0,0,0,0)';
      PINUSE='POWER';
      NO_LOAD_CHECK='Both';
      NO_IO_CHECK='Both';
      NO_ASSERT_CHECK='TRUE';
      NO_DIR_CHECK='TRUE';
      ALLOW_CONNECT='TRUE';
    'VSS804':
      PIN_NUMBER='(0,0,0,0,0,0,0,0,0,0,0,0,0,0,0,0,0,0,0,0,0,0,0,0,0,0,0,0,0,0,0~
,0,0,0,CT10,0,0,0,0,0,0,0)';
      PINUSE='POWER';
      NO_LOAD_CHECK='Both';
      NO_IO_CHECK='Both';
      NO_ASSERT_CHECK='TRUE';
      NO_DIR_CHECK='TRUE';
      ALLOW_CONNECT='TRUE';
    'VSS803':
      PIN_NUMBER='(0,0,0,0,0,0,0,0,0,0,0,0,0,0,0,0,0,0,0,0,0,0,0,0,0,0,0,0,0,0,0~
,0,0,0,CR90,0,0,0,0,0,0,0)';
      PINUSE='POWER';
      NO_LOAD_CHECK='Both';
      NO_IO_CHECK='Both';
      NO_ASSERT_CHECK='TRUE';
      NO_DIR_CHECK='TRUE';
      ALLOW_CONNECT='TRUE';
    'VSS801':
      PIN_NUMBER='(0,0,0,0,0,0,0,0,0,0,0,0,0,0,0,0,0,0,0,0,0,0,0,0,0,0,0,0,0,0,0~
,0,0,0,CR9,0,0,0,0,0,0,0)';
      PINUSE='POWER';
      NO_LOAD_CHECK='Both';
      NO_IO_CHECK='Both';
      NO_ASSERT_CHECK='TRUE';
      NO_DIR_CHECK='TRUE';
      ALLOW_CONNECT='TRUE';
    'VSS800':
      PIN_NUMBER='(0,0,0,0,0,0,0,0,0,0,0,0,0,0,0,0,0,0,0,0,0,0,0,0,0,0,0,0,0,0,0~
,0,0,0,CR88,0,0,0,0,0,0,0)';
      PINUSE='POWER';
      NO_LOAD_CHECK='Both';
      NO_IO_CHECK='Both';
      NO_ASSERT_CHECK='TRUE';
      NO_DIR_CHECK='TRUE';
      ALLOW_CONNECT='TRUE';
    'VSS797':
      PIN_NUMBER='(0,0,0,0,0,0,0,0,0,0,0,0,0,0,0,0,0,0,0,0,0,0,0,0,0,0,0,0,0,0,0~
,0,0,0,CR84,0,0,0,0,0,0,0)';
      PINUSE='POWER';
      NO_LOAD_CHECK='Both';
      NO_IO_CHECK='Both';
      NO_ASSERT_CHECK='TRUE';
      NO_DIR_CHECK='TRUE';
      ALLOW_CONNECT='TRUE';
    'VSS796':
      PIN_NUMBER='(0,0,0,0,0,0,0,0,0,0,0,0,0,0,0,0,0,0,0,0,0,0,0,0,0,0,0,0,0,0,0~
,0,0,0,CR64,0,0,0,0,0,0,0)';
      PINUSE='POWER';
      NO_LOAD_CHECK='Both';
      NO_IO_CHECK='Both';
      NO_ASSERT_CHECK='TRUE';
      NO_DIR_CHECK='TRUE';
      ALLOW_CONNECT='TRUE';
    'VSS795':
      PIN_NUMBER='(0,0,0,0,0,0,0,0,0,0,0,0,0,0,0,0,0,0,0,0,0,0,0,0,0,0,0,0,0,0,0~
,0,0,0,CR62,0,0,0,0,0,0,0)';
      PINUSE='POWER';
      NO_LOAD_CHECK='Both';
      NO_IO_CHECK='Both';
      NO_ASSERT_CHECK='TRUE';
      NO_DIR_CHECK='TRUE';
      ALLOW_CONNECT='TRUE';
    'VSS794':
      PIN_NUMBER='(0,0,0,0,0,0,0,0,0,0,0,0,0,0,0,0,0,0,0,0,0,0,0,0,0,0,0,0,0,0,0~
,0,0,0,CR5,0,0,0,0,0,0,0)';
      PINUSE='POWER';
      NO_LOAD_CHECK='Both';
      NO_IO_CHECK='Both';
      NO_ASSERT_CHECK='TRUE';
      NO_DIR_CHECK='TRUE';
      ALLOW_CONNECT='TRUE';
    'VSS793':
      PIN_NUMBER='(0,0,0,0,0,0,0,0,0,0,0,0,0,0,0,0,0,0,0,0,0,0,0,0,0,0,0,0,0,0,0~
,0,0,0,CR17,0,0,0,0,0,0,0)';
      PINUSE='POWER';
      NO_LOAD_CHECK='Both';
      NO_IO_CHECK='Both';
      NO_ASSERT_CHECK='TRUE';
      NO_DIR_CHECK='TRUE';
      ALLOW_CONNECT='TRUE';
    'VSS792':
      PIN_NUMBER='(0,0,0,0,0,0,0,0,0,0,0,0,0,0,0,0,0,0,0,0,0,0,0,0,0,0,0,0,0,0,0~
,0,0,0,CR13,0,0,0,0,0,0,0)';
      PINUSE='POWER';
      NO_LOAD_CHECK='Both';
      NO_IO_CHECK='Both';
      NO_ASSERT_CHECK='TRUE';
      NO_DIR_CHECK='TRUE';
      ALLOW_CONNECT='TRUE';
    'VSS790':
      PIN_NUMBER='(0,0,0,0,0,0,0,0,0,0,0,0,0,0,0,0,0,0,0,0,0,0,0,0,0,0,0,0,0,0,0~
,0,0,0,CR11,0,0,0,0,0,0,0)';
      PINUSE='POWER';
      NO_LOAD_CHECK='Both';
      NO_IO_CHECK='Both';
      NO_ASSERT_CHECK='TRUE';
      NO_DIR_CHECK='TRUE';
      ALLOW_CONNECT='TRUE';
    'VSS789':
      PIN_NUMBER='(0,0,0,0,0,0,0,0,0,0,0,0,0,0,0,0,0,0,0,0,0,0,0,0,0,0,0,0,0,0,0~
,0,0,0,CR1,0,0,0,0,0,0,0)';
      PINUSE='POWER';
      NO_LOAD_CHECK='Both';
      NO_IO_CHECK='Both';
      NO_ASSERT_CHECK='TRUE';
      NO_DIR_CHECK='TRUE';
      ALLOW_CONNECT='TRUE';
    'VSS788':
      PIN_NUMBER='(0,0,0,0,0,0,0,0,0,0,0,0,0,0,0,0,0,0,0,0,0,0,0,0,0,0,0,0,0,0,0~
,0,0,0,CP91,0,0,0,0,0,0,0)';
      PINUSE='POWER';
      NO_LOAD_CHECK='Both';
      NO_IO_CHECK='Both';
      NO_ASSERT_CHECK='TRUE';
      NO_DIR_CHECK='TRUE';
      ALLOW_CONNECT='TRUE';
    'VSS787':
      PIN_NUMBER='(0,0,0,0,0,0,0,0,0,0,0,0,0,0,0,0,0,0,0,0,0,0,0,0,0,0,0,0,0,0,0~
,0,0,0,CP87,0,0,0,0,0,0,0)';
      PINUSE='POWER';
      NO_LOAD_CHECK='Both';
      NO_IO_CHECK='Both';
      NO_ASSERT_CHECK='TRUE';
      NO_DIR_CHECK='TRUE';
      ALLOW_CONNECT='TRUE';
    'VSS786':
      PIN_NUMBER='(0,0,0,0,0,0,0,0,0,0,0,0,0,0,0,0,0,0,0,0,0,0,0,0,0,0,0,0,0,0,0~
,0,0,0,CP83,0,0,0,0,0,0,0)';
      PINUSE='POWER';
      NO_LOAD_CHECK='Both';
      NO_IO_CHECK='Both';
      NO_ASSERT_CHECK='TRUE';
      NO_DIR_CHECK='TRUE';
      ALLOW_CONNECT='TRUE';
    'VSS785':
      PIN_NUMBER='(0,0,0,0,0,0,0,0,0,0,0,0,0,0,0,0,0,0,0,0,0,0,0,0,0,0,0,0,0,0,0~
,0,0,0,CP8,0,0,0,0,0,0,0)';
      PINUSE='POWER';
      NO_LOAD_CHECK='Both';
      NO_IO_CHECK='Both';
      NO_ASSERT_CHECK='TRUE';
      NO_DIR_CHECK='TRUE';
      ALLOW_CONNECT='TRUE';
    'VSS784':
      PIN_NUMBER='(0,0,0,0,0,0,0,0,0,0,0,0,0,0,0,0,0,0,0,0,0,0,0,0,0,0,0,0,0,0,0~
,0,0,0,CP77,0,0,0,0,0,0,0)';
      PINUSE='POWER';
      NO_LOAD_CHECK='Both';
      NO_IO_CHECK='Both';
      NO_ASSERT_CHECK='TRUE';
      NO_DIR_CHECK='TRUE';
      ALLOW_CONNECT='TRUE';
    'VSS783':
      PIN_NUMBER='(0,0,0,0,0,0,0,0,0,0,0,0,0,0,0,0,0,0,0,0,0,0,0,0,0,0,0,0,0,0,0~
,0,0,0,CP75,0,0,0,0,0,0,0)';
      PINUSE='POWER';
      NO_LOAD_CHECK='Both';
      NO_IO_CHECK='Both';
      NO_ASSERT_CHECK='TRUE';
      NO_DIR_CHECK='TRUE';
      ALLOW_CONNECT='TRUE';
    'VSS782':
      PIN_NUMBER='(0,0,0,0,0,0,0,0,0,0,0,0,0,0,0,0,0,0,0,0,0,0,0,0,0,0,0,0,0,0,0~
,0,0,0,CP4,0,0,0,0,0,0,0)';
      PINUSE='POWER';
      NO_LOAD_CHECK='Both';
      NO_IO_CHECK='Both';
      NO_ASSERT_CHECK='TRUE';
      NO_DIR_CHECK='TRUE';
      ALLOW_CONNECT='TRUE';
    'VSS781':
      PIN_NUMBER='(0,0,0,0,0,0,0,0,0,0,0,0,0,0,0,0,0,0,0,0,0,0,0,0,0,0,0,0,0,0,0~
,0,0,0,CP18,0,0,0,0,0,0,0)';
      PINUSE='POWER';
      NO_LOAD_CHECK='Both';
      NO_IO_CHECK='Both';
      NO_ASSERT_CHECK='TRUE';
      NO_DIR_CHECK='TRUE';
      ALLOW_CONNECT='TRUE';
    'VSS780':
      PIN_NUMBER='(0,0,0,0,0,0,0,0,0,0,0,0,0,0,0,0,0,0,0,0,0,0,0,0,0,0,0,0,0,0,0~
,0,0,0,CP12,0,0,0,0,0,0,0)';
      PINUSE='POWER';
      NO_LOAD_CHECK='Both';
      NO_IO_CHECK='Both';
      NO_ASSERT_CHECK='TRUE';
      NO_DIR_CHECK='TRUE';
      ALLOW_CONNECT='TRUE';
    'VSS779':
      PIN_NUMBER='(0,0,0,0,0,0,0,0,0,0,0,0,0,0,0,0,0,0,0,0,0,0,0,0,0,0,0,0,0,0,0~
,0,0,0,CN86,0,0,0,0,0,0,0)';
      PINUSE='POWER';
      NO_LOAD_CHECK='Both';
      NO_IO_CHECK='Both';
      NO_ASSERT_CHECK='TRUE';
      NO_DIR_CHECK='TRUE';
      ALLOW_CONNECT='TRUE';
    'VSS778':
      PIN_NUMBER='(0,0,0,0,0,0,0,0,0,0,0,0,0,0,0,0,0,0,0,0,0,0,0,0,0,0,0,0,0,0,0~
,0,0,0,CN84,0,0,0,0,0,0,0)';
      PINUSE='POWER';
      NO_LOAD_CHECK='Both';
      NO_IO_CHECK='Both';
      NO_ASSERT_CHECK='TRUE';
      NO_DIR_CHECK='TRUE';
      ALLOW_CONNECT='TRUE';
    'VSS777':
      PIN_NUMBER='(0,0,0,0,0,0,0,0,0,0,0,0,0,0,0,0,0,0,0,0,0,0,0,0,0,0,0,0,0,0,0~
,0,0,0,CN74,0,0,0,0,0,0,0)';
      PINUSE='POWER';
      NO_LOAD_CHECK='Both';
      NO_IO_CHECK='Both';
      NO_ASSERT_CHECK='TRUE';
      NO_DIR_CHECK='TRUE';
      ALLOW_CONNECT='TRUE';
    'VSS775':
      PIN_NUMBER='(0,0,0,0,0,0,0,0,0,0,0,0,0,0,0,0,0,0,0,0,0,0,0,0,0,0,0,0,0,0,0~
,0,0,0,CN72,0,0,0,0,0,0,0)';
      PINUSE='POWER';
      NO_LOAD_CHECK='Both';
      NO_IO_CHECK='Both';
      NO_ASSERT_CHECK='TRUE';
      NO_DIR_CHECK='TRUE';
      ALLOW_CONNECT='TRUE';
    'VSS774':
      PIN_NUMBER='(0,0,0,0,0,0,0,0,0,0,0,0,0,0,0,0,0,0,0,0,0,0,0,0,0,0,0,0,0,0,0~
,0,0,0,CN70,0,0,0,0,0,0,0)';
      PINUSE='POWER';
      NO_LOAD_CHECK='Both';
      NO_IO_CHECK='Both';
      NO_ASSERT_CHECK='TRUE';
      NO_DIR_CHECK='TRUE';
      ALLOW_CONNECT='TRUE';
    'VSS773':
      PIN_NUMBER='(0,0,0,0,0,0,0,0,0,0,0,0,0,0,0,0,0,0,0,0,0,0,0,0,0,0,0,0,0,0,0~
,0,0,0,CN68,0,0,0,0,0,0,0)';
      PINUSE='POWER';
      NO_LOAD_CHECK='Both';
      NO_IO_CHECK='Both';
      NO_ASSERT_CHECK='TRUE';
      NO_DIR_CHECK='TRUE';
      ALLOW_CONNECT='TRUE';
    'VSS772':
      PIN_NUMBER='(0,0,0,0,0,0,0,0,0,0,0,0,0,0,0,0,0,0,0,0,0,0,0,0,0,0,0,0,0,0,0~
,0,0,0,CM85,0,0,0,0,0,0,0)';
      PINUSE='POWER';
      NO_LOAD_CHECK='Both';
      NO_IO_CHECK='Both';
      NO_ASSERT_CHECK='TRUE';
      NO_DIR_CHECK='TRUE';
      ALLOW_CONNECT='TRUE';
    'VSS771':
      PIN_NUMBER='(0,0,0,0,0,0,0,0,0,0,0,0,0,0,0,0,0,0,0,0,0,0,0,0,0,0,0,0,0,0,0~
,0,0,0,CM83,0,0,0,0,0,0,0)';
      PINUSE='POWER';
      NO_LOAD_CHECK='Both';
      NO_IO_CHECK='Both';
      NO_ASSERT_CHECK='TRUE';
      NO_DIR_CHECK='TRUE';
      ALLOW_CONNECT='TRUE';
    'VSS770':
      PIN_NUMBER='(0,0,0,0,0,0,0,0,0,0,0,0,0,0,0,0,0,0,0,0,0,0,0,0,0,0,0,0,0,0,0~
,0,0,0,CM81,0,0,0,0,0,0,0)';
      PINUSE='POWER';
      NO_LOAD_CHECK='Both';
      NO_IO_CHECK='Both';
      NO_ASSERT_CHECK='TRUE';
      NO_DIR_CHECK='TRUE';
      ALLOW_CONNECT='TRUE';
    'VSS769':
      PIN_NUMBER='(0,0,0,0,0,0,0,0,0,0,0,0,0,0,0,0,0,0,0,0,0,0,0,0,0,0,0,0,0,0,0~
,0,0,0,CM8,0,0,0,0,0,0,0)';
      PINUSE='POWER';
      NO_LOAD_CHECK='Both';
      NO_IO_CHECK='Both';
      NO_ASSERT_CHECK='TRUE';
      NO_DIR_CHECK='TRUE';
      ALLOW_CONNECT='TRUE';
    'VSS768':
      PIN_NUMBER='(0,0,0,0,0,0,0,0,0,0,0,0,0,0,0,0,0,0,0,0,0,0,0,0,0,0,0,0,0,0,0~
,0,0,0,CM79,0,0,0,0,0,0,0)';
      PINUSE='POWER';
      NO_LOAD_CHECK='Both';
      NO_IO_CHECK='Both';
      NO_ASSERT_CHECK='TRUE';
      NO_DIR_CHECK='TRUE';
      ALLOW_CONNECT='TRUE';
    'VSS767':
      PIN_NUMBER='(0,0,0,0,0,0,0,0,0,0,0,0,0,0,0,0,0,0,0,0,0,0,0,0,0,0,0,0,0,0,0~
,0,0,0,CM67,0,0,0,0,0,0,0)';
      PINUSE='POWER';
      NO_LOAD_CHECK='Both';
      NO_IO_CHECK='Both';
      NO_ASSERT_CHECK='TRUE';
      NO_DIR_CHECK='TRUE';
      ALLOW_CONNECT='TRUE';
    'VSS766':
      PIN_NUMBER='(0,0,0,0,0,0,0,0,0,0,0,0,0,0,0,0,0,0,0,0,0,0,0,0,0,0,0,0,0,0,0~
,0,0,0,CM65,0,0,0,0,0,0,0)';
      PINUSE='POWER';
      NO_LOAD_CHECK='Both';
      NO_IO_CHECK='Both';
      NO_ASSERT_CHECK='TRUE';
      NO_DIR_CHECK='TRUE';
      ALLOW_CONNECT='TRUE';
    'VSS765':
      PIN_NUMBER='(0,0,0,0,0,0,0,0,0,0,0,0,0,0,0,0,0,0,0,0,0,0,0,0,0,0,0,0,0,0,0~
,0,0,0,CM61,0,0,0,0,0,0,0)';
      PINUSE='POWER';
      NO_LOAD_CHECK='Both';
      NO_IO_CHECK='Both';
      NO_ASSERT_CHECK='TRUE';
      NO_DIR_CHECK='TRUE';
      ALLOW_CONNECT='TRUE';
    'VSS764':
      PIN_NUMBER='(0,0,0,0,0,0,0,0,0,0,0,0,0,0,0,0,0,0,0,0,0,0,0,0,0,0,0,0,0,0,0~
,0,0,0,CM4,0,0,0,0,0,0,0)';
      PINUSE='POWER';
      NO_LOAD_CHECK='Both';
      NO_IO_CHECK='Both';
      NO_ASSERT_CHECK='TRUE';
      NO_DIR_CHECK='TRUE';
      ALLOW_CONNECT='TRUE';
    'VSS763':
      PIN_NUMBER='(0,0,0,0,0,0,0,0,0,0,0,0,0,0,0,0,0,0,0,0,0,0,0,0,0,0,0,0,0,0,0~
,0,0,0,CM24,0,0,0,0,0,0,0)';
      PINUSE='POWER';
      NO_LOAD_CHECK='Both';
      NO_IO_CHECK='Both';
      NO_ASSERT_CHECK='TRUE';
      NO_DIR_CHECK='TRUE';
      ALLOW_CONNECT='TRUE';
    'VSS762':
      PIN_NUMBER='(0,0,0,0,0,0,0,0,0,0,0,0,0,0,0,0,0,0,0,0,0,0,0,0,0,0,0,0,0,0,0~
,0,0,0,CM20,0,0,0,0,0,0,0)';
      PINUSE='POWER';
      NO_LOAD_CHECK='Both';
      NO_IO_CHECK='Both';
      NO_ASSERT_CHECK='TRUE';
      NO_DIR_CHECK='TRUE';
      ALLOW_CONNECT='TRUE';
    'VSS761':
      PIN_NUMBER='(0,0,0,0,0,0,0,0,0,0,0,0,0,0,0,0,0,0,0,0,0,0,0,0,0,0,0,0,0,0,0~
,0,0,0,CM12,0,0,0,0,0,0,0)';
      PINUSE='POWER';
      NO_LOAD_CHECK='Both';
      NO_IO_CHECK='Both';
      NO_ASSERT_CHECK='TRUE';
      NO_DIR_CHECK='TRUE';
      ALLOW_CONNECT='TRUE';
    'VSS760':
      PIN_NUMBER='(0,0,0,0,0,0,0,0,0,0,0,0,0,0,0,0,0,0,0,0,0,0,0,0,0,0,0,0,0,0,0~
,0,0,0,CL9,0,0,0,0,0,0,0)';
      PINUSE='POWER';
      NO_LOAD_CHECK='Both';
      NO_IO_CHECK='Both';
      NO_ASSERT_CHECK='TRUE';
      NO_DIR_CHECK='TRUE';
      ALLOW_CONNECT='TRUE';
    'VSS759':
      PIN_NUMBER='(0,0,0,0,0,0,0,0,0,0,0,0,0,0,0,0,0,0,0,0,0,0,0,0,0,0,0,0,0,0,0~
,0,0,0,CL82,0,0,0,0,0,0,0)';
      PINUSE='POWER';
      NO_LOAD_CHECK='Both';
      NO_IO_CHECK='Both';
      NO_ASSERT_CHECK='TRUE';
      NO_DIR_CHECK='TRUE';
      ALLOW_CONNECT='TRUE';
    'VSS758':
      PIN_NUMBER='(0,0,0,0,0,0,0,0,0,0,0,0,0,0,0,0,0,0,0,0,0,0,0,0,0,0,0,0,0,0,0~
,0,0,0,CL80,0,0,0,0,0,0,0)';
      PINUSE='POWER';
      NO_LOAD_CHECK='Both';
      NO_IO_CHECK='Both';
      NO_ASSERT_CHECK='TRUE';
      NO_DIR_CHECK='TRUE';
      ALLOW_CONNECT='TRUE';
    'VSS757':
      PIN_NUMBER='(0,0,0,0,0,0,0,0,0,0,0,0,0,0,0,0,0,0,0,0,0,0,0,0,0,0,0,0,0,0,0~
,0,0,0,CL78,0,0,0,0,0,0,0)';
      PINUSE='POWER';
      NO_LOAD_CHECK='Both';
      NO_IO_CHECK='Both';
      NO_ASSERT_CHECK='TRUE';
      NO_DIR_CHECK='TRUE';
      ALLOW_CONNECT='TRUE';
    'VSS756':
      PIN_NUMBER='(0,0,0,0,0,0,0,0,0,0,0,0,0,0,0,0,0,0,0,0,0,0,0,0,0,0,0,0,0,0,0~
,0,0,0,CL74,0,0,0,0,0,0,0)';
      PINUSE='POWER';
      NO_LOAD_CHECK='Both';
      NO_IO_CHECK='Both';
      NO_ASSERT_CHECK='TRUE';
      NO_DIR_CHECK='TRUE';
      ALLOW_CONNECT='TRUE';
    'VSS755':
      PIN_NUMBER='(0,0,0,0,0,0,0,0,0,0,0,0,0,0,0,0,0,0,0,0,0,0,0,0,0,0,0,0,0,0,0~
,0,0,0,CL62,0,0,0,0,0,0,0)';
      PINUSE='POWER';
      NO_LOAD_CHECK='Both';
      NO_IO_CHECK='Both';
      NO_ASSERT_CHECK='TRUE';
      NO_DIR_CHECK='TRUE';
      ALLOW_CONNECT='TRUE';
    'VSS754':
      PIN_NUMBER='(0,0,0,0,0,0,0,0,0,0,0,0,0,0,0,0,0,0,0,0,0,0,0,0,0,0,0,0,0,0,0~
,0,0,0,CL5,0,0,0,0,0,0,0)';
      PINUSE='POWER';
      NO_LOAD_CHECK='Both';
      NO_IO_CHECK='Both';
      NO_ASSERT_CHECK='TRUE';
      NO_DIR_CHECK='TRUE';
      ALLOW_CONNECT='TRUE';
    'VSS752':
      PIN_NUMBER='(0,0,0,0,0,0,0,0,0,0,0,0,0,0,0,0,0,0,0,0,0,0,0,0,0,0,0,0,0,0,0~
,0,0,0,CL17,0,0,0,0,0,0,0)';
      PINUSE='POWER';
      NO_LOAD_CHECK='Both';
      NO_IO_CHECK='Both';
      NO_ASSERT_CHECK='TRUE';
      NO_DIR_CHECK='TRUE';
      ALLOW_CONNECT='TRUE';
    'VSS751':
      PIN_NUMBER='(0,0,0,0,0,0,0,0,0,0,0,0,0,0,0,0,0,0,0,0,0,0,0,0,0,0,0,0,0,0,0~
,0,0,0,CL13,0,0,0,0,0,0,0)';
      PINUSE='POWER';
      NO_LOAD_CHECK='Both';
      NO_IO_CHECK='Both';
      NO_ASSERT_CHECK='TRUE';
      NO_DIR_CHECK='TRUE';
      ALLOW_CONNECT='TRUE';
    'VSS750':
      PIN_NUMBER='(0,0,0,0,0,0,0,0,0,0,0,0,0,0,0,0,0,0,0,0,0,0,0,0,0,0,0,0,0,0,0~
,0,0,0,CL1,0,0,0,0,0,0,0)';
      PINUSE='POWER';
      NO_LOAD_CHECK='Both';
      NO_IO_CHECK='Both';
      NO_ASSERT_CHECK='TRUE';
      NO_DIR_CHECK='TRUE';
      ALLOW_CONNECT='TRUE';
    'VSS749':
      PIN_NUMBER='(0,0,0,0,0,0,0,0,0,0,0,0,0,0,0,0,0,0,0,0,0,0,0,0,0,0,0,0,0,0,0~
,0,0,0,CK81,0,0,0,0,0,0,0)';
      PINUSE='POWER';
      NO_LOAD_CHECK='Both';
      NO_IO_CHECK='Both';
      NO_ASSERT_CHECK='TRUE';
      NO_DIR_CHECK='TRUE';
      ALLOW_CONNECT='TRUE';
    'VSS745':
      PIN_NUMBER='(0,0,0,0,0,0,0,0,0,0,0,0,0,0,0,0,0,0,0,0,0,0,0,0,0,0,0,0,0,0,0~
,0,0,0,CK69,0,0,0,0,0,0,0)';
      PINUSE='POWER';
      NO_LOAD_CHECK='Both';
      NO_IO_CHECK='Both';
      NO_ASSERT_CHECK='TRUE';
      NO_DIR_CHECK='TRUE';
      ALLOW_CONNECT='TRUE';
    'VSS744':
      PIN_NUMBER='(0,0,0,0,0,0,0,0,0,0,0,0,0,0,0,0,0,0,0,0,0,0,0,0,0,0,0,0,0,0,0~
,0,0,0,CK63,0,0,0,0,0,0,0)';
      PINUSE='POWER';
      NO_LOAD_CHECK='Both';
      NO_IO_CHECK='Both';
      NO_ASSERT_CHECK='TRUE';
      NO_DIR_CHECK='TRUE';
      ALLOW_CONNECT='TRUE';
    'VSS719':
      PIN_NUMBER='(0,0,0,0,0,0,0,0,0,0,0,0,0,0,0,0,0,0,0,0,0,0,0,0,0,0,0,0,0,0,0~
,0,0,0,DB75,0,0,0,0,0,0,0)';
      PINUSE='POWER';
      NO_LOAD_CHECK='Both';
      NO_IO_CHECK='Both';
      NO_ASSERT_CHECK='TRUE';
      NO_DIR_CHECK='TRUE';
      ALLOW_CONNECT='TRUE';
    'VSS717':
      PIN_NUMBER='(0,0,0,0,0,0,0,0,0,0,0,0,0,0,0,0,0,0,0,0,0,0,0,0,0,0,0,0,0,0,0~
,0,0,0,DB69,0,0,0,0,0,0,0)';
      PINUSE='POWER';
      NO_LOAD_CHECK='Both';
      NO_IO_CHECK='Both';
      NO_ASSERT_CHECK='TRUE';
      NO_DIR_CHECK='TRUE';
      ALLOW_CONNECT='TRUE';
    'VSS715':
      PIN_NUMBER='(0,0,0,0,0,0,0,0,0,0,0,0,0,0,0,0,0,0,0,0,0,0,0,0,0,0,0,0,0,0,0~
,0,0,0,DB63,0,0,0,0,0,0,0)';
      PINUSE='POWER';
      NO_LOAD_CHECK='Both';
      NO_IO_CHECK='Both';
      NO_ASSERT_CHECK='TRUE';
      NO_DIR_CHECK='TRUE';
      ALLOW_CONNECT='TRUE';
    'VSS714':
      PIN_NUMBER='(0,0,0,0,0,0,0,0,0,0,0,0,0,0,0,0,0,0,0,0,0,0,0,0,0,0,0,0,0,0,0~
,0,0,0,DB59,0,0,0,0,0,0,0)';
      PINUSE='POWER';
      NO_LOAD_CHECK='Both';
      NO_IO_CHECK='Both';
      NO_ASSERT_CHECK='TRUE';
      NO_DIR_CHECK='TRUE';
      ALLOW_CONNECT='TRUE';
    'VSS712':
      PIN_NUMBER='(0,0,0,0,0,0,0,0,0,0,0,0,0,0,0,0,0,0,0,0,0,0,0,0,0,0,0,0,0,0,0~
,0,0,0,DB53,0,0,0,0,0,0,0)';
      PINUSE='POWER';
      NO_LOAD_CHECK='Both';
      NO_IO_CHECK='Both';
      NO_ASSERT_CHECK='TRUE';
      NO_DIR_CHECK='TRUE';
      ALLOW_CONNECT='TRUE';
    'VSS711':
      PIN_NUMBER='(0,0,0,0,0,0,0,0,0,0,0,0,0,0,0,0,0,0,0,0,0,0,0,0,0,0,0,0,0,0,0~
,0,0,0,DB51,0,0,0,0,0,0,0)';
      PINUSE='POWER';
      NO_LOAD_CHECK='Both';
      NO_IO_CHECK='Both';
      NO_ASSERT_CHECK='TRUE';
      NO_DIR_CHECK='TRUE';
      ALLOW_CONNECT='TRUE';
    'VSS709':
      PIN_NUMBER='(0,0,0,0,0,0,0,0,0,0,0,0,0,0,0,0,0,0,0,0,0,0,0,0,0,0,0,0,0,0,0~
,0,0,0,DB44,0,0,0,0,0,0,0)';
      PINUSE='POWER';
      NO_LOAD_CHECK='Both';
      NO_IO_CHECK='Both';
      NO_ASSERT_CHECK='TRUE';
      NO_DIR_CHECK='TRUE';
      ALLOW_CONNECT='TRUE';
    'VSS705':
      PIN_NUMBER='(0,0,0,0,0,0,0,0,0,0,0,0,0,0,0,0,0,0,0,0,0,0,0,0,0,0,0,0,0,0,0~
,0,0,0,DB34,0,0,0,0,0,0,0)';
      PINUSE='POWER';
      NO_LOAD_CHECK='Both';
      NO_IO_CHECK='Both';
      NO_ASSERT_CHECK='TRUE';
      NO_DIR_CHECK='TRUE';
      ALLOW_CONNECT='TRUE';
    'VSS702':
      PIN_NUMBER='(0,0,0,0,0,0,0,0,0,0,0,0,0,0,0,0,0,0,0,0,0,0,0,0,0,0,0,0,0,0,0~
,0,0,0,DB26,0,0,0,0,0,0,0)';
      PINUSE='POWER';
      NO_LOAD_CHECK='Both';
      NO_IO_CHECK='Both';
      NO_ASSERT_CHECK='TRUE';
      NO_DIR_CHECK='TRUE';
      ALLOW_CONNECT='TRUE';
    'VSS700':
      PIN_NUMBER='(0,0,0,0,0,0,0,0,0,0,0,0,0,0,0,0,0,0,0,0,0,0,0,0,0,0,0,0,0,0,0~
,0,0,0,DB20,0,0,0,0,0,0,0)';
      PINUSE='POWER';
      NO_LOAD_CHECK='Both';
      NO_IO_CHECK='Both';
      NO_ASSERT_CHECK='TRUE';
      NO_DIR_CHECK='TRUE';
      ALLOW_CONNECT='TRUE';
    'VSS699':
      PIN_NUMBER='(0,0,0,0,0,0,0,0,0,0,0,0,0,0,0,0,0,0,0,0,0,0,0,0,0,0,0,0,0,0,0~
,0,0,0,DB16,0,0,0,0,0,0,0)';
      PINUSE='POWER';
      NO_LOAD_CHECK='Both';
      NO_IO_CHECK='Both';
      NO_ASSERT_CHECK='TRUE';
      NO_DIR_CHECK='TRUE';
      ALLOW_CONNECT='TRUE';
    'VSS690':
      PIN_NUMBER='(0,0,0,0,0,0,0,0,0,0,0,0,0,0,0,0,0,0,0,0,0,0,0,0,0,0,0,0,0,0,0~
,0,0,0,DA68,0,0,0,0,0,0,0)';
      PINUSE='POWER';
      NO_LOAD_CHECK='Both';
      NO_IO_CHECK='Both';
      NO_ASSERT_CHECK='TRUE';
      NO_DIR_CHECK='TRUE';
      ALLOW_CONNECT='TRUE';
    'VSS679':
      PIN_NUMBER='(0,0,0,0,0,0,0,0,0,0,0,0,0,0,0,0,0,0,0,0,0,0,0,0,0,0,0,0,0,0,0~
,0,0,0,DA43,0,0,0,0,0,0,0)';
      PINUSE='POWER';
      NO_LOAD_CHECK='Both';
      NO_IO_CHECK='Both';
      NO_ASSERT_CHECK='TRUE';
      NO_DIR_CHECK='TRUE';
      ALLOW_CONNECT='TRUE';
    'VSS611':
      PIN_NUMBER='(0,0,0,0,0,0,0,0,0,0,0,0,0,0,0,0,0,0,0,0,0,0,0,0,0,0,0,0,0,0,0~
,0,0,0,CY4,0,0,0,0,0,0,0)';
      PINUSE='POWER';
      NO_LOAD_CHECK='Both';
      NO_IO_CHECK='Both';
      NO_ASSERT_CHECK='TRUE';
      NO_DIR_CHECK='TRUE';
      ALLOW_CONNECT='TRUE';
    'VSS595':
      PIN_NUMBER='(0,0,0,0,0,0,0,0,0,0,0,0,0,0,0,0,0,0,0,0,0,0,0,0,0,0,0,0,0,0,0~
,0,0,0,CW70,0,0,0,0,0,0,0)';
      PINUSE='POWER';
      NO_LOAD_CHECK='Both';
      NO_IO_CHECK='Both';
      NO_ASSERT_CHECK='TRUE';
      NO_DIR_CHECK='TRUE';
      ALLOW_CONNECT='TRUE';
    'VSS583':
      PIN_NUMBER='(0,0,0,0,0,0,0,0,0,0,0,0,0,0,0,0,0,0,0,0,0,0,0,0,0,0,0,0,0,0,0~
,0,0,0,CW33,0,0,0,0,0,0,0)';
      PINUSE='POWER';
      NO_LOAD_CHECK='Both';
      NO_IO_CHECK='Both';
      NO_ASSERT_CHECK='TRUE';
      NO_DIR_CHECK='TRUE';
      ALLOW_CONNECT='TRUE';
    'VSS571':
      PIN_NUMBER='(0,0,0,0,0,0,0,0,0,0,0,0,0,0,0,0,0,0,0,0,0,0,0,0,0,0,0,0,0,0,0~
,0,0,0,CV79,0,0,0,0,0,0,0)';
      PINUSE='POWER';
      NO_LOAD_CHECK='Both';
      NO_IO_CHECK='Both';
      NO_ASSERT_CHECK='TRUE';
      NO_DIR_CHECK='TRUE';
      ALLOW_CONNECT='TRUE';
    'VSS562':
      PIN_NUMBER='(0,0,0,0,0,0,0,0,0,0,0,0,0,0,0,0,0,0,0,0,0,0,0,0,0,0,0,0,0,0,0~
,0,0,0,CV26,0,0,0,0,0,0,0)';
      PINUSE='POWER';
      NO_LOAD_CHECK='Both';
      NO_IO_CHECK='Both';
      NO_ASSERT_CHECK='TRUE';
      NO_DIR_CHECK='TRUE';
      ALLOW_CONNECT='TRUE';
    'VSS558':
      PIN_NUMBER='(0,0,0,0,0,0,0,0,0,0,0,0,0,0,0,0,0,0,0,0,0,0,0,0,0,0,0,0,0,0,0~
,0,0,0,CV16,0,0,0,0,0,0,0)';
      PINUSE='POWER';
      NO_LOAD_CHECK='Both';
      NO_IO_CHECK='Both';
      NO_ASSERT_CHECK='TRUE';
      NO_DIR_CHECK='TRUE';
      ALLOW_CONNECT='TRUE';
    'VSS554':
      PIN_NUMBER='(0,0,0,0,0,0,0,0,0,0,0,0,0,0,0,0,0,0,0,0,0,0,0,0,0,0,0,0,0,0,0~
,0,0,0,CU78,0,0,0,0,0,0,0)';
      PINUSE='POWER';
      NO_LOAD_CHECK='Both';
      NO_IO_CHECK='Both';
      NO_ASSERT_CHECK='TRUE';
      NO_DIR_CHECK='TRUE';
      ALLOW_CONNECT='TRUE';
    'VSS553':
      PIN_NUMBER='(0,0,0,0,0,0,0,0,0,0,0,0,0,0,0,0,0,0,0,0,0,0,0,0,0,0,0,0,0,0,0~
,0,0,0,CU72,0,0,0,0,0,0,0)';
      PINUSE='POWER';
      NO_LOAD_CHECK='Both';
      NO_IO_CHECK='Both';
      NO_ASSERT_CHECK='TRUE';
      NO_DIR_CHECK='TRUE';
      ALLOW_CONNECT='TRUE';
    'VSS544':
      PIN_NUMBER='(0,0,0,0,0,0,0,0,0,0,0,0,0,0,0,0,0,0,0,0,0,0,0,0,0,0,0,0,0,0,0~
,0,0,0,CU25,0,0,0,0,0,0,0)';
      PINUSE='POWER';
      NO_LOAD_CHECK='Both';
      NO_IO_CHECK='Both';
      NO_ASSERT_CHECK='TRUE';
      NO_DIR_CHECK='TRUE';
      ALLOW_CONNECT='TRUE';
    'VSS537':
      PIN_NUMBER='(0,0,0,0,0,0,0,0,0,0,0,0,0,0,0,0,0,0,0,0,0,0,0,0,0,0,0,0,0,0,0~
,0,0,0,CT89,0,0,0,0,0,0,0)';
      PINUSE='POWER';
      NO_LOAD_CHECK='Both';
      NO_IO_CHECK='Both';
      NO_ASSERT_CHECK='TRUE';
      NO_DIR_CHECK='TRUE';
      ALLOW_CONNECT='TRUE';
    'VSS534':
      PIN_NUMBER='(0,0,0,0,0,0,0,0,0,0,0,0,0,0,0,0,0,0,0,0,0,0,0,0,0,0,0,0,0,0,0~
,0,0,0,CT8,0,0,0,0,0,0,0)';
      PINUSE='POWER';
      NO_LOAD_CHECK='Both';
      NO_IO_CHECK='Both';
      NO_ASSERT_CHECK='TRUE';
      NO_DIR_CHECK='TRUE';
      ALLOW_CONNECT='TRUE';
    'VSS526':
      PIN_NUMBER='(0,0,0,0,0,0,0,0,0,0,0,0,0,0,0,0,0,0,0,0,0,0,0,0,0,0,0,0,0,0,0~
,0,0,0,CT4,0,0,0,0,0,0,0)';
      PINUSE='POWER';
      NO_LOAD_CHECK='Both';
      NO_IO_CHECK='Both';
      NO_ASSERT_CHECK='TRUE';
      NO_DIR_CHECK='TRUE';
      ALLOW_CONNECT='TRUE';
    'VSS521':
      PIN_NUMBER='(0,0,0,0,0,0,0,0,0,0,0,0,0,0,0,0,0,0,0,0,0,0,0,0,0,0,0,0,0,0,0~
,0,0,0,CT16,0,0,0,0,0,0,0)';
      PINUSE='POWER';
      NO_LOAD_CHECK='Both';
      NO_IO_CHECK='Both';
      NO_ASSERT_CHECK='TRUE';
      NO_DIR_CHECK='TRUE';
      ALLOW_CONNECT='TRUE';
    'VSS514':
      PIN_NUMBER='(0,0,0,0,0,0,0,0,0,0,0,0,0,0,0,0,0,0,0,0,0,0,0,0,0,0,0,0,0,0,0~
,0,0,0,CR78,0,0,0,0,0,0,0)';
      PINUSE='POWER';
      NO_LOAD_CHECK='Both';
      NO_IO_CHECK='Both';
      NO_ASSERT_CHECK='TRUE';
      NO_DIR_CHECK='TRUE';
      ALLOW_CONNECT='TRUE';
    'VSS493':
      PIN_NUMBER='(0,0,0,0,0,0,0,0,0,0,0,0,0,0,0,0,0,0,0,0,0,0,0,0,0,0,0,0,0,0,0~
,0,0,0,CP79,0,0,0,0,0,0,0)';
      PINUSE='POWER';
      NO_LOAD_CHECK='Both';
      NO_IO_CHECK='Both';
      NO_ASSERT_CHECK='TRUE';
      NO_DIR_CHECK='TRUE';
      ALLOW_CONNECT='TRUE';
    'VSS478':
      PIN_NUMBER='(0,0,0,0,0,0,0,0,0,0,0,0,0,0,0,0,0,0,0,0,0,0,0,0,0,0,0,0,0,0,0~
,0,0,0,CP16,0,0,0,0,0,0,0)';
      PINUSE='POWER';
      NO_LOAD_CHECK='Both';
      NO_IO_CHECK='Both';
      NO_ASSERT_CHECK='TRUE';
      NO_DIR_CHECK='TRUE';
      ALLOW_CONNECT='TRUE';
    'VSS471':
      PIN_NUMBER='(0,0,0,0,0,0,0,0,0,0,0,0,0,0,0,0,0,0,0,0,0,0,0,0,0,0,0,0,0,0,0~
,0,0,0,CN76,0,0,0,0,0,0,0)';
      PINUSE='POWER';
      NO_LOAD_CHECK='Both';
      NO_IO_CHECK='Both';
      NO_ASSERT_CHECK='TRUE';
      NO_DIR_CHECK='TRUE';
      ALLOW_CONNECT='TRUE';
    'VSS438':
      PIN_NUMBER='(0,0,0,0,0,0,0,0,0,0,0,0,0,0,0,0,0,0,0,0,0,0,0,0,0,0,0,0,0,0,0~
,0,0,0,CM22,0,0,0,0,0,0,0)';
      PINUSE='POWER';
      NO_LOAD_CHECK='Both';
      NO_IO_CHECK='Both';
      NO_ASSERT_CHECK='TRUE';
      NO_DIR_CHECK='TRUE';
      ALLOW_CONNECT='TRUE';
    'VSS436':
      PIN_NUMBER='(0,0,0,0,0,0,0,0,0,0,0,0,0,0,0,0,0,0,0,0,0,0,0,0,0,0,0,0,0,0,0~
,0,0,0,CM16,0,0,0,0,0,0,0)';
      PINUSE='POWER';
      NO_LOAD_CHECK='Both';
      NO_IO_CHECK='Both';
      NO_ASSERT_CHECK='TRUE';
      NO_DIR_CHECK='TRUE';
      ALLOW_CONNECT='TRUE';
    'VSS746':
      PIN_NUMBER='(0,0,0,0,0,0,0,0,0,0,0,0,0,0,0,0,0,0,0,0,0,0,0,0,0,0,0,0,0,0,0~
,0,0,0,0,CK8,0,0,0,0,0,0)';
      PINUSE='POWER';
      NO_LOAD_CHECK='Both';
      NO_IO_CHECK='Both';
      NO_ASSERT_CHECK='TRUE';
      NO_DIR_CHECK='TRUE';
      ALLOW_CONNECT='TRUE';
    'VSS743':
      PIN_NUMBER='(0,0,0,0,0,0,0,0,0,0,0,0,0,0,0,0,0,0,0,0,0,0,0,0,0,0,0,0,0,0,0~
,0,0,0,0,CK26,0,0,0,0,0,0)';
      PINUSE='POWER';
      NO_LOAD_CHECK='Both';
      NO_IO_CHECK='Both';
      NO_ASSERT_CHECK='TRUE';
      NO_DIR_CHECK='TRUE';
      ALLOW_CONNECT='TRUE';
    'VSS742':
      PIN_NUMBER='(0,0,0,0,0,0,0,0,0,0,0,0,0,0,0,0,0,0,0,0,0,0,0,0,0,0,0,0,0,0,0~
,0,0,0,0,CK20,0,0,0,0,0,0)';
      PINUSE='POWER';
      NO_LOAD_CHECK='Both';
      NO_IO_CHECK='Both';
      NO_ASSERT_CHECK='TRUE';
      NO_DIR_CHECK='TRUE';
      ALLOW_CONNECT='TRUE';
    'VSS741':
      PIN_NUMBER='(0,0,0,0,0,0,0,0,0,0,0,0,0,0,0,0,0,0,0,0,0,0,0,0,0,0,0,0,0,0,0~
,0,0,0,0,CK16,0,0,0,0,0,0)';
      PINUSE='POWER';
      NO_LOAD_CHECK='Both';
      NO_IO_CHECK='Both';
      NO_ASSERT_CHECK='TRUE';
      NO_DIR_CHECK='TRUE';
      ALLOW_CONNECT='TRUE';
    'VSS740':
      PIN_NUMBER='(0,0,0,0,0,0,0,0,0,0,0,0,0,0,0,0,0,0,0,0,0,0,0,0,0,0,0,0,0,0,0~
,0,0,0,0,CK12,0,0,0,0,0,0)';
      PINUSE='POWER';
      NO_LOAD_CHECK='Both';
      NO_IO_CHECK='Both';
      NO_ASSERT_CHECK='TRUE';
      NO_DIR_CHECK='TRUE';
      ALLOW_CONNECT='TRUE';
    'VSS737':
      PIN_NUMBER='(0,0,0,0,0,0,0,0,0,0,0,0,0,0,0,0,0,0,0,0,0,0,0,0,0,0,0,0,0,0,0~
,0,0,0,0,CJ80,0,0,0,0,0,0)';
      PINUSE='POWER';
      NO_LOAD_CHECK='Both';
      NO_IO_CHECK='Both';
      NO_ASSERT_CHECK='TRUE';
      NO_DIR_CHECK='TRUE';
      ALLOW_CONNECT='TRUE';
    'VSS736':
      PIN_NUMBER='(0,0,0,0,0,0,0,0,0,0,0,0,0,0,0,0,0,0,0,0,0,0,0,0,0,0,0,0,0,0,0~
,0,0,0,0,CJ60,0,0,0,0,0,0)';
      PINUSE='POWER';
      NO_LOAD_CHECK='Both';
      NO_IO_CHECK='Both';
      NO_ASSERT_CHECK='TRUE';
      NO_DIR_CHECK='TRUE';
      ALLOW_CONNECT='TRUE';
    'VSS734':
      PIN_NUMBER='(0,0,0,0,0,0,0,0,0,0,0,0,0,0,0,0,0,0,0,0,0,0,0,0,0,0,0,0,0,0,0~
,0,0,0,0,CH89,0,0,0,0,0,0)';
      PINUSE='POWER';
      NO_LOAD_CHECK='Both';
      NO_IO_CHECK='Both';
      NO_ASSERT_CHECK='TRUE';
      NO_DIR_CHECK='TRUE';
      ALLOW_CONNECT='TRUE';
    'VSS733':
      PIN_NUMBER='(0,0,0,0,0,0,0,0,0,0,0,0,0,0,0,0,0,0,0,0,0,0,0,0,0,0,0,0,0,0,0~
,0,0,0,0,CH87,0,0,0,0,0,0)';
      PINUSE='POWER';
      NO_LOAD_CHECK='Both';
      NO_IO_CHECK='Both';
      NO_ASSERT_CHECK='TRUE';
      NO_DIR_CHECK='TRUE';
      ALLOW_CONNECT='TRUE';
    'VSS732':
      PIN_NUMBER='(0,0,0,0,0,0,0,0,0,0,0,0,0,0,0,0,0,0,0,0,0,0,0,0,0,0,0,0,0,0,0~
,0,0,0,0,CH85,0,0,0,0,0,0)';
      PINUSE='POWER';
      NO_LOAD_CHECK='Both';
      NO_IO_CHECK='Both';
      NO_ASSERT_CHECK='TRUE';
      NO_DIR_CHECK='TRUE';
      ALLOW_CONNECT='TRUE';
    'VSS731':
      PIN_NUMBER='(0,0,0,0,0,0,0,0,0,0,0,0,0,0,0,0,0,0,0,0,0,0,0,0,0,0,0,0,0,0,0~
,0,0,0,0,CH83,0,0,0,0,0,0)';
      PINUSE='POWER';
      NO_LOAD_CHECK='Both';
      NO_IO_CHECK='Both';
      NO_ASSERT_CHECK='TRUE';
      NO_DIR_CHECK='TRUE';
      ALLOW_CONNECT='TRUE';
    'VSS730':
      PIN_NUMBER='(0,0,0,0,0,0,0,0,0,0,0,0,0,0,0,0,0,0,0,0,0,0,0,0,0,0,0,0,0,0,0~
,0,0,0,0,CH8,0,0,0,0,0,0)';
      PINUSE='POWER';
      NO_LOAD_CHECK='Both';
      NO_IO_CHECK='Both';
      NO_ASSERT_CHECK='TRUE';
      NO_DIR_CHECK='TRUE';
      ALLOW_CONNECT='TRUE';
    'VSS729':
      PIN_NUMBER='(0,0,0,0,0,0,0,0,0,0,0,0,0,0,0,0,0,0,0,0,0,0,0,0,0,0,0,0,0,0,0~
,0,0,0,0,CH79,0,0,0,0,0,0)';
      PINUSE='POWER';
      NO_LOAD_CHECK='Both';
      NO_IO_CHECK='Both';
      NO_ASSERT_CHECK='TRUE';
      NO_DIR_CHECK='TRUE';
      ALLOW_CONNECT='TRUE';
    'VSS728':
      PIN_NUMBER='(0,0,0,0,0,0,0,0,0,0,0,0,0,0,0,0,0,0,0,0,0,0,0,0,0,0,0,0,0,0,0~
,0,0,0,0,CH73,0,0,0,0,0,0)';
      PINUSE='POWER';
      NO_LOAD_CHECK='Both';
      NO_IO_CHECK='Both';
      NO_ASSERT_CHECK='TRUE';
      NO_DIR_CHECK='TRUE';
      ALLOW_CONNECT='TRUE';
    'VSS727':
      PIN_NUMBER='(0,0,0,0,0,0,0,0,0,0,0,0,0,0,0,0,0,0,0,0,0,0,0,0,0,0,0,0,0,0,0~
,0,0,0,0,CH67,0,0,0,0,0,0)';
      PINUSE='POWER';
      NO_LOAD_CHECK='Both';
      NO_IO_CHECK='Both';
      NO_ASSERT_CHECK='TRUE';
      NO_DIR_CHECK='TRUE';
      ALLOW_CONNECT='TRUE';
    'VSS722':
      PIN_NUMBER='(0,0,0,0,0,0,0,0,0,0,0,0,0,0,0,0,0,0,0,0,0,0,0,0,0,0,0,0,0,0,0~
,0,0,0,0,CH4,0,0,0,0,0,0)';
      PINUSE='POWER';
      NO_LOAD_CHECK='Both';
      NO_IO_CHECK='Both';
      NO_ASSERT_CHECK='TRUE';
      NO_DIR_CHECK='TRUE';
      ALLOW_CONNECT='TRUE';
    'VSS721':
      PIN_NUMBER='(0,0,0,0,0,0,0,0,0,0,0,0,0,0,0,0,0,0,0,0,0,0,0,0,0,0,0,0,0,0,0~
,0,0,0,0,CH20,0,0,0,0,0,0)';
      PINUSE='POWER';
      NO_LOAD_CHECK='Both';
      NO_IO_CHECK='Both';
      NO_ASSERT_CHECK='TRUE';
      NO_DIR_CHECK='TRUE';
      ALLOW_CONNECT='TRUE';
    'VSS720':
      PIN_NUMBER='(0,0,0,0,0,0,0,0,0,0,0,0,0,0,0,0,0,0,0,0,0,0,0,0,0,0,0,0,0,0,0~
,0,0,0,0,CH16,0,0,0,0,0,0)';
      PINUSE='POWER';
      NO_LOAD_CHECK='Both';
      NO_IO_CHECK='Both';
      NO_ASSERT_CHECK='TRUE';
      NO_DIR_CHECK='TRUE';
      ALLOW_CONNECT='TRUE';
    'VSS718':
      PIN_NUMBER='(0,0,0,0,0,0,0,0,0,0,0,0,0,0,0,0,0,0,0,0,0,0,0,0,0,0,0,0,0,0,0~
,0,0,0,0,CH12,0,0,0,0,0,0)';
      PINUSE='POWER';
      NO_LOAD_CHECK='Both';
      NO_IO_CHECK='Both';
      NO_ASSERT_CHECK='TRUE';
      NO_DIR_CHECK='TRUE';
      ALLOW_CONNECT='TRUE';
    'VSS716':
      PIN_NUMBER='(0,0,0,0,0,0,0,0,0,0,0,0,0,0,0,0,0,0,0,0,0,0,0,0,0,0,0,0,0,0,0~
,0,0,0,0,CG9,0,0,0,0,0,0)';
      PINUSE='POWER';
      NO_LOAD_CHECK='Both';
      NO_IO_CHECK='Both';
      NO_ASSERT_CHECK='TRUE';
      NO_DIR_CHECK='TRUE';
      ALLOW_CONNECT='TRUE';
    'VSS713':
      PIN_NUMBER='(0,0,0,0,0,0,0,0,0,0,0,0,0,0,0,0,0,0,0,0,0,0,0,0,0,0,0,0,0,0,0~
,0,0,0,0,CG78,0,0,0,0,0,0)';
      PINUSE='POWER';
      NO_LOAD_CHECK='Both';
      NO_IO_CHECK='Both';
      NO_ASSERT_CHECK='TRUE';
      NO_DIR_CHECK='TRUE';
      ALLOW_CONNECT='TRUE';
    'VSS710':
      PIN_NUMBER='(0,0,0,0,0,0,0,0,0,0,0,0,0,0,0,0,0,0,0,0,0,0,0,0,0,0,0,0,0,0,0~
,0,0,0,0,CG74,0,0,0,0,0,0)';
      PINUSE='POWER';
      NO_LOAD_CHECK='Both';
      NO_IO_CHECK='Both';
      NO_ASSERT_CHECK='TRUE';
      NO_DIR_CHECK='TRUE';
      ALLOW_CONNECT='TRUE';
    'VSS708':
      PIN_NUMBER='(0,0,0,0,0,0,0,0,0,0,0,0,0,0,0,0,0,0,0,0,0,0,0,0,0,0,0,0,0,0,0~
,0,0,0,0,CG72,0,0,0,0,0,0)';
      PINUSE='POWER';
      NO_LOAD_CHECK='Both';
      NO_IO_CHECK='Both';
      NO_ASSERT_CHECK='TRUE';
      NO_DIR_CHECK='TRUE';
      ALLOW_CONNECT='TRUE';
    'VSS707':
      PIN_NUMBER='(0,0,0,0,0,0,0,0,0,0,0,0,0,0,0,0,0,0,0,0,0,0,0,0,0,0,0,0,0,0,0~
,0,0,0,0,CG70,0,0,0,0,0,0)';
      PINUSE='POWER';
      NO_LOAD_CHECK='Both';
      NO_IO_CHECK='Both';
      NO_ASSERT_CHECK='TRUE';
      NO_DIR_CHECK='TRUE';
      ALLOW_CONNECT='TRUE';
    'VSS706':
      PIN_NUMBER='(0,0,0,0,0,0,0,0,0,0,0,0,0,0,0,0,0,0,0,0,0,0,0,0,0,0,0,0,0,0,0~
,0,0,0,0,CG64,0,0,0,0,0,0)';
      PINUSE='POWER';
      NO_LOAD_CHECK='Both';
      NO_IO_CHECK='Both';
      NO_ASSERT_CHECK='TRUE';
      NO_DIR_CHECK='TRUE';
      ALLOW_CONNECT='TRUE';
    'VSS704':
      PIN_NUMBER='(0,0,0,0,0,0,0,0,0,0,0,0,0,0,0,0,0,0,0,0,0,0,0,0,0,0,0,0,0,0,0~
,0,0,0,0,CG62,0,0,0,0,0,0)';
      PINUSE='POWER';
      NO_LOAD_CHECK='Both';
      NO_IO_CHECK='Both';
      NO_ASSERT_CHECK='TRUE';
      NO_DIR_CHECK='TRUE';
      ALLOW_CONNECT='TRUE';
    'VSS703':
      PIN_NUMBER='(0,0,0,0,0,0,0,0,0,0,0,0,0,0,0,0,0,0,0,0,0,0,0,0,0,0,0,0,0,0,0~
,0,0,0,0,CG5,0,0,0,0,0,0)';
      PINUSE='POWER';
      NO_LOAD_CHECK='Both';
      NO_IO_CHECK='Both';
      NO_ASSERT_CHECK='TRUE';
      NO_DIR_CHECK='TRUE';
      ALLOW_CONNECT='TRUE';
    'VSS701':
      PIN_NUMBER='(0,0,0,0,0,0,0,0,0,0,0,0,0,0,0,0,0,0,0,0,0,0,0,0,0,0,0,0,0,0,0~
,0,0,0,0,CG25,0,0,0,0,0,0)';
      PINUSE='POWER';
      NO_LOAD_CHECK='Both';
      NO_IO_CHECK='Both';
      NO_ASSERT_CHECK='TRUE';
      NO_DIR_CHECK='TRUE';
      ALLOW_CONNECT='TRUE';
    'VSS698':
      PIN_NUMBER='(0,0,0,0,0,0,0,0,0,0,0,0,0,0,0,0,0,0,0,0,0,0,0,0,0,0,0,0,0,0,0~
,0,0,0,0,CG23,0,0,0,0,0,0)';
      PINUSE='POWER';
      NO_LOAD_CHECK='Both';
      NO_IO_CHECK='Both';
      NO_ASSERT_CHECK='TRUE';
      NO_DIR_CHECK='TRUE';
      ALLOW_CONNECT='TRUE';
    'VSS697':
      PIN_NUMBER='(0,0,0,0,0,0,0,0,0,0,0,0,0,0,0,0,0,0,0,0,0,0,0,0,0,0,0,0,0,0,0~
,0,0,0,0,CG21,0,0,0,0,0,0)';
      PINUSE='POWER';
      NO_LOAD_CHECK='Both';
      NO_IO_CHECK='Both';
      NO_ASSERT_CHECK='TRUE';
      NO_DIR_CHECK='TRUE';
      ALLOW_CONNECT='TRUE';
    'VSS696':
      PIN_NUMBER='(0,0,0,0,0,0,0,0,0,0,0,0,0,0,0,0,0,0,0,0,0,0,0,0,0,0,0,0,0,0,0~
,0,0,0,0,CG17,0,0,0,0,0,0)';
      PINUSE='POWER';
      NO_LOAD_CHECK='Both';
      NO_IO_CHECK='Both';
      NO_ASSERT_CHECK='TRUE';
      NO_DIR_CHECK='TRUE';
      ALLOW_CONNECT='TRUE';
    'VSS695':
      PIN_NUMBER='(0,0,0,0,0,0,0,0,0,0,0,0,0,0,0,0,0,0,0,0,0,0,0,0,0,0,0,0,0,0,0~
,0,0,0,0,CG13,0,0,0,0,0,0)';
      PINUSE='POWER';
      NO_LOAD_CHECK='Both';
      NO_IO_CHECK='Both';
      NO_ASSERT_CHECK='TRUE';
      NO_DIR_CHECK='TRUE';
      ALLOW_CONNECT='TRUE';
    'VSS694':
      PIN_NUMBER='(0,0,0,0,0,0,0,0,0,0,0,0,0,0,0,0,0,0,0,0,0,0,0,0,0,0,0,0,0,0,0~
,0,0,0,0,CG1,0,0,0,0,0,0)';
      PINUSE='POWER';
      NO_LOAD_CHECK='Both';
      NO_IO_CHECK='Both';
      NO_ASSERT_CHECK='TRUE';
      NO_DIR_CHECK='TRUE';
      ALLOW_CONNECT='TRUE';
    'VSS693':
      PIN_NUMBER='(0,0,0,0,0,0,0,0,0,0,0,0,0,0,0,0,0,0,0,0,0,0,0,0,0,0,0,0,0,0,0~
,0,0,0,0,CF8,0,0,0,0,0,0)';
      PINUSE='POWER';
      NO_LOAD_CHECK='Both';
      NO_IO_CHECK='Both';
      NO_ASSERT_CHECK='TRUE';
      NO_DIR_CHECK='TRUE';
      ALLOW_CONNECT='TRUE';
    'VSS692':
      PIN_NUMBER='(0,0,0,0,0,0,0,0,0,0,0,0,0,0,0,0,0,0,0,0,0,0,0,0,0,0,0,0,0,0,0~
,0,0,0,0,CF71,0,0,0,0,0,0)';
      PINUSE='POWER';
      NO_LOAD_CHECK='Both';
      NO_IO_CHECK='Both';
      NO_ASSERT_CHECK='TRUE';
      NO_DIR_CHECK='TRUE';
      ALLOW_CONNECT='TRUE';
    'VSS691':
      PIN_NUMBER='(0,0,0,0,0,0,0,0,0,0,0,0,0,0,0,0,0,0,0,0,0,0,0,0,0,0,0,0,0,0,0~
,0,0,0,0,CF69,0,0,0,0,0,0)';
      PINUSE='POWER';
      NO_LOAD_CHECK='Both';
      NO_IO_CHECK='Both';
      NO_ASSERT_CHECK='TRUE';
      NO_DIR_CHECK='TRUE';
      ALLOW_CONNECT='TRUE';
    'VSS689':
      PIN_NUMBER='(0,0,0,0,0,0,0,0,0,0,0,0,0,0,0,0,0,0,0,0,0,0,0,0,0,0,0,0,0,0,0~
,0,0,0,0,CF4,0,0,0,0,0,0)';
      PINUSE='POWER';
      NO_LOAD_CHECK='Both';
      NO_IO_CHECK='Both';
      NO_ASSERT_CHECK='TRUE';
      NO_DIR_CHECK='TRUE';
      ALLOW_CONNECT='TRUE';
    'VSS688':
      PIN_NUMBER='(0,0,0,0,0,0,0,0,0,0,0,0,0,0,0,0,0,0,0,0,0,0,0,0,0,0,0,0,0,0,0~
,0,0,0,0,CF20,0,0,0,0,0,0)';
      PINUSE='POWER';
      NO_LOAD_CHECK='Both';
      NO_IO_CHECK='Both';
      NO_ASSERT_CHECK='TRUE';
      NO_DIR_CHECK='TRUE';
      ALLOW_CONNECT='TRUE';
    'VSS687':
      PIN_NUMBER='(0,0,0,0,0,0,0,0,0,0,0,0,0,0,0,0,0,0,0,0,0,0,0,0,0,0,0,0,0,0,0~
,0,0,0,0,CF16,0,0,0,0,0,0)';
      PINUSE='POWER';
      NO_LOAD_CHECK='Both';
      NO_IO_CHECK='Both';
      NO_ASSERT_CHECK='TRUE';
      NO_DIR_CHECK='TRUE';
      ALLOW_CONNECT='TRUE';
    'VSS686':
      PIN_NUMBER='(0,0,0,0,0,0,0,0,0,0,0,0,0,0,0,0,0,0,0,0,0,0,0,0,0,0,0,0,0,0,0~
,0,0,0,0,CF12,0,0,0,0,0,0)';
      PINUSE='POWER';
      NO_LOAD_CHECK='Both';
      NO_IO_CHECK='Both';
      NO_ASSERT_CHECK='TRUE';
      NO_DIR_CHECK='TRUE';
      ALLOW_CONNECT='TRUE';
    'VSS685':
      PIN_NUMBER='(0,0,0,0,0,0,0,0,0,0,0,0,0,0,0,0,0,0,0,0,0,0,0,0,0,0,0,0,0,0,0~
,0,0,0,0,CE78,0,0,0,0,0,0)';
      PINUSE='POWER';
      NO_LOAD_CHECK='Both';
      NO_IO_CHECK='Both';
      NO_ASSERT_CHECK='TRUE';
      NO_DIR_CHECK='TRUE';
      ALLOW_CONNECT='TRUE';
    'VSS684':
      PIN_NUMBER='(0,0,0,0,0,0,0,0,0,0,0,0,0,0,0,0,0,0,0,0,0,0,0,0,0,0,0,0,0,0,0~
,0,0,0,0,CE76,0,0,0,0,0,0)';
      PINUSE='POWER';
      NO_LOAD_CHECK='Both';
      NO_IO_CHECK='Both';
      NO_ASSERT_CHECK='TRUE';
      NO_DIR_CHECK='TRUE';
      ALLOW_CONNECT='TRUE';
    'VSS683':
      PIN_NUMBER='(0,0,0,0,0,0,0,0,0,0,0,0,0,0,0,0,0,0,0,0,0,0,0,0,0,0,0,0,0,0,0~
,0,0,0,0,CE72,0,0,0,0,0,0)';
      PINUSE='POWER';
      NO_LOAD_CHECK='Both';
      NO_IO_CHECK='Both';
      NO_ASSERT_CHECK='TRUE';
      NO_DIR_CHECK='TRUE';
      ALLOW_CONNECT='TRUE';
    'VSS682':
      PIN_NUMBER='(0,0,0,0,0,0,0,0,0,0,0,0,0,0,0,0,0,0,0,0,0,0,0,0,0,0,0,0,0,0,0~
,0,0,0,0,CE66,0,0,0,0,0,0)';
      PINUSE='POWER';
      NO_LOAD_CHECK='Both';
      NO_IO_CHECK='Both';
      NO_ASSERT_CHECK='TRUE';
      NO_DIR_CHECK='TRUE';
      ALLOW_CONNECT='TRUE';
    'VSS681':
      PIN_NUMBER='(0,0,0,0,0,0,0,0,0,0,0,0,0,0,0,0,0,0,0,0,0,0,0,0,0,0,0,0,0,0,0~
,0,0,0,0,CE60,0,0,0,0,0,0)';
      PINUSE='POWER';
      NO_LOAD_CHECK='Both';
      NO_IO_CHECK='Both';
      NO_ASSERT_CHECK='TRUE';
      NO_DIR_CHECK='TRUE';
      ALLOW_CONNECT='TRUE';
    'VSS680':
      PIN_NUMBER='(0,0,0,0,0,0,0,0,0,0,0,0,0,0,0,0,0,0,0,0,0,0,0,0,0,0,0,0,0,0,0~
,0,0,0,0,CE3,0,0,0,0,0,0)';
      PINUSE='POWER';
      NO_LOAD_CHECK='Both';
      NO_IO_CHECK='Both';
      NO_ASSERT_CHECK='TRUE';
      NO_DIR_CHECK='TRUE';
      ALLOW_CONNECT='TRUE';
    'VSS678':
      PIN_NUMBER='(0,0,0,0,0,0,0,0,0,0,0,0,0,0,0,0,0,0,0,0,0,0,0,0,0,0,0,0,0,0,0~
,0,0,0,0,CD8,0,0,0,0,0,0)';
      PINUSE='POWER';
      NO_LOAD_CHECK='Both';
      NO_IO_CHECK='Both';
      NO_ASSERT_CHECK='TRUE';
      NO_DIR_CHECK='TRUE';
      ALLOW_CONNECT='TRUE';
    'VSS677':
      PIN_NUMBER='(0,0,0,0,0,0,0,0,0,0,0,0,0,0,0,0,0,0,0,0,0,0,0,0,0,0,0,0,0,0,0~
,0,0,0,0,CD77,0,0,0,0,0,0)';
      PINUSE='POWER';
      NO_LOAD_CHECK='Both';
      NO_IO_CHECK='Both';
      NO_ASSERT_CHECK='TRUE';
      NO_DIR_CHECK='TRUE';
      ALLOW_CONNECT='TRUE';
    'VSS676':
      PIN_NUMBER='(0,0,0,0,0,0,0,0,0,0,0,0,0,0,0,0,0,0,0,0,0,0,0,0,0,0,0,0,0,0,0~
,0,0,0,0,CD75,0,0,0,0,0,0)';
      PINUSE='POWER';
      NO_LOAD_CHECK='Both';
      NO_IO_CHECK='Both';
      NO_ASSERT_CHECK='TRUE';
      NO_DIR_CHECK='TRUE';
      ALLOW_CONNECT='TRUE';
    'VSS675':
      PIN_NUMBER='(0,0,0,0,0,0,0,0,0,0,0,0,0,0,0,0,0,0,0,0,0,0,0,0,0,0,0,0,0,0,0~
,0,0,0,0,CD61,0,0,0,0,0,0)';
      PINUSE='POWER';
      NO_LOAD_CHECK='Both';
      NO_IO_CHECK='Both';
      NO_ASSERT_CHECK='TRUE';
      NO_DIR_CHECK='TRUE';
      ALLOW_CONNECT='TRUE';
    'VSS674':
      PIN_NUMBER='(0,0,0,0,0,0,0,0,0,0,0,0,0,0,0,0,0,0,0,0,0,0,0,0,0,0,0,0,0,0,0~
,0,0,0,0,CD4,0,0,0,0,0,0)';
      PINUSE='POWER';
      NO_LOAD_CHECK='Both';
      NO_IO_CHECK='Both';
      NO_ASSERT_CHECK='TRUE';
      NO_DIR_CHECK='TRUE';
      ALLOW_CONNECT='TRUE';
    'VSS673':
      PIN_NUMBER='(0,0,0,0,0,0,0,0,0,0,0,0,0,0,0,0,0,0,0,0,0,0,0,0,0,0,0,0,0,0,0~
,0,0,0,0,CD20,0,0,0,0,0,0)';
      PINUSE='POWER';
      NO_LOAD_CHECK='Both';
      NO_IO_CHECK='Both';
      NO_ASSERT_CHECK='TRUE';
      NO_DIR_CHECK='TRUE';
      ALLOW_CONNECT='TRUE';
    'VSS672':
      PIN_NUMBER='(0,0,0,0,0,0,0,0,0,0,0,0,0,0,0,0,0,0,0,0,0,0,0,0,0,0,0,0,0,0,0~
,0,0,0,0,CD16,0,0,0,0,0,0)';
      PINUSE='POWER';
      NO_LOAD_CHECK='Both';
      NO_IO_CHECK='Both';
      NO_ASSERT_CHECK='TRUE';
      NO_DIR_CHECK='TRUE';
      ALLOW_CONNECT='TRUE';
    'VSS671':
      PIN_NUMBER='(0,0,0,0,0,0,0,0,0,0,0,0,0,0,0,0,0,0,0,0,0,0,0,0,0,0,0,0,0,0,0~
,0,0,0,0,CD12,0,0,0,0,0,0)';
      PINUSE='POWER';
      NO_LOAD_CHECK='Both';
      NO_IO_CHECK='Both';
      NO_ASSERT_CHECK='TRUE';
      NO_DIR_CHECK='TRUE';
      ALLOW_CONNECT='TRUE';
    'VSS670':
      PIN_NUMBER='(0,0,0,0,0,0,0,0,0,0,0,0,0,0,0,0,0,0,0,0,0,0,0,0,0,0,0,0,0,0,0~
,0,0,0,0,CC9,0,0,0,0,0,0)';
      PINUSE='POWER';
      NO_LOAD_CHECK='Both';
      NO_IO_CHECK='Both';
      NO_ASSERT_CHECK='TRUE';
      NO_DIR_CHECK='TRUE';
      ALLOW_CONNECT='TRUE';
    'VSS669':
      PIN_NUMBER='(0,0,0,0,0,0,0,0,0,0,0,0,0,0,0,0,0,0,0,0,0,0,0,0,0,0,0,0,0,0,0~
,0,0,0,0,CC74,0,0,0,0,0,0)';
      PINUSE='POWER';
      NO_LOAD_CHECK='Both';
      NO_IO_CHECK='Both';
      NO_ASSERT_CHECK='TRUE';
      NO_DIR_CHECK='TRUE';
      ALLOW_CONNECT='TRUE';
    'VSS668':
      PIN_NUMBER='(0,0,0,0,0,0,0,0,0,0,0,0,0,0,0,0,0,0,0,0,0,0,0,0,0,0,0,0,0,0,0~
,0,0,0,0,CC72,0,0,0,0,0,0)';
      PINUSE='POWER';
      NO_LOAD_CHECK='Both';
      NO_IO_CHECK='Both';
      NO_ASSERT_CHECK='TRUE';
      NO_DIR_CHECK='TRUE';
      ALLOW_CONNECT='TRUE';
    'VSS667':
      PIN_NUMBER='(0,0,0,0,0,0,0,0,0,0,0,0,0,0,0,0,0,0,0,0,0,0,0,0,0,0,0,0,0,0,0~
,0,0,0,0,CC70,0,0,0,0,0,0)';
      PINUSE='POWER';
      NO_LOAD_CHECK='Both';
      NO_IO_CHECK='Both';
      NO_ASSERT_CHECK='TRUE';
      NO_DIR_CHECK='TRUE';
      ALLOW_CONNECT='TRUE';
    'VSS666':
      PIN_NUMBER='(0,0,0,0,0,0,0,0,0,0,0,0,0,0,0,0,0,0,0,0,0,0,0,0,0,0,0,0,0,0,0~
,0,0,0,0,CC62,0,0,0,0,0,0)';
      PINUSE='POWER';
      NO_LOAD_CHECK='Both';
      NO_IO_CHECK='Both';
      NO_ASSERT_CHECK='TRUE';
      NO_DIR_CHECK='TRUE';
      ALLOW_CONNECT='TRUE';
    'VSS665':
      PIN_NUMBER='(0,0,0,0,0,0,0,0,0,0,0,0,0,0,0,0,0,0,0,0,0,0,0,0,0,0,0,0,0,0,0~
,0,0,0,0,CC5,0,0,0,0,0,0)';
      PINUSE='POWER';
      NO_LOAD_CHECK='Both';
      NO_IO_CHECK='Both';
      NO_ASSERT_CHECK='TRUE';
      NO_DIR_CHECK='TRUE';
      ALLOW_CONNECT='TRUE';
    'VSS664':
      PIN_NUMBER='(0,0,0,0,0,0,0,0,0,0,0,0,0,0,0,0,0,0,0,0,0,0,0,0,0,0,0,0,0,0,0~
,0,0,0,0,CC31,0,0,0,0,0,0)';
      PINUSE='POWER';
      NO_LOAD_CHECK='Both';
      NO_IO_CHECK='Both';
      NO_ASSERT_CHECK='TRUE';
      NO_DIR_CHECK='TRUE';
      ALLOW_CONNECT='TRUE';
    'VSS661':
      PIN_NUMBER='(0,0,0,0,0,0,0,0,0,0,0,0,0,0,0,0,0,0,0,0,0,0,0,0,0,0,0,0,0,0,0~
,0,0,0,0,CC17,0,0,0,0,0,0)';
      PINUSE='POWER';
      NO_LOAD_CHECK='Both';
      NO_IO_CHECK='Both';
      NO_ASSERT_CHECK='TRUE';
      NO_DIR_CHECK='TRUE';
      ALLOW_CONNECT='TRUE';
    'VSS660':
      PIN_NUMBER='(0,0,0,0,0,0,0,0,0,0,0,0,0,0,0,0,0,0,0,0,0,0,0,0,0,0,0,0,0,0,0~
,0,0,0,0,CC13,0,0,0,0,0,0)';
      PINUSE='POWER';
      NO_LOAD_CHECK='Both';
      NO_IO_CHECK='Both';
      NO_ASSERT_CHECK='TRUE';
      NO_DIR_CHECK='TRUE';
      ALLOW_CONNECT='TRUE';
    'VSS656':
      PIN_NUMBER='(0,0,0,0,0,0,0,0,0,0,0,0,0,0,0,0,0,0,0,0,0,0,0,0,0,0,0,0,0,0,0~
,0,0,0,0,CB89,0,0,0,0,0,0)';
      PINUSE='POWER';
      NO_LOAD_CHECK='Both';
      NO_IO_CHECK='Both';
      NO_ASSERT_CHECK='TRUE';
      NO_DIR_CHECK='TRUE';
      ALLOW_CONNECT='TRUE';
    'VSS655':
      PIN_NUMBER='(0,0,0,0,0,0,0,0,0,0,0,0,0,0,0,0,0,0,0,0,0,0,0,0,0,0,0,0,0,0,0~
,0,0,0,0,CB87,0,0,0,0,0,0)';
      PINUSE='POWER';
      NO_LOAD_CHECK='Both';
      NO_IO_CHECK='Both';
      NO_ASSERT_CHECK='TRUE';
      NO_DIR_CHECK='TRUE';
      ALLOW_CONNECT='TRUE';
    'VSS654':
      PIN_NUMBER='(0,0,0,0,0,0,0,0,0,0,0,0,0,0,0,0,0,0,0,0,0,0,0,0,0,0,0,0,0,0,0~
,0,0,0,0,CB85,0,0,0,0,0,0)';
      PINUSE='POWER';
      NO_LOAD_CHECK='Both';
      NO_IO_CHECK='Both';
      NO_ASSERT_CHECK='TRUE';
      NO_DIR_CHECK='TRUE';
      ALLOW_CONNECT='TRUE';
    'VSS653':
      PIN_NUMBER='(0,0,0,0,0,0,0,0,0,0,0,0,0,0,0,0,0,0,0,0,0,0,0,0,0,0,0,0,0,0,0~
,0,0,0,0,CB83,0,0,0,0,0,0)';
      PINUSE='POWER';
      NO_LOAD_CHECK='Both';
      NO_IO_CHECK='Both';
      NO_ASSERT_CHECK='TRUE';
      NO_DIR_CHECK='TRUE';
      ALLOW_CONNECT='TRUE';
    'VSS652':
      PIN_NUMBER='(0,0,0,0,0,0,0,0,0,0,0,0,0,0,0,0,0,0,0,0,0,0,0,0,0,0,0,0,0,0,0~
,0,0,0,0,CB81,0,0,0,0,0,0)';
      PINUSE='POWER';
      NO_LOAD_CHECK='Both';
      NO_IO_CHECK='Both';
      NO_ASSERT_CHECK='TRUE';
      NO_DIR_CHECK='TRUE';
      ALLOW_CONNECT='TRUE';
    'VSS651':
      PIN_NUMBER='(0,0,0,0,0,0,0,0,0,0,0,0,0,0,0,0,0,0,0,0,0,0,0,0,0,0,0,0,0,0,0~
,0,0,0,0,CB8,0,0,0,0,0,0)';
      PINUSE='POWER';
      NO_LOAD_CHECK='Both';
      NO_IO_CHECK='Both';
      NO_ASSERT_CHECK='TRUE';
      NO_DIR_CHECK='TRUE';
      ALLOW_CONNECT='TRUE';
    'VSS650':
      PIN_NUMBER='(0,0,0,0,0,0,0,0,0,0,0,0,0,0,0,0,0,0,0,0,0,0,0,0,0,0,0,0,0,0,0~
,0,0,0,0,CB79,0,0,0,0,0,0)';
      PINUSE='POWER';
      NO_LOAD_CHECK='Both';
      NO_IO_CHECK='Both';
      NO_ASSERT_CHECK='TRUE';
      NO_DIR_CHECK='TRUE';
      ALLOW_CONNECT='TRUE';
    'VSS649':
      PIN_NUMBER='(0,0,0,0,0,0,0,0,0,0,0,0,0,0,0,0,0,0,0,0,0,0,0,0,0,0,0,0,0,0,0~
,0,0,0,0,CB73,0,0,0,0,0,0)';
      PINUSE='POWER';
      NO_LOAD_CHECK='Both';
      NO_IO_CHECK='Both';
      NO_ASSERT_CHECK='TRUE';
      NO_DIR_CHECK='TRUE';
      ALLOW_CONNECT='TRUE';
    'VSS648':
      PIN_NUMBER='(0,0,0,0,0,0,0,0,0,0,0,0,0,0,0,0,0,0,0,0,0,0,0,0,0,0,0,0,0,0,0~
,0,0,0,0,CB71,0,0,0,0,0,0)';
      PINUSE='POWER';
      NO_LOAD_CHECK='Both';
      NO_IO_CHECK='Both';
      NO_ASSERT_CHECK='TRUE';
      NO_DIR_CHECK='TRUE';
      ALLOW_CONNECT='TRUE';
    'VSS647':
      PIN_NUMBER='(0,0,0,0,0,0,0,0,0,0,0,0,0,0,0,0,0,0,0,0,0,0,0,0,0,0,0,0,0,0,0~
,0,0,0,0,CB69,0,0,0,0,0,0)';
      PINUSE='POWER';
      NO_LOAD_CHECK='Both';
      NO_IO_CHECK='Both';
      NO_ASSERT_CHECK='TRUE';
      NO_DIR_CHECK='TRUE';
      ALLOW_CONNECT='TRUE';
    'VSS646':
      PIN_NUMBER='(0,0,0,0,0,0,0,0,0,0,0,0,0,0,0,0,0,0,0,0,0,0,0,0,0,0,0,0,0,0,0~
,0,0,0,0,CB67,0,0,0,0,0,0)';
      PINUSE='POWER';
      NO_LOAD_CHECK='Both';
      NO_IO_CHECK='Both';
      NO_ASSERT_CHECK='TRUE';
      NO_DIR_CHECK='TRUE';
      ALLOW_CONNECT='TRUE';
    'VSS645':
      PIN_NUMBER='(0,0,0,0,0,0,0,0,0,0,0,0,0,0,0,0,0,0,0,0,0,0,0,0,0,0,0,0,0,0,0~
,0,0,0,0,CB65,0,0,0,0,0,0)';
      PINUSE='POWER';
      NO_LOAD_CHECK='Both';
      NO_IO_CHECK='Both';
      NO_ASSERT_CHECK='TRUE';
      NO_DIR_CHECK='TRUE';
      ALLOW_CONNECT='TRUE';
    'VSS644':
      PIN_NUMBER='(0,0,0,0,0,0,0,0,0,0,0,0,0,0,0,0,0,0,0,0,0,0,0,0,0,0,0,0,0,0,0~
,0,0,0,0,CB63,0,0,0,0,0,0)';
      PINUSE='POWER';
      NO_LOAD_CHECK='Both';
      NO_IO_CHECK='Both';
      NO_ASSERT_CHECK='TRUE';
      NO_DIR_CHECK='TRUE';
      ALLOW_CONNECT='TRUE';
    'VSS643':
      PIN_NUMBER='(0,0,0,0,0,0,0,0,0,0,0,0,0,0,0,0,0,0,0,0,0,0,0,0,0,0,0,0,0,0,0~
,0,0,0,0,CB59,0,0,0,0,0,0)';
      PINUSE='POWER';
      NO_LOAD_CHECK='Both';
      NO_IO_CHECK='Both';
      NO_ASSERT_CHECK='TRUE';
      NO_DIR_CHECK='TRUE';
      ALLOW_CONNECT='TRUE';
    'VSS642':
      PIN_NUMBER='(0,0,0,0,0,0,0,0,0,0,0,0,0,0,0,0,0,0,0,0,0,0,0,0,0,0,0,0,0,0,0~
,0,0,0,0,CB57,0,0,0,0,0,0)';
      PINUSE='POWER';
      NO_LOAD_CHECK='Both';
      NO_IO_CHECK='Both';
      NO_ASSERT_CHECK='TRUE';
      NO_DIR_CHECK='TRUE';
      ALLOW_CONNECT='TRUE';
    'VSS641':
      PIN_NUMBER='(0,0,0,0,0,0,0,0,0,0,0,0,0,0,0,0,0,0,0,0,0,0,0,0,0,0,0,0,0,0,0~
,0,0,0,0,CB55,0,0,0,0,0,0)';
      PINUSE='POWER';
      NO_LOAD_CHECK='Both';
      NO_IO_CHECK='Both';
      NO_ASSERT_CHECK='TRUE';
      NO_DIR_CHECK='TRUE';
      ALLOW_CONNECT='TRUE';
    'VSS640':
      PIN_NUMBER='(0,0,0,0,0,0,0,0,0,0,0,0,0,0,0,0,0,0,0,0,0,0,0,0,0,0,0,0,0,0,0~
,0,0,0,0,CB53,0,0,0,0,0,0)';
      PINUSE='POWER';
      NO_LOAD_CHECK='Both';
      NO_IO_CHECK='Both';
      NO_ASSERT_CHECK='TRUE';
      NO_DIR_CHECK='TRUE';
      ALLOW_CONNECT='TRUE';
    'VSS639':
      PIN_NUMBER='(0,0,0,0,0,0,0,0,0,0,0,0,0,0,0,0,0,0,0,0,0,0,0,0,0,0,0,0,0,0,0~
,0,0,0,0,CB51,0,0,0,0,0,0)';
      PINUSE='POWER';
      NO_LOAD_CHECK='Both';
      NO_IO_CHECK='Both';
      NO_ASSERT_CHECK='TRUE';
      NO_DIR_CHECK='TRUE';
      ALLOW_CONNECT='TRUE';
    'VSS638':
      PIN_NUMBER='(0,0,0,0,0,0,0,0,0,0,0,0,0,0,0,0,0,0,0,0,0,0,0,0,0,0,0,0,0,0,0~
,0,0,0,0,CB49,0,0,0,0,0,0)';
      PINUSE='POWER';
      NO_LOAD_CHECK='Both';
      NO_IO_CHECK='Both';
      NO_ASSERT_CHECK='TRUE';
      NO_DIR_CHECK='TRUE';
      ALLOW_CONNECT='TRUE';
    'VSS637':
      PIN_NUMBER='(0,0,0,0,0,0,0,0,0,0,0,0,0,0,0,0,0,0,0,0,0,0,0,0,0,0,0,0,0,0,0~
,0,0,0,0,CB47,0,0,0,0,0,0)';
      PINUSE='POWER';
      NO_LOAD_CHECK='Both';
      NO_IO_CHECK='Both';
      NO_ASSERT_CHECK='TRUE';
      NO_DIR_CHECK='TRUE';
      ALLOW_CONNECT='TRUE';
    'VSS636':
      PIN_NUMBER='(0,0,0,0,0,0,0,0,0,0,0,0,0,0,0,0,0,0,0,0,0,0,0,0,0,0,0,0,0,0,0~
,0,0,0,0,CB44,0,0,0,0,0,0)';
      PINUSE='POWER';
      NO_LOAD_CHECK='Both';
      NO_IO_CHECK='Both';
      NO_ASSERT_CHECK='TRUE';
      NO_DIR_CHECK='TRUE';
      ALLOW_CONNECT='TRUE';
    'VSS635':
      PIN_NUMBER='(0,0,0,0,0,0,0,0,0,0,0,0,0,0,0,0,0,0,0,0,0,0,0,0,0,0,0,0,0,0,0~
,0,0,0,0,CB42,0,0,0,0,0,0)';
      PINUSE='POWER';
      NO_LOAD_CHECK='Both';
      NO_IO_CHECK='Both';
      NO_ASSERT_CHECK='TRUE';
      NO_DIR_CHECK='TRUE';
      ALLOW_CONNECT='TRUE';
    'VSS634':
      PIN_NUMBER='(0,0,0,0,0,0,0,0,0,0,0,0,0,0,0,0,0,0,0,0,0,0,0,0,0,0,0,0,0,0,0~
,0,0,0,0,CB40,0,0,0,0,0,0)';
      PINUSE='POWER';
      NO_LOAD_CHECK='Both';
      NO_IO_CHECK='Both';
      NO_ASSERT_CHECK='TRUE';
      NO_DIR_CHECK='TRUE';
      ALLOW_CONNECT='TRUE';
    'VSS633':
      PIN_NUMBER='(0,0,0,0,0,0,0,0,0,0,0,0,0,0,0,0,0,0,0,0,0,0,0,0,0,0,0,0,0,0,0~
,0,0,0,0,CB4,0,0,0,0,0,0)';
      PINUSE='POWER';
      NO_LOAD_CHECK='Both';
      NO_IO_CHECK='Both';
      NO_ASSERT_CHECK='TRUE';
      NO_DIR_CHECK='TRUE';
      ALLOW_CONNECT='TRUE';
    'VSS632':
      PIN_NUMBER='(0,0,0,0,0,0,0,0,0,0,0,0,0,0,0,0,0,0,0,0,0,0,0,0,0,0,0,0,0,0,0~
,0,0,0,0,CB38,0,0,0,0,0,0)';
      PINUSE='POWER';
      NO_LOAD_CHECK='Both';
      NO_IO_CHECK='Both';
      NO_ASSERT_CHECK='TRUE';
      NO_DIR_CHECK='TRUE';
      ALLOW_CONNECT='TRUE';
    'VSS631':
      PIN_NUMBER='(0,0,0,0,0,0,0,0,0,0,0,0,0,0,0,0,0,0,0,0,0,0,0,0,0,0,0,0,0,0,0~
,0,0,0,0,CB36,0,0,0,0,0,0)';
      PINUSE='POWER';
      NO_LOAD_CHECK='Both';
      NO_IO_CHECK='Both';
      NO_ASSERT_CHECK='TRUE';
      NO_DIR_CHECK='TRUE';
      ALLOW_CONNECT='TRUE';
    'VSS630':
      PIN_NUMBER='(0,0,0,0,0,0,0,0,0,0,0,0,0,0,0,0,0,0,0,0,0,0,0,0,0,0,0,0,0,0,0~
,0,0,0,0,CB34,0,0,0,0,0,0)';
      PINUSE='POWER';
      NO_LOAD_CHECK='Both';
      NO_IO_CHECK='Both';
      NO_ASSERT_CHECK='TRUE';
      NO_DIR_CHECK='TRUE';
      ALLOW_CONNECT='TRUE';
    'VSS629':
      PIN_NUMBER='(0,0,0,0,0,0,0,0,0,0,0,0,0,0,0,0,0,0,0,0,0,0,0,0,0,0,0,0,0,0,0~
,0,0,0,0,CB32,0,0,0,0,0,0)';
      PINUSE='POWER';
      NO_LOAD_CHECK='Both';
      NO_IO_CHECK='Both';
      NO_ASSERT_CHECK='TRUE';
      NO_DIR_CHECK='TRUE';
      ALLOW_CONNECT='TRUE';
    'VSS628':
      PIN_NUMBER='(0,0,0,0,0,0,0,0,0,0,0,0,0,0,0,0,0,0,0,0,0,0,0,0,0,0,0,0,0,0,0~
,0,0,0,0,CB28,0,0,0,0,0,0)';
      PINUSE='POWER';
      NO_LOAD_CHECK='Both';
      NO_IO_CHECK='Both';
      NO_ASSERT_CHECK='TRUE';
      NO_DIR_CHECK='TRUE';
      ALLOW_CONNECT='TRUE';
    'VSS627':
      PIN_NUMBER='(0,0,0,0,0,0,0,0,0,0,0,0,0,0,0,0,0,0,0,0,0,0,0,0,0,0,0,0,0,0,0~
,0,0,0,0,CB26,0,0,0,0,0,0)';
      PINUSE='POWER';
      NO_LOAD_CHECK='Both';
      NO_IO_CHECK='Both';
      NO_ASSERT_CHECK='TRUE';
      NO_DIR_CHECK='TRUE';
      ALLOW_CONNECT='TRUE';
    'VSS626':
      PIN_NUMBER='(0,0,0,0,0,0,0,0,0,0,0,0,0,0,0,0,0,0,0,0,0,0,0,0,0,0,0,0,0,0,0~
,0,0,0,0,CB24,0,0,0,0,0,0)';
      PINUSE='POWER';
      NO_LOAD_CHECK='Both';
      NO_IO_CHECK='Both';
      NO_ASSERT_CHECK='TRUE';
      NO_DIR_CHECK='TRUE';
      ALLOW_CONNECT='TRUE';
    'VSS625':
      PIN_NUMBER='(0,0,0,0,0,0,0,0,0,0,0,0,0,0,0,0,0,0,0,0,0,0,0,0,0,0,0,0,0,0,0~
,0,0,0,0,CB22,0,0,0,0,0,0)';
      PINUSE='POWER';
      NO_LOAD_CHECK='Both';
      NO_IO_CHECK='Both';
      NO_ASSERT_CHECK='TRUE';
      NO_DIR_CHECK='TRUE';
      ALLOW_CONNECT='TRUE';
    'VSS624':
      PIN_NUMBER='(0,0,0,0,0,0,0,0,0,0,0,0,0,0,0,0,0,0,0,0,0,0,0,0,0,0,0,0,0,0,0~
,0,0,0,0,CB20,0,0,0,0,0,0)';
      PINUSE='POWER';
      NO_LOAD_CHECK='Both';
      NO_IO_CHECK='Both';
      NO_ASSERT_CHECK='TRUE';
      NO_DIR_CHECK='TRUE';
      ALLOW_CONNECT='TRUE';
    'VSS623':
      PIN_NUMBER='(0,0,0,0,0,0,0,0,0,0,0,0,0,0,0,0,0,0,0,0,0,0,0,0,0,0,0,0,0,0,0~
,0,0,0,0,CB16,0,0,0,0,0,0)';
      PINUSE='POWER';
      NO_LOAD_CHECK='Both';
      NO_IO_CHECK='Both';
      NO_ASSERT_CHECK='TRUE';
      NO_DIR_CHECK='TRUE';
      ALLOW_CONNECT='TRUE';
    'VSS622':
      PIN_NUMBER='(0,0,0,0,0,0,0,0,0,0,0,0,0,0,0,0,0,0,0,0,0,0,0,0,0,0,0,0,0,0,0~
,0,0,0,0,CB12,0,0,0,0,0,0)';
      PINUSE='POWER';
      NO_LOAD_CHECK='Both';
      NO_IO_CHECK='Both';
      NO_ASSERT_CHECK='TRUE';
      NO_DIR_CHECK='TRUE';
      ALLOW_CONNECT='TRUE';
    'VSS621':
      PIN_NUMBER='(0,0,0,0,0,0,0,0,0,0,0,0,0,0,0,0,0,0,0,0,0,0,0,0,0,0,0,0,0,0,0~
,0,0,0,0,CA31,0,0,0,0,0,0)';
      PINUSE='POWER';
      NO_LOAD_CHECK='Both';
      NO_IO_CHECK='Both';
      NO_ASSERT_CHECK='TRUE';
      NO_DIR_CHECK='TRUE';
      ALLOW_CONNECT='TRUE';
    'VSS620':
      PIN_NUMBER='(0,0,0,0,0,0,0,0,0,0,0,0,0,0,0,0,0,0,0,0,0,0,0,0,0,0,0,0,0,0,0~
,0,0,0,0,CA3,0,0,0,0,0,0)';
      PINUSE='POWER';
      NO_LOAD_CHECK='Both';
      NO_IO_CHECK='Both';
      NO_ASSERT_CHECK='TRUE';
      NO_DIR_CHECK='TRUE';
      ALLOW_CONNECT='TRUE';
    'VSS608':
      PIN_NUMBER='(0,0,0,0,0,0,0,0,0,0,0,0,0,0,0,0,0,0,0,0,0,0,0,0,0,0,0,0,0,0,0~
,0,0,0,0,BY8,0,0,0,0,0,0)';
      PINUSE='POWER';
      NO_LOAD_CHECK='Both';
      NO_IO_CHECK='Both';
      NO_ASSERT_CHECK='TRUE';
      NO_DIR_CHECK='TRUE';
      ALLOW_CONNECT='TRUE';
    'VSS607':
      PIN_NUMBER='(0,0,0,0,0,0,0,0,0,0,0,0,0,0,0,0,0,0,0,0,0,0,0,0,0,0,0,0,0,0,0~
,0,0,0,0,BY4,0,0,0,0,0,0)';
      PINUSE='POWER';
      NO_LOAD_CHECK='Both';
      NO_IO_CHECK='Both';
      NO_ASSERT_CHECK='TRUE';
      NO_DIR_CHECK='TRUE';
      ALLOW_CONNECT='TRUE';
    'VSS606':
      PIN_NUMBER='(0,0,0,0,0,0,0,0,0,0,0,0,0,0,0,0,0,0,0,0,0,0,0,0,0,0,0,0,0,0,0~
,0,0,0,0,BY20,0,0,0,0,0,0)';
      PINUSE='POWER';
      NO_LOAD_CHECK='Both';
      NO_IO_CHECK='Both';
      NO_ASSERT_CHECK='TRUE';
      NO_DIR_CHECK='TRUE';
      ALLOW_CONNECT='TRUE';
    'VSS605':
      PIN_NUMBER='(0,0,0,0,0,0,0,0,0,0,0,0,0,0,0,0,0,0,0,0,0,0,0,0,0,0,0,0,0,0,0~
,0,0,0,0,BY16,0,0,0,0,0,0)';
      PINUSE='POWER';
      NO_LOAD_CHECK='Both';
      NO_IO_CHECK='Both';
      NO_ASSERT_CHECK='TRUE';
      NO_DIR_CHECK='TRUE';
      ALLOW_CONNECT='TRUE';
    'VSS604':
      PIN_NUMBER='(0,0,0,0,0,0,0,0,0,0,0,0,0,0,0,0,0,0,0,0,0,0,0,0,0,0,0,0,0,0,0~
,0,0,0,0,BY12,0,0,0,0,0,0)';
      PINUSE='POWER';
      NO_LOAD_CHECK='Both';
      NO_IO_CHECK='Both';
      NO_ASSERT_CHECK='TRUE';
      NO_DIR_CHECK='TRUE';
      ALLOW_CONNECT='TRUE';
    'VSS603':
      PIN_NUMBER='(0,0,0,0,0,0,0,0,0,0,0,0,0,0,0,0,0,0,0,0,0,0,0,0,0,0,0,0,0,0,0~
,0,0,0,0,BW9,0,0,0,0,0,0)';
      PINUSE='POWER';
      NO_LOAD_CHECK='Both';
      NO_IO_CHECK='Both';
      NO_ASSERT_CHECK='TRUE';
      NO_DIR_CHECK='TRUE';
      ALLOW_CONNECT='TRUE';
    'VSS602':
      PIN_NUMBER='(0,0,0,0,0,0,0,0,0,0,0,0,0,0,0,0,0,0,0,0,0,0,0,0,0,0,0,0,0,0,0~
,0,0,0,0,BW5,0,0,0,0,0,0)';
      PINUSE='POWER';
      NO_LOAD_CHECK='Both';
      NO_IO_CHECK='Both';
      NO_ASSERT_CHECK='TRUE';
      NO_DIR_CHECK='TRUE';
      ALLOW_CONNECT='TRUE';
    'VSS601':
      PIN_NUMBER='(0,0,0,0,0,0,0,0,0,0,0,0,0,0,0,0,0,0,0,0,0,0,0,0,0,0,0,0,0,0,0~
,0,0,0,0,BW31,0,0,0,0,0,0)';
      PINUSE='POWER';
      NO_LOAD_CHECK='Both';
      NO_IO_CHECK='Both';
      NO_ASSERT_CHECK='TRUE';
      NO_DIR_CHECK='TRUE';
      ALLOW_CONNECT='TRUE';
    'VSS600':
      PIN_NUMBER='(0,0,0,0,0,0,0,0,0,0,0,0,0,0,0,0,0,0,0,0,0,0,0,0,0,0,0,0,0,0,0~
,0,0,0,0,BW3,0,0,0,0,0,0)';
      PINUSE='POWER';
      NO_LOAD_CHECK='Both';
      NO_IO_CHECK='Both';
      NO_ASSERT_CHECK='TRUE';
      NO_DIR_CHECK='TRUE';
      ALLOW_CONNECT='TRUE';
    'VSS599':
      PIN_NUMBER='(0,0,0,0,0,0,0,0,0,0,0,0,0,0,0,0,0,0,0,0,0,0,0,0,0,0,0,0,0,0,0~
,0,0,0,0,BW29,0,0,0,0,0,0)';
      PINUSE='POWER';
      NO_LOAD_CHECK='Both';
      NO_IO_CHECK='Both';
      NO_ASSERT_CHECK='TRUE';
      NO_DIR_CHECK='TRUE';
      ALLOW_CONNECT='TRUE';
    'VSS598':
      PIN_NUMBER='(0,0,0,0,0,0,0,0,0,0,0,0,0,0,0,0,0,0,0,0,0,0,0,0,0,0,0,0,0,0,0~
,0,0,0,0,BW27,0,0,0,0,0,0)';
      PINUSE='POWER';
      NO_LOAD_CHECK='Both';
      NO_IO_CHECK='Both';
      NO_ASSERT_CHECK='TRUE';
      NO_DIR_CHECK='TRUE';
      ALLOW_CONNECT='TRUE';
    'VSS597':
      PIN_NUMBER='(0,0,0,0,0,0,0,0,0,0,0,0,0,0,0,0,0,0,0,0,0,0,0,0,0,0,0,0,0,0,0~
,0,0,0,0,BW17,0,0,0,0,0,0)';
      PINUSE='POWER';
      NO_LOAD_CHECK='Both';
      NO_IO_CHECK='Both';
      NO_ASSERT_CHECK='TRUE';
      NO_DIR_CHECK='TRUE';
      ALLOW_CONNECT='TRUE';
    'VSS596':
      PIN_NUMBER='(0,0,0,0,0,0,0,0,0,0,0,0,0,0,0,0,0,0,0,0,0,0,0,0,0,0,0,0,0,0,0~
,0,0,0,0,BW13,0,0,0,0,0,0)';
      PINUSE='POWER';
      NO_LOAD_CHECK='Both';
      NO_IO_CHECK='Both';
      NO_ASSERT_CHECK='TRUE';
      NO_DIR_CHECK='TRUE';
      ALLOW_CONNECT='TRUE';
    'VSS594':
      PIN_NUMBER='(0,0,0,0,0,0,0,0,0,0,0,0,0,0,0,0,0,0,0,0,0,0,0,0,0,0,0,0,0,0,0~
,0,0,0,0,BV8,0,0,0,0,0,0)';
      PINUSE='POWER';
      NO_LOAD_CHECK='Both';
      NO_IO_CHECK='Both';
      NO_ASSERT_CHECK='TRUE';
      NO_DIR_CHECK='TRUE';
      ALLOW_CONNECT='TRUE';
    'VSS593':
      PIN_NUMBER='(0,0,0,0,0,0,0,0,0,0,0,0,0,0,0,0,0,0,0,0,0,0,0,0,0,0,0,0,0,0,0~
,0,0,0,0,BV6,0,0,0,0,0,0)';
      PINUSE='POWER';
      NO_LOAD_CHECK='Both';
      NO_IO_CHECK='Both';
      NO_ASSERT_CHECK='TRUE';
      NO_DIR_CHECK='TRUE';
      ALLOW_CONNECT='TRUE';
    'VSS592':
      PIN_NUMBER='(0,0,0,0,0,0,0,0,0,0,0,0,0,0,0,0,0,0,0,0,0,0,0,0,0,0,0,0,0,0,0~
,0,0,0,0,BV4,0,0,0,0,0,0)';
      PINUSE='POWER';
      NO_LOAD_CHECK='Both';
      NO_IO_CHECK='Both';
      NO_ASSERT_CHECK='TRUE';
      NO_DIR_CHECK='TRUE';
      ALLOW_CONNECT='TRUE';
    'VSS591':
      PIN_NUMBER='(0,0,0,0,0,0,0,0,0,0,0,0,0,0,0,0,0,0,0,0,0,0,0,0,0,0,0,0,0,0,0~
,0,0,0,0,BV20,0,0,0,0,0,0)';
      PINUSE='POWER';
      NO_LOAD_CHECK='Both';
      NO_IO_CHECK='Both';
      NO_ASSERT_CHECK='TRUE';
      NO_DIR_CHECK='TRUE';
      ALLOW_CONNECT='TRUE';
    'VSS590':
      PIN_NUMBER='(0,0,0,0,0,0,0,0,0,0,0,0,0,0,0,0,0,0,0,0,0,0,0,0,0,0,0,0,0,0,0~
,0,0,0,0,BV2,0,0,0,0,0,0)';
      PINUSE='POWER';
      NO_LOAD_CHECK='Both';
      NO_IO_CHECK='Both';
      NO_ASSERT_CHECK='TRUE';
      NO_DIR_CHECK='TRUE';
      ALLOW_CONNECT='TRUE';
    'VSS589':
      PIN_NUMBER='(0,0,0,0,0,0,0,0,0,0,0,0,0,0,0,0,0,0,0,0,0,0,0,0,0,0,0,0,0,0,0~
,0,0,0,0,BV18,0,0,0,0,0,0)';
      PINUSE='POWER';
      NO_LOAD_CHECK='Both';
      NO_IO_CHECK='Both';
      NO_ASSERT_CHECK='TRUE';
      NO_DIR_CHECK='TRUE';
      ALLOW_CONNECT='TRUE';
    'VSS588':
      PIN_NUMBER='(0,0,0,0,0,0,0,0,0,0,0,0,0,0,0,0,0,0,0,0,0,0,0,0,0,0,0,0,0,0,0~
,0,0,0,0,BV16,0,0,0,0,0,0)';
      PINUSE='POWER';
      NO_LOAD_CHECK='Both';
      NO_IO_CHECK='Both';
      NO_ASSERT_CHECK='TRUE';
      NO_DIR_CHECK='TRUE';
      ALLOW_CONNECT='TRUE';
    'VSS587':
      PIN_NUMBER='(0,0,0,0,0,0,0,0,0,0,0,0,0,0,0,0,0,0,0,0,0,0,0,0,0,0,0,0,0,0,0~
,0,0,0,0,BV12,0,0,0,0,0,0)';
      PINUSE='POWER';
      NO_LOAD_CHECK='Both';
      NO_IO_CHECK='Both';
      NO_ASSERT_CHECK='TRUE';
      NO_DIR_CHECK='TRUE';
      ALLOW_CONNECT='TRUE';
    'VSS586':
      PIN_NUMBER='(0,0,0,0,0,0,0,0,0,0,0,0,0,0,0,0,0,0,0,0,0,0,0,0,0,0,0,0,0,0,0~
,0,0,0,0,BU7,0,0,0,0,0,0)';
      PINUSE='POWER';
      NO_LOAD_CHECK='Both';
      NO_IO_CHECK='Both';
      NO_ASSERT_CHECK='TRUE';
      NO_DIR_CHECK='TRUE';
      ALLOW_CONNECT='TRUE';
    'VSS585':
      PIN_NUMBER='(0,0,0,0,0,0,0,0,0,0,0,0,0,0,0,0,0,0,0,0,0,0,0,0,0,0,0,0,0,0,0~
,0,0,0,0,BU31,0,0,0,0,0,0)';
      PINUSE='POWER';
      NO_LOAD_CHECK='Both';
      NO_IO_CHECK='Both';
      NO_ASSERT_CHECK='TRUE';
      NO_DIR_CHECK='TRUE';
      ALLOW_CONNECT='TRUE';
    'VSS584':
      PIN_NUMBER='(0,0,0,0,0,0,0,0,0,0,0,0,0,0,0,0,0,0,0,0,0,0,0,0,0,0,0,0,0,0,0~
,0,0,0,0,BU25,0,0,0,0,0,0)';
      PINUSE='POWER';
      NO_LOAD_CHECK='Both';
      NO_IO_CHECK='Both';
      NO_ASSERT_CHECK='TRUE';
      NO_DIR_CHECK='TRUE';
      ALLOW_CONNECT='TRUE';
    'VSS582':
      PIN_NUMBER='(0,0,0,0,0,0,0,0,0,0,0,0,0,0,0,0,0,0,0,0,0,0,0,0,0,0,0,0,0,0,0~
,0,0,0,0,BU23,0,0,0,0,0,0)';
      PINUSE='POWER';
      NO_LOAD_CHECK='Both';
      NO_IO_CHECK='Both';
      NO_ASSERT_CHECK='TRUE';
      NO_DIR_CHECK='TRUE';
      ALLOW_CONNECT='TRUE';
    'VSS581':
      PIN_NUMBER='(0,0,0,0,0,0,0,0,0,0,0,0,0,0,0,0,0,0,0,0,0,0,0,0,0,0,0,0,0,0,0~
,0,0,0,0,BU21,0,0,0,0,0,0)';
      PINUSE='POWER';
      NO_LOAD_CHECK='Both';
      NO_IO_CHECK='Both';
      NO_ASSERT_CHECK='TRUE';
      NO_DIR_CHECK='TRUE';
      ALLOW_CONNECT='TRUE';
    'VSS580':
      PIN_NUMBER='(0,0,0,0,0,0,0,0,0,0,0,0,0,0,0,0,0,0,0,0,0,0,0,0,0,0,0,0,0,0,0~
,0,0,0,0,BU19,0,0,0,0,0,0)';
      PINUSE='POWER';
      NO_LOAD_CHECK='Both';
      NO_IO_CHECK='Both';
      NO_ASSERT_CHECK='TRUE';
      NO_DIR_CHECK='TRUE';
      ALLOW_CONNECT='TRUE';
    'VSS579':
      PIN_NUMBER='(0,0,0,0,0,0,0,0,0,0,0,0,0,0,0,0,0,0,0,0,0,0,0,0,0,0,0,0,0,0,0~
,0,0,0,0,BU15,0,0,0,0,0,0)';
      PINUSE='POWER';
      NO_LOAD_CHECK='Both';
      NO_IO_CHECK='Both';
      NO_ASSERT_CHECK='TRUE';
      NO_DIR_CHECK='TRUE';
      ALLOW_CONNECT='TRUE';
    'VSS578':
      PIN_NUMBER='(0,0,0,0,0,0,0,0,0,0,0,0,0,0,0,0,0,0,0,0,0,0,0,0,0,0,0,0,0,0,0~
,0,0,0,0,BT8,0,0,0,0,0,0)';
      PINUSE='POWER';
      NO_LOAD_CHECK='Both';
      NO_IO_CHECK='Both';
      NO_ASSERT_CHECK='TRUE';
      NO_DIR_CHECK='TRUE';
      ALLOW_CONNECT='TRUE';
    'VSS577':
      PIN_NUMBER='(0,0,0,0,0,0,0,0,0,0,0,0,0,0,0,0,0,0,0,0,0,0,0,0,0,0,0,0,0,0,0~
,0,0,0,0,BT4,0,0,0,0,0,0)';
      PINUSE='POWER';
      NO_LOAD_CHECK='Both';
      NO_IO_CHECK='Both';
      NO_ASSERT_CHECK='TRUE';
      NO_DIR_CHECK='TRUE';
      ALLOW_CONNECT='TRUE';
    'VSS576':
      PIN_NUMBER='(0,0,0,0,0,0,0,0,0,0,0,0,0,0,0,0,0,0,0,0,0,0,0,0,0,0,0,0,0,0,0~
,0,0,0,0,BT20,0,0,0,0,0,0)';
      PINUSE='POWER';
      NO_LOAD_CHECK='Both';
      NO_IO_CHECK='Both';
      NO_ASSERT_CHECK='TRUE';
      NO_DIR_CHECK='TRUE';
      ALLOW_CONNECT='TRUE';
    'VSS575':
      PIN_NUMBER='(0,0,0,0,0,0,0,0,0,0,0,0,0,0,0,0,0,0,0,0,0,0,0,0,0,0,0,0,0,0,0~
,0,0,0,0,BT16,0,0,0,0,0,0)';
      PINUSE='POWER';
      NO_LOAD_CHECK='Both';
      NO_IO_CHECK='Both';
      NO_ASSERT_CHECK='TRUE';
      NO_DIR_CHECK='TRUE';
      ALLOW_CONNECT='TRUE';
    'VSS574':
      PIN_NUMBER='(0,0,0,0,0,0,0,0,0,0,0,0,0,0,0,0,0,0,0,0,0,0,0,0,0,0,0,0,0,0,0~
,0,0,0,0,BT12,0,0,0,0,0,0)';
      PINUSE='POWER';
      NO_LOAD_CHECK='Both';
      NO_IO_CHECK='Both';
      NO_ASSERT_CHECK='TRUE';
      NO_DIR_CHECK='TRUE';
      ALLOW_CONNECT='TRUE';
    'VSS573':
      PIN_NUMBER='(0,0,0,0,0,0,0,0,0,0,0,0,0,0,0,0,0,0,0,0,0,0,0,0,0,0,0,0,0,0,0~
,0,0,0,0,BR90,0,0,0,0,0,0)';
      PINUSE='POWER';
      NO_LOAD_CHECK='Both';
      NO_IO_CHECK='Both';
      NO_ASSERT_CHECK='TRUE';
      NO_DIR_CHECK='TRUE';
      ALLOW_CONNECT='TRUE';
    'VSS570':
      PIN_NUMBER='(0,0,0,0,0,0,0,0,0,0,0,0,0,0,0,0,0,0,0,0,0,0,0,0,0,0,0,0,0,0,0~
,0,0,0,0,BR88,0,0,0,0,0,0)';
      PINUSE='POWER';
      NO_LOAD_CHECK='Both';
      NO_IO_CHECK='Both';
      NO_ASSERT_CHECK='TRUE';
      NO_DIR_CHECK='TRUE';
      ALLOW_CONNECT='TRUE';
    'VSS569':
      PIN_NUMBER='(0,0,0,0,0,0,0,0,0,0,0,0,0,0,0,0,0,0,0,0,0,0,0,0,0,0,0,0,0,0,0~
,0,0,0,0,BR86,0,0,0,0,0,0)';
      PINUSE='POWER';
      NO_LOAD_CHECK='Both';
      NO_IO_CHECK='Both';
      NO_ASSERT_CHECK='TRUE';
      NO_DIR_CHECK='TRUE';
      ALLOW_CONNECT='TRUE';
    'VSS568':
      PIN_NUMBER='(0,0,0,0,0,0,0,0,0,0,0,0,0,0,0,0,0,0,0,0,0,0,0,0,0,0,0,0,0,0,0~
,0,0,0,0,BR84,0,0,0,0,0,0)';
      PINUSE='POWER';
      NO_LOAD_CHECK='Both';
      NO_IO_CHECK='Both';
      NO_ASSERT_CHECK='TRUE';
      NO_DIR_CHECK='TRUE';
      ALLOW_CONNECT='TRUE';
    'VSS567':
      PIN_NUMBER='(0,0,0,0,0,0,0,0,0,0,0,0,0,0,0,0,0,0,0,0,0,0,0,0,0,0,0,0,0,0,0~
,0,0,0,0,BR82,0,0,0,0,0,0)';
      PINUSE='POWER';
      NO_LOAD_CHECK='Both';
      NO_IO_CHECK='Both';
      NO_ASSERT_CHECK='TRUE';
      NO_DIR_CHECK='TRUE';
      ALLOW_CONNECT='TRUE';
    'VSS566':
      PIN_NUMBER='(0,0,0,0,0,0,0,0,0,0,0,0,0,0,0,0,0,0,0,0,0,0,0,0,0,0,0,0,0,0,0~
,0,0,0,0,BR80,0,0,0,0,0,0)';
      PINUSE='POWER';
      NO_LOAD_CHECK='Both';
      NO_IO_CHECK='Both';
      NO_ASSERT_CHECK='TRUE';
      NO_DIR_CHECK='TRUE';
      ALLOW_CONNECT='TRUE';
    'VSS565':
      PIN_NUMBER='(0,0,0,0,0,0,0,0,0,0,0,0,0,0,0,0,0,0,0,0,0,0,0,0,0,0,0,0,0,0,0~
,0,0,0,0,BR76,0,0,0,0,0,0)';
      PINUSE='POWER';
      NO_LOAD_CHECK='Both';
      NO_IO_CHECK='Both';
      NO_ASSERT_CHECK='TRUE';
      NO_DIR_CHECK='TRUE';
      ALLOW_CONNECT='TRUE';
    'VSS564':
      PIN_NUMBER='(0,0,0,0,0,0,0,0,0,0,0,0,0,0,0,0,0,0,0,0,0,0,0,0,0,0,0,0,0,0,0~
,0,0,0,0,BR74,0,0,0,0,0,0)';
      PINUSE='POWER';
      NO_LOAD_CHECK='Both';
      NO_IO_CHECK='Both';
      NO_ASSERT_CHECK='TRUE';
      NO_DIR_CHECK='TRUE';
      ALLOW_CONNECT='TRUE';
    'VSS563':
      PIN_NUMBER='(0,0,0,0,0,0,0,0,0,0,0,0,0,0,0,0,0,0,0,0,0,0,0,0,0,0,0,0,0,0,0~
,0,0,0,0,BR72,0,0,0,0,0,0)';
      PINUSE='POWER';
      NO_LOAD_CHECK='Both';
      NO_IO_CHECK='Both';
      NO_ASSERT_CHECK='TRUE';
      NO_DIR_CHECK='TRUE';
      ALLOW_CONNECT='TRUE';
    'VSS561':
      PIN_NUMBER='(0,0,0,0,0,0,0,0,0,0,0,0,0,0,0,0,0,0,0,0,0,0,0,0,0,0,0,0,0,0,0~
,0,0,0,0,BR70,0,0,0,0,0,0)';
      PINUSE='POWER';
      NO_LOAD_CHECK='Both';
      NO_IO_CHECK='Both';
      NO_ASSERT_CHECK='TRUE';
      NO_DIR_CHECK='TRUE';
      ALLOW_CONNECT='TRUE';
    'VSS560':
      PIN_NUMBER='(0,0,0,0,0,0,0,0,0,0,0,0,0,0,0,0,0,0,0,0,0,0,0,0,0,0,0,0,0,0,0~
,0,0,0,0,BR68,0,0,0,0,0,0)';
      PINUSE='POWER';
      NO_LOAD_CHECK='Both';
      NO_IO_CHECK='Both';
      NO_ASSERT_CHECK='TRUE';
      NO_DIR_CHECK='TRUE';
      ALLOW_CONNECT='TRUE';
    'VSS559':
      PIN_NUMBER='(0,0,0,0,0,0,0,0,0,0,0,0,0,0,0,0,0,0,0,0,0,0,0,0,0,0,0,0,0,0,0~
,0,0,0,0,BR66,0,0,0,0,0,0)';
      PINUSE='POWER';
      NO_LOAD_CHECK='Both';
      NO_IO_CHECK='Both';
      NO_ASSERT_CHECK='TRUE';
      NO_DIR_CHECK='TRUE';
      ALLOW_CONNECT='TRUE';
    'VSS557':
      PIN_NUMBER='(0,0,0,0,0,0,0,0,0,0,0,0,0,0,0,0,0,0,0,0,0,0,0,0,0,0,0,0,0,0,0~
,0,0,0,0,BR64,0,0,0,0,0,0)';
      PINUSE='POWER';
      NO_LOAD_CHECK='Both';
      NO_IO_CHECK='Both';
      NO_ASSERT_CHECK='TRUE';
      NO_DIR_CHECK='TRUE';
      ALLOW_CONNECT='TRUE';
    'VSS556':
      PIN_NUMBER='(0,0,0,0,0,0,0,0,0,0,0,0,0,0,0,0,0,0,0,0,0,0,0,0,0,0,0,0,0,0,0~
,0,0,0,0,BR58,0,0,0,0,0,0)';
      PINUSE='POWER';
      NO_LOAD_CHECK='Both';
      NO_IO_CHECK='Both';
      NO_ASSERT_CHECK='TRUE';
      NO_DIR_CHECK='TRUE';
      ALLOW_CONNECT='TRUE';
    'VSS555':
      PIN_NUMBER='(0,0,0,0,0,0,0,0,0,0,0,0,0,0,0,0,0,0,0,0,0,0,0,0,0,0,0,0,0,0,0~
,0,0,0,0,BR56,0,0,0,0,0,0)';
      PINUSE='POWER';
      NO_LOAD_CHECK='Both';
      NO_IO_CHECK='Both';
      NO_ASSERT_CHECK='TRUE';
      NO_DIR_CHECK='TRUE';
      ALLOW_CONNECT='TRUE';
    'VSS552':
      PIN_NUMBER='(0,0,0,0,0,0,0,0,0,0,0,0,0,0,0,0,0,0,0,0,0,0,0,0,0,0,0,0,0,0,0~
,0,0,0,0,BR54,0,0,0,0,0,0)';
      PINUSE='POWER';
      NO_LOAD_CHECK='Both';
      NO_IO_CHECK='Both';
      NO_ASSERT_CHECK='TRUE';
      NO_DIR_CHECK='TRUE';
      ALLOW_CONNECT='TRUE';
    'VSS551':
      PIN_NUMBER='(0,0,0,0,0,0,0,0,0,0,0,0,0,0,0,0,0,0,0,0,0,0,0,0,0,0,0,0,0,0,0~
,0,0,0,0,BR52,0,0,0,0,0,0)';
      PINUSE='POWER';
      NO_LOAD_CHECK='Both';
      NO_IO_CHECK='Both';
      NO_ASSERT_CHECK='TRUE';
      NO_DIR_CHECK='TRUE';
      ALLOW_CONNECT='TRUE';
    'VSS550':
      PIN_NUMBER='(0,0,0,0,0,0,0,0,0,0,0,0,0,0,0,0,0,0,0,0,0,0,0,0,0,0,0,0,0,0,0~
,0,0,0,0,BR50,0,0,0,0,0,0)';
      PINUSE='POWER';
      NO_LOAD_CHECK='Both';
      NO_IO_CHECK='Both';
      NO_ASSERT_CHECK='TRUE';
      NO_DIR_CHECK='TRUE';
      ALLOW_CONNECT='TRUE';
    'VSS549':
      PIN_NUMBER='(0,0,0,0,0,0,0,0,0,0,0,0,0,0,0,0,0,0,0,0,0,0,0,0,0,0,0,0,0,0,0~
,0,0,0,0,BR48,0,0,0,0,0,0)';
      PINUSE='POWER';
      NO_LOAD_CHECK='Both';
      NO_IO_CHECK='Both';
      NO_ASSERT_CHECK='TRUE';
      NO_DIR_CHECK='TRUE';
      ALLOW_CONNECT='TRUE';
    'VSS548':
      PIN_NUMBER='(0,0,0,0,0,0,0,0,0,0,0,0,0,0,0,0,0,0,0,0,0,0,0,0,0,0,0,0,0,0,0~
,0,0,0,0,BR45,0,0,0,0,0,0)';
      PINUSE='POWER';
      NO_LOAD_CHECK='Both';
      NO_IO_CHECK='Both';
      NO_ASSERT_CHECK='TRUE';
      NO_DIR_CHECK='TRUE';
      ALLOW_CONNECT='TRUE';
    'VSS547':
      PIN_NUMBER='(0,0,0,0,0,0,0,0,0,0,0,0,0,0,0,0,0,0,0,0,0,0,0,0,0,0,0,0,0,0,0~
,0,0,0,0,BR43,0,0,0,0,0,0)';
      PINUSE='POWER';
      NO_LOAD_CHECK='Both';
      NO_IO_CHECK='Both';
      NO_ASSERT_CHECK='TRUE';
      NO_DIR_CHECK='TRUE';
      ALLOW_CONNECT='TRUE';
    'VSS546':
      PIN_NUMBER='(0,0,0,0,0,0,0,0,0,0,0,0,0,0,0,0,0,0,0,0,0,0,0,0,0,0,0,0,0,0,0~
,0,0,0,0,BR41,0,0,0,0,0,0)';
      PINUSE='POWER';
      NO_LOAD_CHECK='Both';
      NO_IO_CHECK='Both';
      NO_ASSERT_CHECK='TRUE';
      NO_DIR_CHECK='TRUE';
      ALLOW_CONNECT='TRUE';
    'VSS545':
      PIN_NUMBER='(0,0,0,0,0,0,0,0,0,0,0,0,0,0,0,0,0,0,0,0,0,0,0,0,0,0,0,0,0,0,0~
,0,0,0,0,BR39,0,0,0,0,0,0)';
      PINUSE='POWER';
      NO_LOAD_CHECK='Both';
      NO_IO_CHECK='Both';
      NO_ASSERT_CHECK='TRUE';
      NO_DIR_CHECK='TRUE';
      ALLOW_CONNECT='TRUE';
    'VSS543':
      PIN_NUMBER='(0,0,0,0,0,0,0,0,0,0,0,0,0,0,0,0,0,0,0,0,0,0,0,0,0,0,0,0,0,0,0~
,0,0,0,0,BR37,0,0,0,0,0,0)';
      PINUSE='POWER';
      NO_LOAD_CHECK='Both';
      NO_IO_CHECK='Both';
      NO_ASSERT_CHECK='TRUE';
      NO_DIR_CHECK='TRUE';
      ALLOW_CONNECT='TRUE';
    'VSS542':
      PIN_NUMBER='(0,0,0,0,0,0,0,0,0,0,0,0,0,0,0,0,0,0,0,0,0,0,0,0,0,0,0,0,0,0,0~
,0,0,0,0,BR35,0,0,0,0,0,0)';
      PINUSE='POWER';
      NO_LOAD_CHECK='Both';
      NO_IO_CHECK='Both';
      NO_ASSERT_CHECK='TRUE';
      NO_DIR_CHECK='TRUE';
      ALLOW_CONNECT='TRUE';
    'VSS396':
      PIN_NUMBER='(0,0,0,0,0,0,0,0,0,0,0,0,0,0,0,0,0,0,0,0,0,0,0,0,0,0,0,0,0,0,0~
,0,0,0,0,CK4,0,0,0,0,0,0)';
      PINUSE='POWER';
      NO_LOAD_CHECK='Both';
      NO_IO_CHECK='Both';
      NO_ASSERT_CHECK='TRUE';
      NO_DIR_CHECK='TRUE';
      ALLOW_CONNECT='TRUE';
    'VSS383':
      PIN_NUMBER='(0,0,0,0,0,0,0,0,0,0,0,0,0,0,0,0,0,0,0,0,0,0,0,0,0,0,0,0,0,0,0~
,0,0,0,0,CJ76,0,0,0,0,0,0)';
      PINUSE='POWER';
      NO_LOAD_CHECK='Both';
      NO_IO_CHECK='Both';
      NO_ASSERT_CHECK='TRUE';
      NO_DIR_CHECK='TRUE';
      ALLOW_CONNECT='TRUE';
    'VSS572':
      PIN_NUMBER='(0,0,0,0,0,0,0,0,0,0,0,0,0,0,0,0,0,0,0,0,0,0,0,0,0,0,0,0,0,0,0~
,0,0,0,0,0,BR9,0,0,0,0,0)';
      PINUSE='POWER';
      NO_LOAD_CHECK='Both';
      NO_IO_CHECK='Both';
      NO_ASSERT_CHECK='TRUE';
      NO_DIR_CHECK='TRUE';
      ALLOW_CONNECT='TRUE';
    'VSS541':
      PIN_NUMBER='(0,0,0,0,0,0,0,0,0,0,0,0,0,0,0,0,0,0,0,0,0,0,0,0,0,0,0,0,0,0,0~
,0,0,0,0,0,BR33,0,0,0,0,0)';
      PINUSE='POWER';
      NO_LOAD_CHECK='Both';
      NO_IO_CHECK='Both';
      NO_ASSERT_CHECK='TRUE';
      NO_DIR_CHECK='TRUE';
      ALLOW_CONNECT='TRUE';
    'VSS540':
      PIN_NUMBER='(0,0,0,0,0,0,0,0,0,0,0,0,0,0,0,0,0,0,0,0,0,0,0,0,0,0,0,0,0,0,0~
,0,0,0,0,0,BR31,0,0,0,0,0)';
      PINUSE='POWER';
      NO_LOAD_CHECK='Both';
      NO_IO_CHECK='Both';
      NO_ASSERT_CHECK='TRUE';
      NO_DIR_CHECK='TRUE';
      ALLOW_CONNECT='TRUE';
    'VSS539':
      PIN_NUMBER='(0,0,0,0,0,0,0,0,0,0,0,0,0,0,0,0,0,0,0,0,0,0,0,0,0,0,0,0,0,0,0~
,0,0,0,0,0,BR29,0,0,0,0,0)';
      PINUSE='POWER';
      NO_LOAD_CHECK='Both';
      NO_IO_CHECK='Both';
      NO_ASSERT_CHECK='TRUE';
      NO_DIR_CHECK='TRUE';
      ALLOW_CONNECT='TRUE';
    'VSS538':
      PIN_NUMBER='(0,0,0,0,0,0,0,0,0,0,0,0,0,0,0,0,0,0,0,0,0,0,0,0,0,0,0,0,0,0,0~
,0,0,0,0,0,BR27,0,0,0,0,0)';
      PINUSE='POWER';
      NO_LOAD_CHECK='Both';
      NO_IO_CHECK='Both';
      NO_ASSERT_CHECK='TRUE';
      NO_DIR_CHECK='TRUE';
      ALLOW_CONNECT='TRUE';
    'VSS536':
      PIN_NUMBER='(0,0,0,0,0,0,0,0,0,0,0,0,0,0,0,0,0,0,0,0,0,0,0,0,0,0,0,0,0,0,0~
,0,0,0,0,0,BR17,0,0,0,0,0)';
      PINUSE='POWER';
      NO_LOAD_CHECK='Both';
      NO_IO_CHECK='Both';
      NO_ASSERT_CHECK='TRUE';
      NO_DIR_CHECK='TRUE';
      ALLOW_CONNECT='TRUE';
    'VSS535':
      PIN_NUMBER='(0,0,0,0,0,0,0,0,0,0,0,0,0,0,0,0,0,0,0,0,0,0,0,0,0,0,0,0,0,0,0~
,0,0,0,0,0,BR13,0,0,0,0,0)';
      PINUSE='POWER';
      NO_LOAD_CHECK='Both';
      NO_IO_CHECK='Both';
      NO_ASSERT_CHECK='TRUE';
      NO_DIR_CHECK='TRUE';
      ALLOW_CONNECT='TRUE';
    'VSS533':
      PIN_NUMBER='(0,0,0,0,0,0,0,0,0,0,0,0,0,0,0,0,0,0,0,0,0,0,0,0,0,0,0,0,0,0,0~
,0,0,0,0,0,BP8,0,0,0,0,0)';
      PINUSE='POWER';
      NO_LOAD_CHECK='Both';
      NO_IO_CHECK='Both';
      NO_ASSERT_CHECK='TRUE';
      NO_DIR_CHECK='TRUE';
      ALLOW_CONNECT='TRUE';
    'VSS532':
      PIN_NUMBER='(0,0,0,0,0,0,0,0,0,0,0,0,0,0,0,0,0,0,0,0,0,0,0,0,0,0,0,0,0,0,0~
,0,0,0,0,0,BP77,0,0,0,0,0)';
      PINUSE='POWER';
      NO_LOAD_CHECK='Both';
      NO_IO_CHECK='Both';
      NO_ASSERT_CHECK='TRUE';
      NO_DIR_CHECK='TRUE';
      ALLOW_CONNECT='TRUE';
    'VSS531':
      PIN_NUMBER='(0,0,0,0,0,0,0,0,0,0,0,0,0,0,0,0,0,0,0,0,0,0,0,0,0,0,0,0,0,0,0~
,0,0,0,0,0,BP75,0,0,0,0,0)';
      PINUSE='POWER';
      NO_LOAD_CHECK='Both';
      NO_IO_CHECK='Both';
      NO_ASSERT_CHECK='TRUE';
      NO_DIR_CHECK='TRUE';
      ALLOW_CONNECT='TRUE';
    'VSS530':
      PIN_NUMBER='(0,0,0,0,0,0,0,0,0,0,0,0,0,0,0,0,0,0,0,0,0,0,0,0,0,0,0,0,0,0,0~
,0,0,0,0,0,BP73,0,0,0,0,0)';
      PINUSE='POWER';
      NO_LOAD_CHECK='Both';
      NO_IO_CHECK='Both';
      NO_ASSERT_CHECK='TRUE';
      NO_DIR_CHECK='TRUE';
      ALLOW_CONNECT='TRUE';
    'VSS529':
      PIN_NUMBER='(0,0,0,0,0,0,0,0,0,0,0,0,0,0,0,0,0,0,0,0,0,0,0,0,0,0,0,0,0,0,0~
,0,0,0,0,0,BP71,0,0,0,0,0)';
      PINUSE='POWER';
      NO_LOAD_CHECK='Both';
      NO_IO_CHECK='Both';
      NO_ASSERT_CHECK='TRUE';
      NO_DIR_CHECK='TRUE';
      ALLOW_CONNECT='TRUE';
    'VSS528':
      PIN_NUMBER='(0,0,0,0,0,0,0,0,0,0,0,0,0,0,0,0,0,0,0,0,0,0,0,0,0,0,0,0,0,0,0~
,0,0,0,0,0,BP63,0,0,0,0,0)';
      PINUSE='POWER';
      NO_LOAD_CHECK='Both';
      NO_IO_CHECK='Both';
      NO_ASSERT_CHECK='TRUE';
      NO_DIR_CHECK='TRUE';
      ALLOW_CONNECT='TRUE';
    'VSS527':
      PIN_NUMBER='(0,0,0,0,0,0,0,0,0,0,0,0,0,0,0,0,0,0,0,0,0,0,0,0,0,0,0,0,0,0,0~
,0,0,0,0,0,BP4,0,0,0,0,0)';
      PINUSE='POWER';
      NO_LOAD_CHECK='Both';
      NO_IO_CHECK='Both';
      NO_ASSERT_CHECK='TRUE';
      NO_DIR_CHECK='TRUE';
      ALLOW_CONNECT='TRUE';
    'VSS525':
      PIN_NUMBER='(0,0,0,0,0,0,0,0,0,0,0,0,0,0,0,0,0,0,0,0,0,0,0,0,0,0,0,0,0,0,0~
,0,0,0,0,0,BP20,0,0,0,0,0)';
      PINUSE='POWER';
      NO_LOAD_CHECK='Both';
      NO_IO_CHECK='Both';
      NO_ASSERT_CHECK='TRUE';
      NO_DIR_CHECK='TRUE';
      ALLOW_CONNECT='TRUE';
    'VSS524':
      PIN_NUMBER='(0,0,0,0,0,0,0,0,0,0,0,0,0,0,0,0,0,0,0,0,0,0,0,0,0,0,0,0,0,0,0~
,0,0,0,0,0,BP2,0,0,0,0,0)';
      PINUSE='POWER';
      NO_LOAD_CHECK='Both';
      NO_IO_CHECK='Both';
      NO_ASSERT_CHECK='TRUE';
      NO_DIR_CHECK='TRUE';
      ALLOW_CONNECT='TRUE';
    'VSS523':
      PIN_NUMBER='(0,0,0,0,0,0,0,0,0,0,0,0,0,0,0,0,0,0,0,0,0,0,0,0,0,0,0,0,0,0,0~
,0,0,0,0,0,BP16,0,0,0,0,0)';
      PINUSE='POWER';
      NO_LOAD_CHECK='Both';
      NO_IO_CHECK='Both';
      NO_ASSERT_CHECK='TRUE';
      NO_DIR_CHECK='TRUE';
      ALLOW_CONNECT='TRUE';
    'VSS522':
      PIN_NUMBER='(0,0,0,0,0,0,0,0,0,0,0,0,0,0,0,0,0,0,0,0,0,0,0,0,0,0,0,0,0,0,0~
,0,0,0,0,0,BP12,0,0,0,0,0)';
      PINUSE='POWER';
      NO_LOAD_CHECK='Both';
      NO_IO_CHECK='Both';
      NO_ASSERT_CHECK='TRUE';
      NO_DIR_CHECK='TRUE';
      ALLOW_CONNECT='TRUE';
    'VSS520':
      PIN_NUMBER='(0,0,0,0,0,0,0,0,0,0,0,0,0,0,0,0,0,0,0,0,0,0,0,0,0,0,0,0,0,0,0~
,0,0,0,0,0,BN70,0,0,0,0,0)';
      PINUSE='POWER';
      NO_LOAD_CHECK='Both';
      NO_IO_CHECK='Both';
      NO_ASSERT_CHECK='TRUE';
      NO_DIR_CHECK='TRUE';
      ALLOW_CONNECT='TRUE';
    'VSS519':
      PIN_NUMBER='(0,0,0,0,0,0,0,0,0,0,0,0,0,0,0,0,0,0,0,0,0,0,0,0,0,0,0,0,0,0,0~
,0,0,0,0,0,BN62,0,0,0,0,0)';
      PINUSE='POWER';
      NO_LOAD_CHECK='Both';
      NO_IO_CHECK='Both';
      NO_ASSERT_CHECK='TRUE';
      NO_DIR_CHECK='TRUE';
      ALLOW_CONNECT='TRUE';
    'VSS518':
      PIN_NUMBER='(0,0,0,0,0,0,0,0,0,0,0,0,0,0,0,0,0,0,0,0,0,0,0,0,0,0,0,0,0,0,0~
,0,0,0,0,0,BN31,0,0,0,0,0)';
      PINUSE='POWER';
      NO_LOAD_CHECK='Both';
      NO_IO_CHECK='Both';
      NO_ASSERT_CHECK='TRUE';
      NO_DIR_CHECK='TRUE';
      ALLOW_CONNECT='TRUE';
    'VSS517':
      PIN_NUMBER='(0,0,0,0,0,0,0,0,0,0,0,0,0,0,0,0,0,0,0,0,0,0,0,0,0,0,0,0,0,0,0~
,0,0,0,0,0,BM8,0,0,0,0,0)';
      PINUSE='POWER';
      NO_LOAD_CHECK='Both';
      NO_IO_CHECK='Both';
      NO_ASSERT_CHECK='TRUE';
      NO_DIR_CHECK='TRUE';
      ALLOW_CONNECT='TRUE';
    'VSS516':
      PIN_NUMBER='(0,0,0,0,0,0,0,0,0,0,0,0,0,0,0,0,0,0,0,0,0,0,0,0,0,0,0,0,0,0,0~
,0,0,0,0,0,BM77,0,0,0,0,0)';
      PINUSE='POWER';
      NO_LOAD_CHECK='Both';
      NO_IO_CHECK='Both';
      NO_ASSERT_CHECK='TRUE';
      NO_DIR_CHECK='TRUE';
      ALLOW_CONNECT='TRUE';
    'VSS515':
      PIN_NUMBER='(0,0,0,0,0,0,0,0,0,0,0,0,0,0,0,0,0,0,0,0,0,0,0,0,0,0,0,0,0,0,0~
,0,0,0,0,0,BM73,0,0,0,0,0)';
      PINUSE='POWER';
      NO_LOAD_CHECK='Both';
      NO_IO_CHECK='Both';
      NO_ASSERT_CHECK='TRUE';
      NO_DIR_CHECK='TRUE';
      ALLOW_CONNECT='TRUE';
    'VSS513':
      PIN_NUMBER='(0,0,0,0,0,0,0,0,0,0,0,0,0,0,0,0,0,0,0,0,0,0,0,0,0,0,0,0,0,0,0~
,0,0,0,0,0,BM61,0,0,0,0,0)';
      PINUSE='POWER';
      NO_LOAD_CHECK='Both';
      NO_IO_CHECK='Both';
      NO_ASSERT_CHECK='TRUE';
      NO_DIR_CHECK='TRUE';
      ALLOW_CONNECT='TRUE';
    'VSS512':
      PIN_NUMBER='(0,0,0,0,0,0,0,0,0,0,0,0,0,0,0,0,0,0,0,0,0,0,0,0,0,0,0,0,0,0,0~
,0,0,0,0,0,BM4,0,0,0,0,0)';
      PINUSE='POWER';
      NO_LOAD_CHECK='Both';
      NO_IO_CHECK='Both';
      NO_ASSERT_CHECK='TRUE';
      NO_DIR_CHECK='TRUE';
      ALLOW_CONNECT='TRUE';
    'VSS511':
      PIN_NUMBER='(0,0,0,0,0,0,0,0,0,0,0,0,0,0,0,0,0,0,0,0,0,0,0,0,0,0,0,0,0,0,0~
,0,0,0,0,0,BM26,0,0,0,0,0)';
      PINUSE='POWER';
      NO_LOAD_CHECK='Both';
      NO_IO_CHECK='Both';
      NO_ASSERT_CHECK='TRUE';
      NO_DIR_CHECK='TRUE';
      ALLOW_CONNECT='TRUE';
    'VSS510':
      PIN_NUMBER='(0,0,0,0,0,0,0,0,0,0,0,0,0,0,0,0,0,0,0,0,0,0,0,0,0,0,0,0,0,0,0~
,0,0,0,0,0,BM24,0,0,0,0,0)';
      PINUSE='POWER';
      NO_LOAD_CHECK='Both';
      NO_IO_CHECK='Both';
      NO_ASSERT_CHECK='TRUE';
      NO_DIR_CHECK='TRUE';
      ALLOW_CONNECT='TRUE';
    'VSS509':
      PIN_NUMBER='(0,0,0,0,0,0,0,0,0,0,0,0,0,0,0,0,0,0,0,0,0,0,0,0,0,0,0,0,0,0,0~
,0,0,0,0,0,BM22,0,0,0,0,0)';
      PINUSE='POWER';
      NO_LOAD_CHECK='Both';
      NO_IO_CHECK='Both';
      NO_ASSERT_CHECK='TRUE';
      NO_DIR_CHECK='TRUE';
      ALLOW_CONNECT='TRUE';
    'VSS508':
      PIN_NUMBER='(0,0,0,0,0,0,0,0,0,0,0,0,0,0,0,0,0,0,0,0,0,0,0,0,0,0,0,0,0,0,0~
,0,0,0,0,0,BM20,0,0,0,0,0)';
      PINUSE='POWER';
      NO_LOAD_CHECK='Both';
      NO_IO_CHECK='Both';
      NO_ASSERT_CHECK='TRUE';
      NO_DIR_CHECK='TRUE';
      ALLOW_CONNECT='TRUE';
    'VSS507':
      PIN_NUMBER='(0,0,0,0,0,0,0,0,0,0,0,0,0,0,0,0,0,0,0,0,0,0,0,0,0,0,0,0,0,0,0~
,0,0,0,0,0,BM16,0,0,0,0,0)';
      PINUSE='POWER';
      NO_LOAD_CHECK='Both';
      NO_IO_CHECK='Both';
      NO_ASSERT_CHECK='TRUE';
      NO_DIR_CHECK='TRUE';
      ALLOW_CONNECT='TRUE';
    'VSS506':
      PIN_NUMBER='(0,0,0,0,0,0,0,0,0,0,0,0,0,0,0,0,0,0,0,0,0,0,0,0,0,0,0,0,0,0,0~
,0,0,0,0,0,BM12,0,0,0,0,0)';
      PINUSE='POWER';
      NO_LOAD_CHECK='Both';
      NO_IO_CHECK='Both';
      NO_ASSERT_CHECK='TRUE';
      NO_DIR_CHECK='TRUE';
      ALLOW_CONNECT='TRUE';
    'VSS505':
      PIN_NUMBER='(0,0,0,0,0,0,0,0,0,0,0,0,0,0,0,0,0,0,0,0,0,0,0,0,0,0,0,0,0,0,0~
,0,0,0,0,0,BL9,0,0,0,0,0)';
      PINUSE='POWER';
      NO_LOAD_CHECK='Both';
      NO_IO_CHECK='Both';
      NO_ASSERT_CHECK='TRUE';
      NO_DIR_CHECK='TRUE';
      ALLOW_CONNECT='TRUE';
    'VSS504':
      PIN_NUMBER='(0,0,0,0,0,0,0,0,0,0,0,0,0,0,0,0,0,0,0,0,0,0,0,0,0,0,0,0,0,0,0~
,0,0,0,0,0,BL78,0,0,0,0,0)';
      PINUSE='POWER';
      NO_LOAD_CHECK='Both';
      NO_IO_CHECK='Both';
      NO_ASSERT_CHECK='TRUE';
      NO_DIR_CHECK='TRUE';
      ALLOW_CONNECT='TRUE';
    'VSS503':
      PIN_NUMBER='(0,0,0,0,0,0,0,0,0,0,0,0,0,0,0,0,0,0,0,0,0,0,0,0,0,0,0,0,0,0,0~
,0,0,0,0,0,BL72,0,0,0,0,0)';
      PINUSE='POWER';
      NO_LOAD_CHECK='Both';
      NO_IO_CHECK='Both';
      NO_ASSERT_CHECK='TRUE';
      NO_DIR_CHECK='TRUE';
      ALLOW_CONNECT='TRUE';
    'VSS502':
      PIN_NUMBER='(0,0,0,0,0,0,0,0,0,0,0,0,0,0,0,0,0,0,0,0,0,0,0,0,0,0,0,0,0,0,0~
,0,0,0,0,0,BL70,0,0,0,0,0)';
      PINUSE='POWER';
      NO_LOAD_CHECK='Both';
      NO_IO_CHECK='Both';
      NO_ASSERT_CHECK='TRUE';
      NO_DIR_CHECK='TRUE';
      ALLOW_CONNECT='TRUE';
    'VSS501':
      PIN_NUMBER='(0,0,0,0,0,0,0,0,0,0,0,0,0,0,0,0,0,0,0,0,0,0,0,0,0,0,0,0,0,0,0~
,0,0,0,0,0,BL68,0,0,0,0,0)';
      PINUSE='POWER';
      NO_LOAD_CHECK='Both';
      NO_IO_CHECK='Both';
      NO_ASSERT_CHECK='TRUE';
      NO_DIR_CHECK='TRUE';
      ALLOW_CONNECT='TRUE';
    'VSS500':
      PIN_NUMBER='(0,0,0,0,0,0,0,0,0,0,0,0,0,0,0,0,0,0,0,0,0,0,0,0,0,0,0,0,0,0,0~
,0,0,0,0,0,BL5,0,0,0,0,0)';
      PINUSE='POWER';
      NO_LOAD_CHECK='Both';
      NO_IO_CHECK='Both';
      NO_ASSERT_CHECK='TRUE';
      NO_DIR_CHECK='TRUE';
      ALLOW_CONNECT='TRUE';
    'VSS499':
      PIN_NUMBER='(0,0,0,0,0,0,0,0,0,0,0,0,0,0,0,0,0,0,0,0,0,0,0,0,0,0,0,0,0,0,0~
,0,0,0,0,0,BL17,0,0,0,0,0)';
      PINUSE='POWER';
      NO_LOAD_CHECK='Both';
      NO_IO_CHECK='Both';
      NO_ASSERT_CHECK='TRUE';
      NO_DIR_CHECK='TRUE';
      ALLOW_CONNECT='TRUE';
    'VSS498':
      PIN_NUMBER='(0,0,0,0,0,0,0,0,0,0,0,0,0,0,0,0,0,0,0,0,0,0,0,0,0,0,0,0,0,0,0~
,0,0,0,0,0,BL13,0,0,0,0,0)';
      PINUSE='POWER';
      NO_LOAD_CHECK='Both';
      NO_IO_CHECK='Both';
      NO_ASSERT_CHECK='TRUE';
      NO_DIR_CHECK='TRUE';
      ALLOW_CONNECT='TRUE';
    'VSS497':
      PIN_NUMBER='(0,0,0,0,0,0,0,0,0,0,0,0,0,0,0,0,0,0,0,0,0,0,0,0,0,0,0,0,0,0,0~
,0,0,0,0,0,BL1,0,0,0,0,0)';
      PINUSE='POWER';
      NO_LOAD_CHECK='Both';
      NO_IO_CHECK='Both';
      NO_ASSERT_CHECK='TRUE';
      NO_DIR_CHECK='TRUE';
      ALLOW_CONNECT='TRUE';
    'VSS496':
      PIN_NUMBER='(0,0,0,0,0,0,0,0,0,0,0,0,0,0,0,0,0,0,0,0,0,0,0,0,0,0,0,0,0,0,0~
,0,0,0,0,0,BK8,0,0,0,0,0)';
      PINUSE='POWER';
      NO_LOAD_CHECK='Both';
      NO_IO_CHECK='Both';
      NO_ASSERT_CHECK='TRUE';
      NO_DIR_CHECK='TRUE';
      ALLOW_CONNECT='TRUE';
    'VSS495':
      PIN_NUMBER='(0,0,0,0,0,0,0,0,0,0,0,0,0,0,0,0,0,0,0,0,0,0,0,0,0,0,0,0,0,0,0~
,0,0,0,0,0,BK79,0,0,0,0,0)';
      PINUSE='POWER';
      NO_LOAD_CHECK='Both';
      NO_IO_CHECK='Both';
      NO_ASSERT_CHECK='TRUE';
      NO_DIR_CHECK='TRUE';
      ALLOW_CONNECT='TRUE';
    'VSS494':
      PIN_NUMBER='(0,0,0,0,0,0,0,0,0,0,0,0,0,0,0,0,0,0,0,0,0,0,0,0,0,0,0,0,0,0,0~
,0,0,0,0,0,BK75,0,0,0,0,0)';
      PINUSE='POWER';
      NO_LOAD_CHECK='Both';
      NO_IO_CHECK='Both';
      NO_ASSERT_CHECK='TRUE';
      NO_DIR_CHECK='TRUE';
      ALLOW_CONNECT='TRUE';
    'VSS492':
      PIN_NUMBER='(0,0,0,0,0,0,0,0,0,0,0,0,0,0,0,0,0,0,0,0,0,0,0,0,0,0,0,0,0,0,0~
,0,0,0,0,0,BK71,0,0,0,0,0)';
      PINUSE='POWER';
      NO_LOAD_CHECK='Both';
      NO_IO_CHECK='Both';
      NO_ASSERT_CHECK='TRUE';
      NO_DIR_CHECK='TRUE';
      ALLOW_CONNECT='TRUE';
    'VSS491':
      PIN_NUMBER='(0,0,0,0,0,0,0,0,0,0,0,0,0,0,0,0,0,0,0,0,0,0,0,0,0,0,0,0,0,0,0~
,0,0,0,0,0,BK65,0,0,0,0,0)';
      PINUSE='POWER';
      NO_LOAD_CHECK='Both';
      NO_IO_CHECK='Both';
      NO_ASSERT_CHECK='TRUE';
      NO_DIR_CHECK='TRUE';
      ALLOW_CONNECT='TRUE';
    'VSS490':
      PIN_NUMBER='(0,0,0,0,0,0,0,0,0,0,0,0,0,0,0,0,0,0,0,0,0,0,0,0,0,0,0,0,0,0,0~
,0,0,0,0,0,BK4,0,0,0,0,0)';
      PINUSE='POWER';
      NO_LOAD_CHECK='Both';
      NO_IO_CHECK='Both';
      NO_ASSERT_CHECK='TRUE';
      NO_DIR_CHECK='TRUE';
      ALLOW_CONNECT='TRUE';
    'VSS489':
      PIN_NUMBER='(0,0,0,0,0,0,0,0,0,0,0,0,0,0,0,0,0,0,0,0,0,0,0,0,0,0,0,0,0,0,0~
,0,0,0,0,0,BK20,0,0,0,0,0)';
      PINUSE='POWER';
      NO_LOAD_CHECK='Both';
      NO_IO_CHECK='Both';
      NO_ASSERT_CHECK='TRUE';
      NO_DIR_CHECK='TRUE';
      ALLOW_CONNECT='TRUE';
    'VSS488':
      PIN_NUMBER='(0,0,0,0,0,0,0,0,0,0,0,0,0,0,0,0,0,0,0,0,0,0,0,0,0,0,0,0,0,0,0~
,0,0,0,0,0,BK16,0,0,0,0,0)';
      PINUSE='POWER';
      NO_LOAD_CHECK='Both';
      NO_IO_CHECK='Both';
      NO_ASSERT_CHECK='TRUE';
      NO_DIR_CHECK='TRUE';
      ALLOW_CONNECT='TRUE';
    'VSS487':
      PIN_NUMBER='(0,0,0,0,0,0,0,0,0,0,0,0,0,0,0,0,0,0,0,0,0,0,0,0,0,0,0,0,0,0,0~
,0,0,0,0,0,BK12,0,0,0,0,0)';
      PINUSE='POWER';
      NO_LOAD_CHECK='Both';
      NO_IO_CHECK='Both';
      NO_ASSERT_CHECK='TRUE';
      NO_DIR_CHECK='TRUE';
      ALLOW_CONNECT='TRUE';
    'VSS486':
      PIN_NUMBER='(0,0,0,0,0,0,0,0,0,0,0,0,0,0,0,0,0,0,0,0,0,0,0,0,0,0,0,0,0,0,0~
,0,0,0,0,0,BJ90,0,0,0,0,0)';
      PINUSE='POWER';
      NO_LOAD_CHECK='Both';
      NO_IO_CHECK='Both';
      NO_ASSERT_CHECK='TRUE';
      NO_DIR_CHECK='TRUE';
      ALLOW_CONNECT='TRUE';
    'VSS485':
      PIN_NUMBER='(0,0,0,0,0,0,0,0,0,0,0,0,0,0,0,0,0,0,0,0,0,0,0,0,0,0,0,0,0,0,0~
,0,0,0,0,0,BJ88,0,0,0,0,0)';
      PINUSE='POWER';
      NO_LOAD_CHECK='Both';
      NO_IO_CHECK='Both';
      NO_ASSERT_CHECK='TRUE';
      NO_DIR_CHECK='TRUE';
      ALLOW_CONNECT='TRUE';
    'VSS484':
      PIN_NUMBER='(0,0,0,0,0,0,0,0,0,0,0,0,0,0,0,0,0,0,0,0,0,0,0,0,0,0,0,0,0,0,0~
,0,0,0,0,0,BJ86,0,0,0,0,0)';
      PINUSE='POWER';
      NO_LOAD_CHECK='Both';
      NO_IO_CHECK='Both';
      NO_ASSERT_CHECK='TRUE';
      NO_DIR_CHECK='TRUE';
      ALLOW_CONNECT='TRUE';
    'VSS483':
      PIN_NUMBER='(0,0,0,0,0,0,0,0,0,0,0,0,0,0,0,0,0,0,0,0,0,0,0,0,0,0,0,0,0,0,0~
,0,0,0,0,0,BJ84,0,0,0,0,0)';
      PINUSE='POWER';
      NO_LOAD_CHECK='Both';
      NO_IO_CHECK='Both';
      NO_ASSERT_CHECK='TRUE';
      NO_DIR_CHECK='TRUE';
      ALLOW_CONNECT='TRUE';
    'VSS482':
      PIN_NUMBER='(0,0,0,0,0,0,0,0,0,0,0,0,0,0,0,0,0,0,0,0,0,0,0,0,0,0,0,0,0,0,0~
,0,0,0,0,0,BJ82,0,0,0,0,0)';
      PINUSE='POWER';
      NO_LOAD_CHECK='Both';
      NO_IO_CHECK='Both';
      NO_ASSERT_CHECK='TRUE';
      NO_DIR_CHECK='TRUE';
      ALLOW_CONNECT='TRUE';
    'VSS481':
      PIN_NUMBER='(0,0,0,0,0,0,0,0,0,0,0,0,0,0,0,0,0,0,0,0,0,0,0,0,0,0,0,0,0,0,0~
,0,0,0,0,0,BJ80,0,0,0,0,0)';
      PINUSE='POWER';
      NO_LOAD_CHECK='Both';
      NO_IO_CHECK='Both';
      NO_ASSERT_CHECK='TRUE';
      NO_DIR_CHECK='TRUE';
      ALLOW_CONNECT='TRUE';
    'VSS480':
      PIN_NUMBER='(0,0,0,0,0,0,0,0,0,0,0,0,0,0,0,0,0,0,0,0,0,0,0,0,0,0,0,0,0,0,0~
,0,0,0,0,0,BJ68,0,0,0,0,0)';
      PINUSE='POWER';
      NO_LOAD_CHECK='Both';
      NO_IO_CHECK='Both';
      NO_ASSERT_CHECK='TRUE';
      NO_DIR_CHECK='TRUE';
      ALLOW_CONNECT='TRUE';
    'VSS479':
      PIN_NUMBER='(0,0,0,0,0,0,0,0,0,0,0,0,0,0,0,0,0,0,0,0,0,0,0,0,0,0,0,0,0,0,0~
,0,0,0,0,0,BJ62,0,0,0,0,0)';
      PINUSE='POWER';
      NO_LOAD_CHECK='Both';
      NO_IO_CHECK='Both';
      NO_ASSERT_CHECK='TRUE';
      NO_DIR_CHECK='TRUE';
      ALLOW_CONNECT='TRUE';
    'VSS477':
      PIN_NUMBER='(0,0,0,0,0,0,0,0,0,0,0,0,0,0,0,0,0,0,0,0,0,0,0,0,0,0,0,0,0,0,0~
,0,0,0,0,0,BH83,0,0,0,0,0)';
      PINUSE='POWER';
      NO_LOAD_CHECK='Both';
      NO_IO_CHECK='Both';
      NO_ASSERT_CHECK='TRUE';
      NO_DIR_CHECK='TRUE';
      ALLOW_CONNECT='TRUE';
    'VSS476':
      PIN_NUMBER='(0,0,0,0,0,0,0,0,0,0,0,0,0,0,0,0,0,0,0,0,0,0,0,0,0,0,0,0,0,0,0~
,0,0,0,0,0,BH81,0,0,0,0,0)';
      PINUSE='POWER';
      NO_LOAD_CHECK='Both';
      NO_IO_CHECK='Both';
      NO_ASSERT_CHECK='TRUE';
      NO_DIR_CHECK='TRUE';
      ALLOW_CONNECT='TRUE';
    'VSS475':
      PIN_NUMBER='(0,0,0,0,0,0,0,0,0,0,0,0,0,0,0,0,0,0,0,0,0,0,0,0,0,0,0,0,0,0,0~
,0,0,0,0,0,BH8,0,0,0,0,0)';
      PINUSE='POWER';
      NO_LOAD_CHECK='Both';
      NO_IO_CHECK='Both';
      NO_ASSERT_CHECK='TRUE';
      NO_DIR_CHECK='TRUE';
      ALLOW_CONNECT='TRUE';
    'VSS474':
      PIN_NUMBER='(0,0,0,0,0,0,0,0,0,0,0,0,0,0,0,0,0,0,0,0,0,0,0,0,0,0,0,0,0,0,0~
,0,0,0,0,0,BH77,0,0,0,0,0)';
      PINUSE='POWER';
      NO_LOAD_CHECK='Both';
      NO_IO_CHECK='Both';
      NO_ASSERT_CHECK='TRUE';
      NO_DIR_CHECK='TRUE';
      ALLOW_CONNECT='TRUE';
    'VSS473':
      PIN_NUMBER='(0,0,0,0,0,0,0,0,0,0,0,0,0,0,0,0,0,0,0,0,0,0,0,0,0,0,0,0,0,0,0~
,0,0,0,0,0,BH73,0,0,0,0,0)';
      PINUSE='POWER';
      NO_LOAD_CHECK='Both';
      NO_IO_CHECK='Both';
      NO_ASSERT_CHECK='TRUE';
      NO_DIR_CHECK='TRUE';
      ALLOW_CONNECT='TRUE';
    'VSS472':
      PIN_NUMBER='(0,0,0,0,0,0,0,0,0,0,0,0,0,0,0,0,0,0,0,0,0,0,0,0,0,0,0,0,0,0,0~
,0,0,0,0,0,BH67,0,0,0,0,0)';
      PINUSE='POWER';
      NO_LOAD_CHECK='Both';
      NO_IO_CHECK='Both';
      NO_ASSERT_CHECK='TRUE';
      NO_DIR_CHECK='TRUE';
      ALLOW_CONNECT='TRUE';
    'VSS470':
      PIN_NUMBER='(0,0,0,0,0,0,0,0,0,0,0,0,0,0,0,0,0,0,0,0,0,0,0,0,0,0,0,0,0,0,0~
,0,0,0,0,0,BH4,0,0,0,0,0)';
      PINUSE='POWER';
      NO_LOAD_CHECK='Both';
      NO_IO_CHECK='Both';
      NO_ASSERT_CHECK='TRUE';
      NO_DIR_CHECK='TRUE';
      ALLOW_CONNECT='TRUE';
    'VSS469':
      PIN_NUMBER='(0,0,0,0,0,0,0,0,0,0,0,0,0,0,0,0,0,0,0,0,0,0,0,0,0,0,0,0,0,0,0~
,0,0,0,0,0,BH20,0,0,0,0,0)';
      PINUSE='POWER';
      NO_LOAD_CHECK='Both';
      NO_IO_CHECK='Both';
      NO_ASSERT_CHECK='TRUE';
      NO_DIR_CHECK='TRUE';
      ALLOW_CONNECT='TRUE';
    'VSS468':
      PIN_NUMBER='(0,0,0,0,0,0,0,0,0,0,0,0,0,0,0,0,0,0,0,0,0,0,0,0,0,0,0,0,0,0,0~
,0,0,0,0,0,BH16,0,0,0,0,0)';
      PINUSE='POWER';
      NO_LOAD_CHECK='Both';
      NO_IO_CHECK='Both';
      NO_ASSERT_CHECK='TRUE';
      NO_DIR_CHECK='TRUE';
      ALLOW_CONNECT='TRUE';
    'VSS467':
      PIN_NUMBER='(0,0,0,0,0,0,0,0,0,0,0,0,0,0,0,0,0,0,0,0,0,0,0,0,0,0,0,0,0,0,0~
,0,0,0,0,0,BH12,0,0,0,0,0)';
      PINUSE='POWER';
      NO_LOAD_CHECK='Both';
      NO_IO_CHECK='Both';
      NO_ASSERT_CHECK='TRUE';
      NO_DIR_CHECK='TRUE';
      ALLOW_CONNECT='TRUE';
    'VSS466':
      PIN_NUMBER='(0,0,0,0,0,0,0,0,0,0,0,0,0,0,0,0,0,0,0,0,0,0,0,0,0,0,0,0,0,0,0~
,0,0,0,0,0,BG9,0,0,0,0,0)';
      PINUSE='POWER';
      NO_LOAD_CHECK='Both';
      NO_IO_CHECK='Both';
      NO_ASSERT_CHECK='TRUE';
      NO_DIR_CHECK='TRUE';
      ALLOW_CONNECT='TRUE';
    'VSS465':
      PIN_NUMBER='(0,0,0,0,0,0,0,0,0,0,0,0,0,0,0,0,0,0,0,0,0,0,0,0,0,0,0,0,0,0,0~
,0,0,0,0,0,BG70,0,0,0,0,0)';
      PINUSE='POWER';
      NO_LOAD_CHECK='Both';
      NO_IO_CHECK='Both';
      NO_ASSERT_CHECK='TRUE';
      NO_DIR_CHECK='TRUE';
      ALLOW_CONNECT='TRUE';
    'VSS464':
      PIN_NUMBER='(0,0,0,0,0,0,0,0,0,0,0,0,0,0,0,0,0,0,0,0,0,0,0,0,0,0,0,0,0,0,0~
,0,0,0,0,0,BG5,0,0,0,0,0)';
      PINUSE='POWER';
      NO_LOAD_CHECK='Both';
      NO_IO_CHECK='Both';
      NO_ASSERT_CHECK='TRUE';
      NO_DIR_CHECK='TRUE';
      ALLOW_CONNECT='TRUE';
    'VSS463':
      PIN_NUMBER='(0,0,0,0,0,0,0,0,0,0,0,0,0,0,0,0,0,0,0,0,0,0,0,0,0,0,0,0,0,0,0~
,0,0,0,0,0,BG25,0,0,0,0,0)';
      PINUSE='POWER';
      NO_LOAD_CHECK='Both';
      NO_IO_CHECK='Both';
      NO_ASSERT_CHECK='TRUE';
      NO_DIR_CHECK='TRUE';
      ALLOW_CONNECT='TRUE';
    'VSS462':
      PIN_NUMBER='(0,0,0,0,0,0,0,0,0,0,0,0,0,0,0,0,0,0,0,0,0,0,0,0,0,0,0,0,0,0,0~
,0,0,0,0,0,BG23,0,0,0,0,0)';
      PINUSE='POWER';
      NO_LOAD_CHECK='Both';
      NO_IO_CHECK='Both';
      NO_ASSERT_CHECK='TRUE';
      NO_DIR_CHECK='TRUE';
      ALLOW_CONNECT='TRUE';
    'VSS461':
      PIN_NUMBER='(0,0,0,0,0,0,0,0,0,0,0,0,0,0,0,0,0,0,0,0,0,0,0,0,0,0,0,0,0,0,0~
,0,0,0,0,0,BG21,0,0,0,0,0)';
      PINUSE='POWER';
      NO_LOAD_CHECK='Both';
      NO_IO_CHECK='Both';
      NO_ASSERT_CHECK='TRUE';
      NO_DIR_CHECK='TRUE';
      ALLOW_CONNECT='TRUE';
    'VSS460':
      PIN_NUMBER='(0,0,0,0,0,0,0,0,0,0,0,0,0,0,0,0,0,0,0,0,0,0,0,0,0,0,0,0,0,0,0~
,0,0,0,0,0,BG17,0,0,0,0,0)';
      PINUSE='POWER';
      NO_LOAD_CHECK='Both';
      NO_IO_CHECK='Both';
      NO_ASSERT_CHECK='TRUE';
      NO_DIR_CHECK='TRUE';
      ALLOW_CONNECT='TRUE';
    'VSS459':
      PIN_NUMBER='(0,0,0,0,0,0,0,0,0,0,0,0,0,0,0,0,0,0,0,0,0,0,0,0,0,0,0,0,0,0,0~
,0,0,0,0,0,BG13,0,0,0,0,0)';
      PINUSE='POWER';
      NO_LOAD_CHECK='Both';
      NO_IO_CHECK='Both';
      NO_ASSERT_CHECK='TRUE';
      NO_DIR_CHECK='TRUE';
      ALLOW_CONNECT='TRUE';
    'VSS458':
      PIN_NUMBER='(0,0,0,0,0,0,0,0,0,0,0,0,0,0,0,0,0,0,0,0,0,0,0,0,0,0,0,0,0,0,0~
,0,0,0,0,0,BG1,0,0,0,0,0)';
      PINUSE='POWER';
      NO_LOAD_CHECK='Both';
      NO_IO_CHECK='Both';
      NO_ASSERT_CHECK='TRUE';
      NO_DIR_CHECK='TRUE';
      ALLOW_CONNECT='TRUE';
    'VSS457':
      PIN_NUMBER='(0,0,0,0,0,0,0,0,0,0,0,0,0,0,0,0,0,0,0,0,0,0,0,0,0,0,0,0,0,0,0~
,0,0,0,0,0,BF83,0,0,0,0,0)';
      PINUSE='POWER';
      NO_LOAD_CHECK='Both';
      NO_IO_CHECK='Both';
      NO_ASSERT_CHECK='TRUE';
      NO_DIR_CHECK='TRUE';
      ALLOW_CONNECT='TRUE';
    'VSS456':
      PIN_NUMBER='(0,0,0,0,0,0,0,0,0,0,0,0,0,0,0,0,0,0,0,0,0,0,0,0,0,0,0,0,0,0,0~
,0,0,0,0,0,BF8,0,0,0,0,0)';
      PINUSE='POWER';
      NO_LOAD_CHECK='Both';
      NO_IO_CHECK='Both';
      NO_ASSERT_CHECK='TRUE';
      NO_DIR_CHECK='TRUE';
      ALLOW_CONNECT='TRUE';
    'VSS455':
      PIN_NUMBER='(0,0,0,0,0,0,0,0,0,0,0,0,0,0,0,0,0,0,0,0,0,0,0,0,0,0,0,0,0,0,0~
,0,0,0,0,0,BF79,0,0,0,0,0)';
      PINUSE='POWER';
      NO_LOAD_CHECK='Both';
      NO_IO_CHECK='Both';
      NO_ASSERT_CHECK='TRUE';
      NO_DIR_CHECK='TRUE';
      ALLOW_CONNECT='TRUE';
    'VSS454':
      PIN_NUMBER='(0,0,0,0,0,0,0,0,0,0,0,0,0,0,0,0,0,0,0,0,0,0,0,0,0,0,0,0,0,0,0~
,0,0,0,0,0,BF75,0,0,0,0,0)';
      PINUSE='POWER';
      NO_LOAD_CHECK='Both';
      NO_IO_CHECK='Both';
      NO_ASSERT_CHECK='TRUE';
      NO_DIR_CHECK='TRUE';
      ALLOW_CONNECT='TRUE';
    'VSS453':
      PIN_NUMBER='(0,0,0,0,0,0,0,0,0,0,0,0,0,0,0,0,0,0,0,0,0,0,0,0,0,0,0,0,0,0,0~
,0,0,0,0,0,BF73,0,0,0,0,0)';
      PINUSE='POWER';
      NO_LOAD_CHECK='Both';
      NO_IO_CHECK='Both';
      NO_ASSERT_CHECK='TRUE';
      NO_DIR_CHECK='TRUE';
      ALLOW_CONNECT='TRUE';
    'VSS452':
      PIN_NUMBER='(0,0,0,0,0,0,0,0,0,0,0,0,0,0,0,0,0,0,0,0,0,0,0,0,0,0,0,0,0,0,0~
,0,0,0,0,0,BF63,0,0,0,0,0)';
      PINUSE='POWER';
      NO_LOAD_CHECK='Both';
      NO_IO_CHECK='Both';
      NO_ASSERT_CHECK='TRUE';
      NO_DIR_CHECK='TRUE';
      ALLOW_CONNECT='TRUE';
    'VSS451':
      PIN_NUMBER='(0,0,0,0,0,0,0,0,0,0,0,0,0,0,0,0,0,0,0,0,0,0,0,0,0,0,0,0,0,0,0~
,0,0,0,0,0,BF61,0,0,0,0,0)';
      PINUSE='POWER';
      NO_LOAD_CHECK='Both';
      NO_IO_CHECK='Both';
      NO_ASSERT_CHECK='TRUE';
      NO_DIR_CHECK='TRUE';
      ALLOW_CONNECT='TRUE';
    'VSS450':
      PIN_NUMBER='(0,0,0,0,0,0,0,0,0,0,0,0,0,0,0,0,0,0,0,0,0,0,0,0,0,0,0,0,0,0,0~
,0,0,0,0,0,BF4,0,0,0,0,0)';
      PINUSE='POWER';
      NO_LOAD_CHECK='Both';
      NO_IO_CHECK='Both';
      NO_ASSERT_CHECK='TRUE';
      NO_DIR_CHECK='TRUE';
      ALLOW_CONNECT='TRUE';
    'VSS449':
      PIN_NUMBER='(0,0,0,0,0,0,0,0,0,0,0,0,0,0,0,0,0,0,0,0,0,0,0,0,0,0,0,0,0,0,0~
,0,0,0,0,0,BF20,0,0,0,0,0)';
      PINUSE='POWER';
      NO_LOAD_CHECK='Both';
      NO_IO_CHECK='Both';
      NO_ASSERT_CHECK='TRUE';
      NO_DIR_CHECK='TRUE';
      ALLOW_CONNECT='TRUE';
    'VSS448':
      PIN_NUMBER='(0,0,0,0,0,0,0,0,0,0,0,0,0,0,0,0,0,0,0,0,0,0,0,0,0,0,0,0,0,0,0~
,0,0,0,0,0,BF16,0,0,0,0,0)';
      PINUSE='POWER';
      NO_LOAD_CHECK='Both';
      NO_IO_CHECK='Both';
      NO_ASSERT_CHECK='TRUE';
      NO_DIR_CHECK='TRUE';
      ALLOW_CONNECT='TRUE';
    'VSS447':
      PIN_NUMBER='(0,0,0,0,0,0,0,0,0,0,0,0,0,0,0,0,0,0,0,0,0,0,0,0,0,0,0,0,0,0,0~
,0,0,0,0,0,BF12,0,0,0,0,0)';
      PINUSE='POWER';
      NO_LOAD_CHECK='Both';
      NO_IO_CHECK='Both';
      NO_ASSERT_CHECK='TRUE';
      NO_DIR_CHECK='TRUE';
      ALLOW_CONNECT='TRUE';
    'VSS446':
      PIN_NUMBER='(0,0,0,0,0,0,0,0,0,0,0,0,0,0,0,0,0,0,0,0,0,0,0,0,0,0,0,0,0,0,0~
,0,0,0,0,0,BE84,0,0,0,0,0)';
      PINUSE='POWER';
      NO_LOAD_CHECK='Both';
      NO_IO_CHECK='Both';
      NO_ASSERT_CHECK='TRUE';
      NO_DIR_CHECK='TRUE';
      ALLOW_CONNECT='TRUE';
    'VSS445':
      PIN_NUMBER='(0,0,0,0,0,0,0,0,0,0,0,0,0,0,0,0,0,0,0,0,0,0,0,0,0,0,0,0,0,0,0~
,0,0,0,0,0,BE78,0,0,0,0,0)';
      PINUSE='POWER';
      NO_LOAD_CHECK='Both';
      NO_IO_CHECK='Both';
      NO_ASSERT_CHECK='TRUE';
      NO_DIR_CHECK='TRUE';
      ALLOW_CONNECT='TRUE';
    'VSS444':
      PIN_NUMBER='(0,0,0,0,0,0,0,0,0,0,0,0,0,0,0,0,0,0,0,0,0,0,0,0,0,0,0,0,0,0,0~
,0,0,0,0,0,BE76,0,0,0,0,0)';
      PINUSE='POWER';
      NO_LOAD_CHECK='Both';
      NO_IO_CHECK='Both';
      NO_ASSERT_CHECK='TRUE';
      NO_DIR_CHECK='TRUE';
      ALLOW_CONNECT='TRUE';
    'VSS443':
      PIN_NUMBER='(0,0,0,0,0,0,0,0,0,0,0,0,0,0,0,0,0,0,0,0,0,0,0,0,0,0,0,0,0,0,0~
,0,0,0,0,0,BE74,0,0,0,0,0)';
      PINUSE='POWER';
      NO_LOAD_CHECK='Both';
      NO_IO_CHECK='Both';
      NO_ASSERT_CHECK='TRUE';
      NO_DIR_CHECK='TRUE';
      ALLOW_CONNECT='TRUE';
    'VSS442':
      PIN_NUMBER='(0,0,0,0,0,0,0,0,0,0,0,0,0,0,0,0,0,0,0,0,0,0,0,0,0,0,0,0,0,0,0~
,0,0,0,0,0,BE68,0,0,0,0,0)';
      PINUSE='POWER';
      NO_LOAD_CHECK='Both';
      NO_IO_CHECK='Both';
      NO_ASSERT_CHECK='TRUE';
      NO_DIR_CHECK='TRUE';
      ALLOW_CONNECT='TRUE';
    'VSS441':
      PIN_NUMBER='(0,0,0,0,0,0,0,0,0,0,0,0,0,0,0,0,0,0,0,0,0,0,0,0,0,0,0,0,0,0,0~
,0,0,0,0,0,BE66,0,0,0,0,0)';
      PINUSE='POWER';
      NO_LOAD_CHECK='Both';
      NO_IO_CHECK='Both';
      NO_ASSERT_CHECK='TRUE';
      NO_DIR_CHECK='TRUE';
      ALLOW_CONNECT='TRUE';
    'VSS440':
      PIN_NUMBER='(0,0,0,0,0,0,0,0,0,0,0,0,0,0,0,0,0,0,0,0,0,0,0,0,0,0,0,0,0,0,0~
,0,0,0,0,0,BE64,0,0,0,0,0)';
      PINUSE='POWER';
      NO_LOAD_CHECK='Both';
      NO_IO_CHECK='Both';
      NO_ASSERT_CHECK='TRUE';
      NO_DIR_CHECK='TRUE';
      ALLOW_CONNECT='TRUE';
    'VSS439':
      PIN_NUMBER='(0,0,0,0,0,0,0,0,0,0,0,0,0,0,0,0,0,0,0,0,0,0,0,0,0,0,0,0,0,0,0~
,0,0,0,0,0,BD89,0,0,0,0,0)';
      PINUSE='POWER';
      NO_LOAD_CHECK='Both';
      NO_IO_CHECK='Both';
      NO_ASSERT_CHECK='TRUE';
      NO_DIR_CHECK='TRUE';
      ALLOW_CONNECT='TRUE';
    'VSS437':
      PIN_NUMBER='(0,0,0,0,0,0,0,0,0,0,0,0,0,0,0,0,0,0,0,0,0,0,0,0,0,0,0,0,0,0,0~
,0,0,0,0,0,BD85,0,0,0,0,0)';
      PINUSE='POWER';
      NO_LOAD_CHECK='Both';
      NO_IO_CHECK='Both';
      NO_ASSERT_CHECK='TRUE';
      NO_DIR_CHECK='TRUE';
      ALLOW_CONNECT='TRUE';
    'VSS435':
      PIN_NUMBER='(0,0,0,0,0,0,0,0,0,0,0,0,0,0,0,0,0,0,0,0,0,0,0,0,0,0,0,0,0,0,0~
,0,0,0,0,0,BD81,0,0,0,0,0)';
      PINUSE='POWER';
      NO_LOAD_CHECK='Both';
      NO_IO_CHECK='Both';
      NO_ASSERT_CHECK='TRUE';
      NO_DIR_CHECK='TRUE';
      ALLOW_CONNECT='TRUE';
    'VSS434':
      PIN_NUMBER='(0,0,0,0,0,0,0,0,0,0,0,0,0,0,0,0,0,0,0,0,0,0,0,0,0,0,0,0,0,0,0~
,0,0,0,0,0,BD8,0,0,0,0,0)';
      PINUSE='POWER';
      NO_LOAD_CHECK='Both';
      NO_IO_CHECK='Both';
      NO_ASSERT_CHECK='TRUE';
      NO_DIR_CHECK='TRUE';
      ALLOW_CONNECT='TRUE';
    'VSS433':
      PIN_NUMBER='(0,0,0,0,0,0,0,0,0,0,0,0,0,0,0,0,0,0,0,0,0,0,0,0,0,0,0,0,0,0,0~
,0,0,0,0,0,BD4,0,0,0,0,0)';
      PINUSE='POWER';
      NO_LOAD_CHECK='Both';
      NO_IO_CHECK='Both';
      NO_ASSERT_CHECK='TRUE';
      NO_DIR_CHECK='TRUE';
      ALLOW_CONNECT='TRUE';
    'VSS432':
      PIN_NUMBER='(0,0,0,0,0,0,0,0,0,0,0,0,0,0,0,0,0,0,0,0,0,0,0,0,0,0,0,0,0,0,0~
,0,0,0,0,0,BD20,0,0,0,0,0)';
      PINUSE='POWER';
      NO_LOAD_CHECK='Both';
      NO_IO_CHECK='Both';
      NO_ASSERT_CHECK='TRUE';
      NO_DIR_CHECK='TRUE';
      ALLOW_CONNECT='TRUE';
    'VSS431':
      PIN_NUMBER='(0,0,0,0,0,0,0,0,0,0,0,0,0,0,0,0,0,0,0,0,0,0,0,0,0,0,0,0,0,0,0~
,0,0,0,0,0,BD16,0,0,0,0,0)';
      PINUSE='POWER';
      NO_LOAD_CHECK='Both';
      NO_IO_CHECK='Both';
      NO_ASSERT_CHECK='TRUE';
      NO_DIR_CHECK='TRUE';
      ALLOW_CONNECT='TRUE';
    'VSS430':
      PIN_NUMBER='(0,0,0,0,0,0,0,0,0,0,0,0,0,0,0,0,0,0,0,0,0,0,0,0,0,0,0,0,0,0,0~
,0,0,0,0,0,BD12,0,0,0,0,0)';
      PINUSE='POWER';
      NO_LOAD_CHECK='Both';
      NO_IO_CHECK='Both';
      NO_ASSERT_CHECK='TRUE';
      NO_DIR_CHECK='TRUE';
      ALLOW_CONNECT='TRUE';
    'VSS429':
      PIN_NUMBER='(0,0,0,0,0,0,0,0,0,0,0,0,0,0,0,0,0,0,0,0,0,0,0,0,0,0,0,0,0,0,0~
,0,0,0,0,0,BC9,0,0,0,0,0)';
      PINUSE='POWER';
      NO_LOAD_CHECK='Both';
      NO_IO_CHECK='Both';
      NO_ASSERT_CHECK='TRUE';
      NO_DIR_CHECK='TRUE';
      ALLOW_CONNECT='TRUE';
    'VSS428':
      PIN_NUMBER='(0,0,0,0,0,0,0,0,0,0,0,0,0,0,0,0,0,0,0,0,0,0,0,0,0,0,0,0,0,0,0~
,0,0,0,0,0,BC88,0,0,0,0,0)';
      PINUSE='POWER';
      NO_LOAD_CHECK='Both';
      NO_IO_CHECK='Both';
      NO_ASSERT_CHECK='TRUE';
      NO_DIR_CHECK='TRUE';
      ALLOW_CONNECT='TRUE';
    'VSS427':
      PIN_NUMBER='(0,0,0,0,0,0,0,0,0,0,0,0,0,0,0,0,0,0,0,0,0,0,0,0,0,0,0,0,0,0,0~
,0,0,0,0,0,BC86,0,0,0,0,0)';
      PINUSE='POWER';
      NO_LOAD_CHECK='Both';
      NO_IO_CHECK='Both';
      NO_ASSERT_CHECK='TRUE';
      NO_DIR_CHECK='TRUE';
      ALLOW_CONNECT='TRUE';
    'VSS426':
      PIN_NUMBER='(0,0,0,0,0,0,0,0,0,0,0,0,0,0,0,0,0,0,0,0,0,0,0,0,0,0,0,0,0,0,0~
,0,0,0,0,0,BC84,0,0,0,0,0)';
      PINUSE='POWER';
      NO_LOAD_CHECK='Both';
      NO_IO_CHECK='Both';
      NO_ASSERT_CHECK='TRUE';
      NO_DIR_CHECK='TRUE';
      ALLOW_CONNECT='TRUE';
    'VSS425':
      PIN_NUMBER='(0,0,0,0,0,0,0,0,0,0,0,0,0,0,0,0,0,0,0,0,0,0,0,0,0,0,0,0,0,0,0~
,0,0,0,0,0,BC78,0,0,0,0,0)';
      PINUSE='POWER';
      NO_LOAD_CHECK='Both';
      NO_IO_CHECK='Both';
      NO_ASSERT_CHECK='TRUE';
      NO_DIR_CHECK='TRUE';
      ALLOW_CONNECT='TRUE';
    'VSS424':
      PIN_NUMBER='(0,0,0,0,0,0,0,0,0,0,0,0,0,0,0,0,0,0,0,0,0,0,0,0,0,0,0,0,0,0,0~
,0,0,0,0,0,BC76,0,0,0,0,0)';
      PINUSE='POWER';
      NO_LOAD_CHECK='Both';
      NO_IO_CHECK='Both';
      NO_ASSERT_CHECK='TRUE';
      NO_DIR_CHECK='TRUE';
      ALLOW_CONNECT='TRUE';
    'VSS423':
      PIN_NUMBER='(0,0,0,0,0,0,0,0,0,0,0,0,0,0,0,0,0,0,0,0,0,0,0,0,0,0,0,0,0,0,0~
,0,0,0,0,0,BC72,0,0,0,0,0)';
      PINUSE='POWER';
      NO_LOAD_CHECK='Both';
      NO_IO_CHECK='Both';
      NO_ASSERT_CHECK='TRUE';
      NO_DIR_CHECK='TRUE';
      ALLOW_CONNECT='TRUE';
    'VSS422':
      PIN_NUMBER='(0,0,0,0,0,0,0,0,0,0,0,0,0,0,0,0,0,0,0,0,0,0,0,0,0,0,0,0,0,0,0~
,0,0,0,0,0,BC66,0,0,0,0,0)';
      PINUSE='POWER';
      NO_LOAD_CHECK='Both';
      NO_IO_CHECK='Both';
      NO_ASSERT_CHECK='TRUE';
      NO_DIR_CHECK='TRUE';
      ALLOW_CONNECT='TRUE';
    'VSS421':
      PIN_NUMBER='(0,0,0,0,0,0,0,0,0,0,0,0,0,0,0,0,0,0,0,0,0,0,0,0,0,0,0,0,0,0,0~
,0,0,0,0,0,BC62,0,0,0,0,0)';
      PINUSE='POWER';
      NO_LOAD_CHECK='Both';
      NO_IO_CHECK='Both';
      NO_ASSERT_CHECK='TRUE';
      NO_DIR_CHECK='TRUE';
      ALLOW_CONNECT='TRUE';
    'VSS420':
      PIN_NUMBER='(0,0,0,0,0,0,0,0,0,0,0,0,0,0,0,0,0,0,0,0,0,0,0,0,0,0,0,0,0,0,0~
,0,0,0,0,0,BC5,0,0,0,0,0)';
      PINUSE='POWER';
      NO_LOAD_CHECK='Both';
      NO_IO_CHECK='Both';
      NO_ASSERT_CHECK='TRUE';
      NO_DIR_CHECK='TRUE';
      ALLOW_CONNECT='TRUE';
    'VSS419':
      PIN_NUMBER='(0,0,0,0,0,0,0,0,0,0,0,0,0,0,0,0,0,0,0,0,0,0,0,0,0,0,0,0,0,0,0~
,0,0,0,0,0,BC17,0,0,0,0,0)';
      PINUSE='POWER';
      NO_LOAD_CHECK='Both';
      NO_IO_CHECK='Both';
      NO_ASSERT_CHECK='TRUE';
      NO_DIR_CHECK='TRUE';
      ALLOW_CONNECT='TRUE';
    'VSS418':
      PIN_NUMBER='(0,0,0,0,0,0,0,0,0,0,0,0,0,0,0,0,0,0,0,0,0,0,0,0,0,0,0,0,0,0,0~
,0,0,0,0,0,BC13,0,0,0,0,0)';
      PINUSE='POWER';
      NO_LOAD_CHECK='Both';
      NO_IO_CHECK='Both';
      NO_ASSERT_CHECK='TRUE';
      NO_DIR_CHECK='TRUE';
      ALLOW_CONNECT='TRUE';
    'VSS417':
      PIN_NUMBER='(0,0,0,0,0,0,0,0,0,0,0,0,0,0,0,0,0,0,0,0,0,0,0,0,0,0,0,0,0,0,0~
,0,0,0,0,0,BC1,0,0,0,0,0)';
      PINUSE='POWER';
      NO_LOAD_CHECK='Both';
      NO_IO_CHECK='Both';
      NO_ASSERT_CHECK='TRUE';
      NO_DIR_CHECK='TRUE';
      ALLOW_CONNECT='TRUE';
    'VSS416':
      PIN_NUMBER='(0,0,0,0,0,0,0,0,0,0,0,0,0,0,0,0,0,0,0,0,0,0,0,0,0,0,0,0,0,0,0~
,0,0,0,0,0,BB91,0,0,0,0,0)';
      PINUSE='POWER';
      NO_LOAD_CHECK='Both';
      NO_IO_CHECK='Both';
      NO_ASSERT_CHECK='TRUE';
      NO_DIR_CHECK='TRUE';
      ALLOW_CONNECT='TRUE';
    'VSS415':
      PIN_NUMBER='(0,0,0,0,0,0,0,0,0,0,0,0,0,0,0,0,0,0,0,0,0,0,0,0,0,0,0,0,0,0,0~
,0,0,0,0,0,BB87,0,0,0,0,0)';
      PINUSE='POWER';
      NO_LOAD_CHECK='Both';
      NO_IO_CHECK='Both';
      NO_ASSERT_CHECK='TRUE';
      NO_DIR_CHECK='TRUE';
      ALLOW_CONNECT='TRUE';
    'VSS414':
      PIN_NUMBER='(0,0,0,0,0,0,0,0,0,0,0,0,0,0,0,0,0,0,0,0,0,0,0,0,0,0,0,0,0,0,0~
,0,0,0,0,0,BB83,0,0,0,0,0)';
      PINUSE='POWER';
      NO_LOAD_CHECK='Both';
      NO_IO_CHECK='Both';
      NO_ASSERT_CHECK='TRUE';
      NO_DIR_CHECK='TRUE';
      ALLOW_CONNECT='TRUE';
    'VSS413':
      PIN_NUMBER='(0,0,0,0,0,0,0,0,0,0,0,0,0,0,0,0,0,0,0,0,0,0,0,0,0,0,0,0,0,0,0~
,0,0,0,0,0,BB8,0,0,0,0,0)';
      PINUSE='POWER';
      NO_LOAD_CHECK='Both';
      NO_IO_CHECK='Both';
      NO_ASSERT_CHECK='TRUE';
      NO_DIR_CHECK='TRUE';
      ALLOW_CONNECT='TRUE';
    'VSS412':
      PIN_NUMBER='(0,0,0,0,0,0,0,0,0,0,0,0,0,0,0,0,0,0,0,0,0,0,0,0,0,0,0,0,0,0,0~
,0,0,0,0,0,BB79,0,0,0,0,0)';
      PINUSE='POWER';
      NO_LOAD_CHECK='Both';
      NO_IO_CHECK='Both';
      NO_ASSERT_CHECK='TRUE';
      NO_DIR_CHECK='TRUE';
      ALLOW_CONNECT='TRUE';
    'VSS411':
      PIN_NUMBER='(0,0,0,0,0,0,0,0,0,0,0,0,0,0,0,0,0,0,0,0,0,0,0,0,0,0,0,0,0,0,0~
,0,0,0,0,0,BB77,0,0,0,0,0)';
      PINUSE='POWER';
      NO_LOAD_CHECK='Both';
      NO_IO_CHECK='Both';
      NO_ASSERT_CHECK='TRUE';
      NO_DIR_CHECK='TRUE';
      ALLOW_CONNECT='TRUE';
    'VSS410':
      PIN_NUMBER='(0,0,0,0,0,0,0,0,0,0,0,0,0,0,0,0,0,0,0,0,0,0,0,0,0,0,0,0,0,0,0~
,0,0,0,0,0,BB71,0,0,0,0,0)';
      PINUSE='POWER';
      NO_LOAD_CHECK='Both';
      NO_IO_CHECK='Both';
      NO_ASSERT_CHECK='TRUE';
      NO_DIR_CHECK='TRUE';
      ALLOW_CONNECT='TRUE';
    'VSS409':
      PIN_NUMBER='(0,0,0,0,0,0,0,0,0,0,0,0,0,0,0,0,0,0,0,0,0,0,0,0,0,0,0,0,0,0,0~
,0,0,0,0,0,BB69,0,0,0,0,0)';
      PINUSE='POWER';
      NO_LOAD_CHECK='Both';
      NO_IO_CHECK='Both';
      NO_ASSERT_CHECK='TRUE';
      NO_DIR_CHECK='TRUE';
      ALLOW_CONNECT='TRUE';
    'VSS408':
      PIN_NUMBER='(0,0,0,0,0,0,0,0,0,0,0,0,0,0,0,0,0,0,0,0,0,0,0,0,0,0,0,0,0,0,0~
,0,0,0,0,0,BB63,0,0,0,0,0)';
      PINUSE='POWER';
      NO_LOAD_CHECK='Both';
      NO_IO_CHECK='Both';
      NO_ASSERT_CHECK='TRUE';
      NO_DIR_CHECK='TRUE';
      ALLOW_CONNECT='TRUE';
    'VSS407':
      PIN_NUMBER='(0,0,0,0,0,0,0,0,0,0,0,0,0,0,0,0,0,0,0,0,0,0,0,0,0,0,0,0,0,0,0~
,0,0,0,0,0,BB4,0,0,0,0,0)';
      PINUSE='POWER';
      NO_LOAD_CHECK='Both';
      NO_IO_CHECK='Both';
      NO_ASSERT_CHECK='TRUE';
      NO_DIR_CHECK='TRUE';
      ALLOW_CONNECT='TRUE';
    'VSS406':
      PIN_NUMBER='(0,0,0,0,0,0,0,0,0,0,0,0,0,0,0,0,0,0,0,0,0,0,0,0,0,0,0,0,0,0,0~
,0,0,0,0,0,BB26,0,0,0,0,0)';
      PINUSE='POWER';
      NO_LOAD_CHECK='Both';
      NO_IO_CHECK='Both';
      NO_ASSERT_CHECK='TRUE';
      NO_DIR_CHECK='TRUE';
      ALLOW_CONNECT='TRUE';
    'VSS405':
      PIN_NUMBER='(0,0,0,0,0,0,0,0,0,0,0,0,0,0,0,0,0,0,0,0,0,0,0,0,0,0,0,0,0,0,0~
,0,0,0,0,0,BB24,0,0,0,0,0)';
      PINUSE='POWER';
      NO_LOAD_CHECK='Both';
      NO_IO_CHECK='Both';
      NO_ASSERT_CHECK='TRUE';
      NO_DIR_CHECK='TRUE';
      ALLOW_CONNECT='TRUE';
    'VSS404':
      PIN_NUMBER='(0,0,0,0,0,0,0,0,0,0,0,0,0,0,0,0,0,0,0,0,0,0,0,0,0,0,0,0,0,0,0~
,0,0,0,0,0,BB22,0,0,0,0,0)';
      PINUSE='POWER';
      NO_LOAD_CHECK='Both';
      NO_IO_CHECK='Both';
      NO_ASSERT_CHECK='TRUE';
      NO_DIR_CHECK='TRUE';
      ALLOW_CONNECT='TRUE';
    'VSS403':
      PIN_NUMBER='(0,0,0,0,0,0,0,0,0,0,0,0,0,0,0,0,0,0,0,0,0,0,0,0,0,0,0,0,0,0,0~
,0,0,0,0,0,BB20,0,0,0,0,0)';
      PINUSE='POWER';
      NO_LOAD_CHECK='Both';
      NO_IO_CHECK='Both';
      NO_ASSERT_CHECK='TRUE';
      NO_DIR_CHECK='TRUE';
      ALLOW_CONNECT='TRUE';
    'VSS402':
      PIN_NUMBER='(0,0,0,0,0,0,0,0,0,0,0,0,0,0,0,0,0,0,0,0,0,0,0,0,0,0,0,0,0,0,0~
,0,0,0,0,0,BB16,0,0,0,0,0)';
      PINUSE='POWER';
      NO_LOAD_CHECK='Both';
      NO_IO_CHECK='Both';
      NO_ASSERT_CHECK='TRUE';
      NO_DIR_CHECK='TRUE';
      ALLOW_CONNECT='TRUE';
    'VSS401':
      PIN_NUMBER='(0,0,0,0,0,0,0,0,0,0,0,0,0,0,0,0,0,0,0,0,0,0,0,0,0,0,0,0,0,0,0~
,0,0,0,0,0,BB12,0,0,0,0,0)';
      PINUSE='POWER';
      NO_LOAD_CHECK='Both';
      NO_IO_CHECK='Both';
      NO_ASSERT_CHECK='TRUE';
      NO_DIR_CHECK='TRUE';
      ALLOW_CONNECT='TRUE';
    'VSS400':
      PIN_NUMBER='(0,0,0,0,0,0,0,0,0,0,0,0,0,0,0,0,0,0,0,0,0,0,0,0,0,0,0,0,0,0,0~
,0,0,0,0,0,BB10,0,0,0,0,0)';
      PINUSE='POWER';
      NO_LOAD_CHECK='Both';
      NO_IO_CHECK='Both';
      NO_ASSERT_CHECK='TRUE';
      NO_DIR_CHECK='TRUE';
      ALLOW_CONNECT='TRUE';
    'VSS399':
      PIN_NUMBER='(0,0,0,0,0,0,0,0,0,0,0,0,0,0,0,0,0,0,0,0,0,0,0,0,0,0,0,0,0,0,0~
,0,0,0,0,0,BA88,0,0,0,0,0)';
      PINUSE='POWER';
      NO_LOAD_CHECK='Both';
      NO_IO_CHECK='Both';
      NO_ASSERT_CHECK='TRUE';
      NO_DIR_CHECK='TRUE';
      ALLOW_CONNECT='TRUE';
    'VSS398':
      PIN_NUMBER='(0,0,0,0,0,0,0,0,0,0,0,0,0,0,0,0,0,0,0,0,0,0,0,0,0,0,0,0,0,0,0~
,0,0,0,0,0,BA84,0,0,0,0,0)';
      PINUSE='POWER';
      NO_LOAD_CHECK='Both';
      NO_IO_CHECK='Both';
      NO_ASSERT_CHECK='TRUE';
      NO_DIR_CHECK='TRUE';
      ALLOW_CONNECT='TRUE';
    'VSS397':
      PIN_NUMBER='(0,0,0,0,0,0,0,0,0,0,0,0,0,0,0,0,0,0,0,0,0,0,0,0,0,0,0,0,0,0,0~
,0,0,0,0,0,BA74,0,0,0,0,0)';
      PINUSE='POWER';
      NO_LOAD_CHECK='Both';
      NO_IO_CHECK='Both';
      NO_ASSERT_CHECK='TRUE';
      NO_DIR_CHECK='TRUE';
      ALLOW_CONNECT='TRUE';
    'VSS395':
      PIN_NUMBER='(0,0,0,0,0,0,0,0,0,0,0,0,0,0,0,0,0,0,0,0,0,0,0,0,0,0,0,0,0,0,0~
,0,0,0,0,0,BA64,0,0,0,0,0)';
      PINUSE='POWER';
      NO_LOAD_CHECK='Both';
      NO_IO_CHECK='Both';
      NO_ASSERT_CHECK='TRUE';
      NO_DIR_CHECK='TRUE';
      ALLOW_CONNECT='TRUE';
    'VSS394':
      PIN_NUMBER='(0,0,0,0,0,0,0,0,0,0,0,0,0,0,0,0,0,0,0,0,0,0,0,0,0,0,0,0,0,0,0~
,0,0,0,0,0,BA60,0,0,0,0,0)';
      PINUSE='POWER';
      NO_LOAD_CHECK='Both';
      NO_IO_CHECK='Both';
      NO_ASSERT_CHECK='TRUE';
      NO_DIR_CHECK='TRUE';
      ALLOW_CONNECT='TRUE';
    'VSS393':
      PIN_NUMBER='(0,0,0,0,0,0,0,0,0,0,0,0,0,0,0,0,0,0,0,0,0,0,0,0,0,0,0,0,0,0,0~
,0,0,0,0,0,BA17,0,0,0,0,0)';
      PINUSE='POWER';
      NO_LOAD_CHECK='Both';
      NO_IO_CHECK='Both';
      NO_ASSERT_CHECK='TRUE';
      NO_DIR_CHECK='TRUE';
      ALLOW_CONNECT='TRUE';
    'VSS377':
      PIN_NUMBER='(0,0,0,0,0,0,0,0,0,0,0,0,0,0,0,0,0,0,0,0,0,0,0,0,0,0,0,0,0,0,0~
,0,0,0,0,0,AY83,0,0,0,0,0)';
      PINUSE='POWER';
      NO_LOAD_CHECK='Both';
      NO_IO_CHECK='Both';
      NO_ASSERT_CHECK='TRUE';
      NO_DIR_CHECK='TRUE';
      ALLOW_CONNECT='TRUE';
    'VSS376':
      PIN_NUMBER='(0,0,0,0,0,0,0,0,0,0,0,0,0,0,0,0,0,0,0,0,0,0,0,0,0,0,0,0,0,0,0~
,0,0,0,0,0,AY81,0,0,0,0,0)';
      PINUSE='POWER';
      NO_LOAD_CHECK='Both';
      NO_IO_CHECK='Both';
      NO_ASSERT_CHECK='TRUE';
      NO_DIR_CHECK='TRUE';
      ALLOW_CONNECT='TRUE';
    'VSS375':
      PIN_NUMBER='(0,0,0,0,0,0,0,0,0,0,0,0,0,0,0,0,0,0,0,0,0,0,0,0,0,0,0,0,0,0,0~
,0,0,0,0,0,AY8,0,0,0,0,0)';
      PINUSE='POWER';
      NO_LOAD_CHECK='Both';
      NO_IO_CHECK='Both';
      NO_ASSERT_CHECK='TRUE';
      NO_DIR_CHECK='TRUE';
      ALLOW_CONNECT='TRUE';
    'VSS374':
      PIN_NUMBER='(0,0,0,0,0,0,0,0,0,0,0,0,0,0,0,0,0,0,0,0,0,0,0,0,0,0,0,0,0,0,0~
,0,0,0,0,0,AY79,0,0,0,0,0)';
      PINUSE='POWER';
      NO_LOAD_CHECK='Both';
      NO_IO_CHECK='Both';
      NO_ASSERT_CHECK='TRUE';
      NO_DIR_CHECK='TRUE';
      ALLOW_CONNECT='TRUE';
    'VSS373':
      PIN_NUMBER='(0,0,0,0,0,0,0,0,0,0,0,0,0,0,0,0,0,0,0,0,0,0,0,0,0,0,0,0,0,0,0~
,0,0,0,0,0,AY77,0,0,0,0,0)';
      PINUSE='POWER';
      NO_LOAD_CHECK='Both';
      NO_IO_CHECK='Both';
      NO_ASSERT_CHECK='TRUE';
      NO_DIR_CHECK='TRUE';
      ALLOW_CONNECT='TRUE';
    'VSS372':
      PIN_NUMBER='(0,0,0,0,0,0,0,0,0,0,0,0,0,0,0,0,0,0,0,0,0,0,0,0,0,0,0,0,0,0,0~
,0,0,0,0,0,AY71,0,0,0,0,0)';
      PINUSE='POWER';
      NO_LOAD_CHECK='Both';
      NO_IO_CHECK='Both';
      NO_ASSERT_CHECK='TRUE';
      NO_DIR_CHECK='TRUE';
      ALLOW_CONNECT='TRUE';
    'VSS371':
      PIN_NUMBER='(0,0,0,0,0,0,0,0,0,0,0,0,0,0,0,0,0,0,0,0,0,0,0,0,0,0,0,0,0,0,0~
,0,0,0,0,0,AY4,0,0,0,0,0)';
      PINUSE='POWER';
      NO_LOAD_CHECK='Both';
      NO_IO_CHECK='Both';
      NO_ASSERT_CHECK='TRUE';
      NO_DIR_CHECK='TRUE';
      ALLOW_CONNECT='TRUE';
    'VSS370':
      PIN_NUMBER='(0,0,0,0,0,0,0,0,0,0,0,0,0,0,0,0,0,0,0,0,0,0,0,0,0,0,0,0,0,0,0~
,0,0,0,0,0,AY16,0,0,0,0,0)';
      PINUSE='POWER';
      NO_LOAD_CHECK='Both';
      NO_IO_CHECK='Both';
      NO_ASSERT_CHECK='TRUE';
      NO_DIR_CHECK='TRUE';
      ALLOW_CONNECT='TRUE';
    'VSS369':
      PIN_NUMBER='(0,0,0,0,0,0,0,0,0,0,0,0,0,0,0,0,0,0,0,0,0,0,0,0,0,0,0,0,0,0,0~
,0,0,0,0,0,AY12,0,0,0,0,0)';
      PINUSE='POWER';
      NO_LOAD_CHECK='Both';
      NO_IO_CHECK='Both';
      NO_ASSERT_CHECK='TRUE';
      NO_DIR_CHECK='TRUE';
      ALLOW_CONNECT='TRUE';
    'VSS367':
      PIN_NUMBER='(0,0,0,0,0,0,0,0,0,0,0,0,0,0,0,0,0,0,0,0,0,0,0,0,0,0,0,0,0,0,0~
,0,0,0,0,0,AW88,0,0,0,0,0)';
      PINUSE='POWER';
      NO_LOAD_CHECK='Both';
      NO_IO_CHECK='Both';
      NO_ASSERT_CHECK='TRUE';
      NO_DIR_CHECK='TRUE';
      ALLOW_CONNECT='TRUE';
    'VSS366':
      PIN_NUMBER='(0,0,0,0,0,0,0,0,0,0,0,0,0,0,0,0,0,0,0,0,0,0,0,0,0,0,0,0,0,0,0~
,0,0,0,0,0,AW84,0,0,0,0,0)';
      PINUSE='POWER';
      NO_LOAD_CHECK='Both';
      NO_IO_CHECK='Both';
      NO_ASSERT_CHECK='TRUE';
      NO_DIR_CHECK='TRUE';
      ALLOW_CONNECT='TRUE';
    'VSS365':
      PIN_NUMBER='(0,0,0,0,0,0,0,0,0,0,0,0,0,0,0,0,0,0,0,0,0,0,0,0,0,0,0,0,0,0,0~
,0,0,0,0,0,AW82,0,0,0,0,0)';
      PINUSE='POWER';
      NO_LOAD_CHECK='Both';
      NO_IO_CHECK='Both';
      NO_ASSERT_CHECK='TRUE';
      NO_DIR_CHECK='TRUE';
      ALLOW_CONNECT='TRUE';
    'VSS364':
      PIN_NUMBER='(0,0,0,0,0,0,0,0,0,0,0,0,0,0,0,0,0,0,0,0,0,0,0,0,0,0,0,0,0,0,0~
,0,0,0,0,0,AW80,0,0,0,0,0)';
      PINUSE='POWER';
      NO_LOAD_CHECK='Both';
      NO_IO_CHECK='Both';
      NO_ASSERT_CHECK='TRUE';
      NO_DIR_CHECK='TRUE';
      ALLOW_CONNECT='TRUE';
    'VSS363':
      PIN_NUMBER='(0,0,0,0,0,0,0,0,0,0,0,0,0,0,0,0,0,0,0,0,0,0,0,0,0,0,0,0,0,0,0~
,0,0,0,0,0,AW72,0,0,0,0,0)';
      PINUSE='POWER';
      NO_LOAD_CHECK='Both';
      NO_IO_CHECK='Both';
      NO_ASSERT_CHECK='TRUE';
      NO_DIR_CHECK='TRUE';
      ALLOW_CONNECT='TRUE';
    'VSS362':
      PIN_NUMBER='(0,0,0,0,0,0,0,0,0,0,0,0,0,0,0,0,0,0,0,0,0,0,0,0,0,0,0,0,0,0,0~
,0,0,0,0,0,AW68,0,0,0,0,0)';
      PINUSE='POWER';
      NO_LOAD_CHECK='Both';
      NO_IO_CHECK='Both';
      NO_ASSERT_CHECK='TRUE';
      NO_DIR_CHECK='TRUE';
      ALLOW_CONNECT='TRUE';
    'VSS361':
      PIN_NUMBER='(0,0,0,0,0,0,0,0,0,0,0,0,0,0,0,0,0,0,0,0,0,0,0,0,0,0,0,0,0,0,0~
,0,0,0,0,0,AW66,0,0,0,0,0)';
      PINUSE='POWER';
      NO_LOAD_CHECK='Both';
      NO_IO_CHECK='Both';
      NO_ASSERT_CHECK='TRUE';
      NO_DIR_CHECK='TRUE';
      ALLOW_CONNECT='TRUE';
    'VSS360':
      PIN_NUMBER='(0,0,0,0,0,0,0,0,0,0,0,0,0,0,0,0,0,0,0,0,0,0,0,0,0,0,0,0,0,0,0~
,0,0,0,0,0,AW62,0,0,0,0,0)';
      PINUSE='POWER';
      NO_LOAD_CHECK='Both';
      NO_IO_CHECK='Both';
      NO_ASSERT_CHECK='TRUE';
      NO_DIR_CHECK='TRUE';
      ALLOW_CONNECT='TRUE';
    'VSS358':
      PIN_NUMBER='(0,0,0,0,0,0,0,0,0,0,0,0,0,0,0,0,0,0,0,0,0,0,0,0,0,0,0,0,0,0,0~
,0,0,0,0,0,AW25,0,0,0,0,0)';
      PINUSE='POWER';
      NO_LOAD_CHECK='Both';
      NO_IO_CHECK='Both';
      NO_ASSERT_CHECK='TRUE';
      NO_DIR_CHECK='TRUE';
      ALLOW_CONNECT='TRUE';
    'VSS357':
      PIN_NUMBER='(0,0,0,0,0,0,0,0,0,0,0,0,0,0,0,0,0,0,0,0,0,0,0,0,0,0,0,0,0,0,0~
,0,0,0,0,0,AW23,0,0,0,0,0)';
      PINUSE='POWER';
      NO_LOAD_CHECK='Both';
      NO_IO_CHECK='Both';
      NO_ASSERT_CHECK='TRUE';
      NO_DIR_CHECK='TRUE';
      ALLOW_CONNECT='TRUE';
    'VSS356':
      PIN_NUMBER='(0,0,0,0,0,0,0,0,0,0,0,0,0,0,0,0,0,0,0,0,0,0,0,0,0,0,0,0,0,0,0~
,0,0,0,0,0,AW21,0,0,0,0,0)';
      PINUSE='POWER';
      NO_LOAD_CHECK='Both';
      NO_IO_CHECK='Both';
      NO_ASSERT_CHECK='TRUE';
      NO_DIR_CHECK='TRUE';
      ALLOW_CONNECT='TRUE';
    'VSS0':
      PIN_NUMBER='(0,0,0,0,0,0,0,0,0,0,0,0,0,0,0,0,0,0,0,0,0,0,0,0,0,0,0,0,0,0,0~
,0,0,0,0,0,BR5,0,0,0,0,0)';
      PINUSE='POWER';
      NO_LOAD_CHECK='Both';
      NO_IO_CHECK='Both';
      NO_ASSERT_CHECK='TRUE';
      NO_DIR_CHECK='TRUE';
      ALLOW_CONNECT='TRUE';
    'VSS368':
      PIN_NUMBER='(0,0,0,0,0,0,0,0,0,0,0,0,0,0,0,0,0,0,0,0,0,0,0,0,0,0,0,0,0,0,0~
,0,0,0,0,0,0,AW9,0,0,0,0)';
      PINUSE='POWER';
      NO_LOAD_CHECK='Both';
      NO_IO_CHECK='Both';
      NO_ASSERT_CHECK='TRUE';
      NO_DIR_CHECK='TRUE';
      ALLOW_CONNECT='TRUE';
    'VSS359':
      PIN_NUMBER='(0,0,0,0,0,0,0,0,0,0,0,0,0,0,0,0,0,0,0,0,0,0,0,0,0,0,0,0,0,0,0~
,0,0,0,0,0,0,AW5,0,0,0,0)';
      PINUSE='POWER';
      NO_LOAD_CHECK='Both';
      NO_IO_CHECK='Both';
      NO_ASSERT_CHECK='TRUE';
      NO_DIR_CHECK='TRUE';
      ALLOW_CONNECT='TRUE';
    'VSS355':
      PIN_NUMBER='(0,0,0,0,0,0,0,0,0,0,0,0,0,0,0,0,0,0,0,0,0,0,0,0,0,0,0,0,0,0,0~
,0,0,0,0,0,0,AW13,0,0,0,0)';
      PINUSE='POWER';
      NO_LOAD_CHECK='Both';
      NO_IO_CHECK='Both';
      NO_ASSERT_CHECK='TRUE';
      NO_DIR_CHECK='TRUE';
      ALLOW_CONNECT='TRUE';
    'VSS354':
      PIN_NUMBER='(0,0,0,0,0,0,0,0,0,0,0,0,0,0,0,0,0,0,0,0,0,0,0,0,0,0,0,0,0,0,0~
,0,0,0,0,0,0,AW1,0,0,0,0)';
      PINUSE='POWER';
      NO_LOAD_CHECK='Both';
      NO_IO_CHECK='Both';
      NO_ASSERT_CHECK='TRUE';
      NO_DIR_CHECK='TRUE';
      ALLOW_CONNECT='TRUE';
    'VSS353':
      PIN_NUMBER='(0,0,0,0,0,0,0,0,0,0,0,0,0,0,0,0,0,0,0,0,0,0,0,0,0,0,0,0,0,0,0~
,0,0,0,0,0,0,AV91,0,0,0,0)';
      PINUSE='POWER';
      NO_LOAD_CHECK='Both';
      NO_IO_CHECK='Both';
      NO_ASSERT_CHECK='TRUE';
      NO_DIR_CHECK='TRUE';
      ALLOW_CONNECT='TRUE';
    'VSS352':
      PIN_NUMBER='(0,0,0,0,0,0,0,0,0,0,0,0,0,0,0,0,0,0,0,0,0,0,0,0,0,0,0,0,0,0,0~
,0,0,0,0,0,0,AV87,0,0,0,0)';
      PINUSE='POWER';
      NO_LOAD_CHECK='Both';
      NO_IO_CHECK='Both';
      NO_ASSERT_CHECK='TRUE';
      NO_DIR_CHECK='TRUE';
      ALLOW_CONNECT='TRUE';
    'VSS351':
      PIN_NUMBER='(0,0,0,0,0,0,0,0,0,0,0,0,0,0,0,0,0,0,0,0,0,0,0,0,0,0,0,0,0,0,0~
,0,0,0,0,0,0,AV8,0,0,0,0)';
      PINUSE='POWER';
      NO_LOAD_CHECK='Both';
      NO_IO_CHECK='Both';
      NO_ASSERT_CHECK='TRUE';
      NO_DIR_CHECK='TRUE';
      ALLOW_CONNECT='TRUE';
    'VSS350':
      PIN_NUMBER='(0,0,0,0,0,0,0,0,0,0,0,0,0,0,0,0,0,0,0,0,0,0,0,0,0,0,0,0,0,0,0~
,0,0,0,0,0,0,AV77,0,0,0,0)';
      PINUSE='POWER';
      NO_LOAD_CHECK='Both';
      NO_IO_CHECK='Both';
      NO_ASSERT_CHECK='TRUE';
      NO_DIR_CHECK='TRUE';
      ALLOW_CONNECT='TRUE';
    'VSS349':
      PIN_NUMBER='(0,0,0,0,0,0,0,0,0,0,0,0,0,0,0,0,0,0,0,0,0,0,0,0,0,0,0,0,0,0,0~
,0,0,0,0,0,0,AV4,0,0,0,0)';
      PINUSE='POWER';
      NO_LOAD_CHECK='Both';
      NO_IO_CHECK='Both';
      NO_ASSERT_CHECK='TRUE';
      NO_DIR_CHECK='TRUE';
      ALLOW_CONNECT='TRUE';
    'VSS348':
      PIN_NUMBER='(0,0,0,0,0,0,0,0,0,0,0,0,0,0,0,0,0,0,0,0,0,0,0,0,0,0,0,0,0,0,0~
,0,0,0,0,0,0,AV16,0,0,0,0)';
      PINUSE='POWER';
      NO_LOAD_CHECK='Both';
      NO_IO_CHECK='Both';
      NO_ASSERT_CHECK='TRUE';
      NO_DIR_CHECK='TRUE';
      ALLOW_CONNECT='TRUE';
    'VSS347':
      PIN_NUMBER='(0,0,0,0,0,0,0,0,0,0,0,0,0,0,0,0,0,0,0,0,0,0,0,0,0,0,0,0,0,0,0~
,0,0,0,0,0,0,AV12,0,0,0,0)';
      PINUSE='POWER';
      NO_LOAD_CHECK='Both';
      NO_IO_CHECK='Both';
      NO_ASSERT_CHECK='TRUE';
      NO_DIR_CHECK='TRUE';
      ALLOW_CONNECT='TRUE';
    'VSS346':
      PIN_NUMBER='(0,0,0,0,0,0,0,0,0,0,0,0,0,0,0,0,0,0,0,0,0,0,0,0,0,0,0,0,0,0,0~
,0,0,0,0,0,0,AU88,0,0,0,0)';
      PINUSE='POWER';
      NO_LOAD_CHECK='Both';
      NO_IO_CHECK='Both';
      NO_ASSERT_CHECK='TRUE';
      NO_DIR_CHECK='TRUE';
      ALLOW_CONNECT='TRUE';
    'VSS345':
      PIN_NUMBER='(0,0,0,0,0,0,0,0,0,0,0,0,0,0,0,0,0,0,0,0,0,0,0,0,0,0,0,0,0,0,0~
,0,0,0,0,0,0,AU84,0,0,0,0)';
      PINUSE='POWER';
      NO_LOAD_CHECK='Both';
      NO_IO_CHECK='Both';
      NO_ASSERT_CHECK='TRUE';
      NO_DIR_CHECK='TRUE';
      ALLOW_CONNECT='TRUE';
    'VSS344':
      PIN_NUMBER='(0,0,0,0,0,0,0,0,0,0,0,0,0,0,0,0,0,0,0,0,0,0,0,0,0,0,0,0,0,0,0~
,0,0,0,0,0,0,AU80,0,0,0,0)';
      PINUSE='POWER';
      NO_LOAD_CHECK='Both';
      NO_IO_CHECK='Both';
      NO_ASSERT_CHECK='TRUE';
      NO_DIR_CHECK='TRUE';
      ALLOW_CONNECT='TRUE';
    'VSS343':
      PIN_NUMBER='(0,0,0,0,0,0,0,0,0,0,0,0,0,0,0,0,0,0,0,0,0,0,0,0,0,0,0,0,0,0,0~
,0,0,0,0,0,0,AU76,0,0,0,0)';
      PINUSE='POWER';
      NO_LOAD_CHECK='Both';
      NO_IO_CHECK='Both';
      NO_ASSERT_CHECK='TRUE';
      NO_DIR_CHECK='TRUE';
      ALLOW_CONNECT='TRUE';
    'VSS342':
      PIN_NUMBER='(0,0,0,0,0,0,0,0,0,0,0,0,0,0,0,0,0,0,0,0,0,0,0,0,0,0,0,0,0,0,0~
,0,0,0,0,0,0,AU74,0,0,0,0)';
      PINUSE='POWER';
      NO_LOAD_CHECK='Both';
      NO_IO_CHECK='Both';
      NO_ASSERT_CHECK='TRUE';
      NO_DIR_CHECK='TRUE';
      ALLOW_CONNECT='TRUE';
    'VSS341':
      PIN_NUMBER='(0,0,0,0,0,0,0,0,0,0,0,0,0,0,0,0,0,0,0,0,0,0,0,0,0,0,0,0,0,0,0~
,0,0,0,0,0,0,AU72,0,0,0,0)';
      PINUSE='POWER';
      NO_LOAD_CHECK='Both';
      NO_IO_CHECK='Both';
      NO_ASSERT_CHECK='TRUE';
      NO_DIR_CHECK='TRUE';
      ALLOW_CONNECT='TRUE';
    'VSS340':
      PIN_NUMBER='(0,0,0,0,0,0,0,0,0,0,0,0,0,0,0,0,0,0,0,0,0,0,0,0,0,0,0,0,0,0,0~
,0,0,0,0,0,0,AU70,0,0,0,0)';
      PINUSE='POWER';
      NO_LOAD_CHECK='Both';
      NO_IO_CHECK='Both';
      NO_ASSERT_CHECK='TRUE';
      NO_DIR_CHECK='TRUE';
      ALLOW_CONNECT='TRUE';
    'VSS339':
      PIN_NUMBER='(0,0,0,0,0,0,0,0,0,0,0,0,0,0,0,0,0,0,0,0,0,0,0,0,0,0,0,0,0,0,0~
,0,0,0,0,0,0,AU48,0,0,0,0)';
      PINUSE='POWER';
      NO_LOAD_CHECK='Both';
      NO_IO_CHECK='Both';
      NO_ASSERT_CHECK='TRUE';
      NO_DIR_CHECK='TRUE';
      ALLOW_CONNECT='TRUE';
    'VSS338':
      PIN_NUMBER='(0,0,0,0,0,0,0,0,0,0,0,0,0,0,0,0,0,0,0,0,0,0,0,0,0,0,0,0,0,0,0~
,0,0,0,0,0,0,AU45,0,0,0,0)';
      PINUSE='POWER';
      NO_LOAD_CHECK='Both';
      NO_IO_CHECK='Both';
      NO_ASSERT_CHECK='TRUE';
      NO_DIR_CHECK='TRUE';
      ALLOW_CONNECT='TRUE';
    'VSS337':
      PIN_NUMBER='(0,0,0,0,0,0,0,0,0,0,0,0,0,0,0,0,0,0,0,0,0,0,0,0,0,0,0,0,0,0,0~
,0,0,0,0,0,0,AU41,0,0,0,0)';
      PINUSE='POWER';
      NO_LOAD_CHECK='Both';
      NO_IO_CHECK='Both';
      NO_ASSERT_CHECK='TRUE';
      NO_DIR_CHECK='TRUE';
      ALLOW_CONNECT='TRUE';
    'VSS336':
      PIN_NUMBER='(0,0,0,0,0,0,0,0,0,0,0,0,0,0,0,0,0,0,0,0,0,0,0,0,0,0,0,0,0,0,0~
,0,0,0,0,0,0,AU39,0,0,0,0)';
      PINUSE='POWER';
      NO_LOAD_CHECK='Both';
      NO_IO_CHECK='Both';
      NO_ASSERT_CHECK='TRUE';
      NO_DIR_CHECK='TRUE';
      ALLOW_CONNECT='TRUE';
    'VSS335':
      PIN_NUMBER='(0,0,0,0,0,0,0,0,0,0,0,0,0,0,0,0,0,0,0,0,0,0,0,0,0,0,0,0,0,0,0~
,0,0,0,0,0,0,AU37,0,0,0,0)';
      PINUSE='POWER';
      NO_LOAD_CHECK='Both';
      NO_IO_CHECK='Both';
      NO_ASSERT_CHECK='TRUE';
      NO_DIR_CHECK='TRUE';
      ALLOW_CONNECT='TRUE';
    'VSS334':
      PIN_NUMBER='(0,0,0,0,0,0,0,0,0,0,0,0,0,0,0,0,0,0,0,0,0,0,0,0,0,0,0,0,0,0,0~
,0,0,0,0,0,0,AU31,0,0,0,0)';
      PINUSE='POWER';
      NO_LOAD_CHECK='Both';
      NO_IO_CHECK='Both';
      NO_ASSERT_CHECK='TRUE';
      NO_DIR_CHECK='TRUE';
      ALLOW_CONNECT='TRUE';
    'VSS333':
      PIN_NUMBER='(0,0,0,0,0,0,0,0,0,0,0,0,0,0,0,0,0,0,0,0,0,0,0,0,0,0,0,0,0,0,0~
,0,0,0,0,0,0,AU27,0,0,0,0)';
      PINUSE='POWER';
      NO_LOAD_CHECK='Both';
      NO_IO_CHECK='Both';
      NO_ASSERT_CHECK='TRUE';
      NO_DIR_CHECK='TRUE';
      ALLOW_CONNECT='TRUE';
    'VSS332':
      PIN_NUMBER='(0,0,0,0,0,0,0,0,0,0,0,0,0,0,0,0,0,0,0,0,0,0,0,0,0,0,0,0,0,0,0~
,0,0,0,0,0,0,AT8,0,0,0,0)';
      PINUSE='POWER';
      NO_LOAD_CHECK='Both';
      NO_IO_CHECK='Both';
      NO_ASSERT_CHECK='TRUE';
      NO_DIR_CHECK='TRUE';
      ALLOW_CONNECT='TRUE';
    'VSS331':
      PIN_NUMBER='(0,0,0,0,0,0,0,0,0,0,0,0,0,0,0,0,0,0,0,0,0,0,0,0,0,0,0,0,0,0,0~
,0,0,0,0,0,0,AT79,0,0,0,0)';
      PINUSE='POWER';
      NO_LOAD_CHECK='Both';
      NO_IO_CHECK='Both';
      NO_ASSERT_CHECK='TRUE';
      NO_DIR_CHECK='TRUE';
      ALLOW_CONNECT='TRUE';
    'VSS330':
      PIN_NUMBER='(0,0,0,0,0,0,0,0,0,0,0,0,0,0,0,0,0,0,0,0,0,0,0,0,0,0,0,0,0,0,0~
,0,0,0,0,0,0,AT77,0,0,0,0)';
      PINUSE='POWER';
      NO_LOAD_CHECK='Both';
      NO_IO_CHECK='Both';
      NO_ASSERT_CHECK='TRUE';
      NO_DIR_CHECK='TRUE';
      ALLOW_CONNECT='TRUE';
    'VSS329':
      PIN_NUMBER='(0,0,0,0,0,0,0,0,0,0,0,0,0,0,0,0,0,0,0,0,0,0,0,0,0,0,0,0,0,0,0~
,0,0,0,0,0,0,AT75,0,0,0,0)';
      PINUSE='POWER';
      NO_LOAD_CHECK='Both';
      NO_IO_CHECK='Both';
      NO_ASSERT_CHECK='TRUE';
      NO_DIR_CHECK='TRUE';
      ALLOW_CONNECT='TRUE';
    'VSS328':
      PIN_NUMBER='(0,0,0,0,0,0,0,0,0,0,0,0,0,0,0,0,0,0,0,0,0,0,0,0,0,0,0,0,0,0,0~
,0,0,0,0,0,0,AT71,0,0,0,0)';
      PINUSE='POWER';
      NO_LOAD_CHECK='Both';
      NO_IO_CHECK='Both';
      NO_ASSERT_CHECK='TRUE';
      NO_DIR_CHECK='TRUE';
      ALLOW_CONNECT='TRUE';
    'VSS327':
      PIN_NUMBER='(0,0,0,0,0,0,0,0,0,0,0,0,0,0,0,0,0,0,0,0,0,0,0,0,0,0,0,0,0,0,0~
,0,0,0,0,0,0,AT69,0,0,0,0)';
      PINUSE='POWER';
      NO_LOAD_CHECK='Both';
      NO_IO_CHECK='Both';
      NO_ASSERT_CHECK='TRUE';
      NO_DIR_CHECK='TRUE';
      ALLOW_CONNECT='TRUE';
    'VSS326':
      PIN_NUMBER='(0,0,0,0,0,0,0,0,0,0,0,0,0,0,0,0,0,0,0,0,0,0,0,0,0,0,0,0,0,0,0~
,0,0,0,0,0,0,AT65,0,0,0,0)';
      PINUSE='POWER';
      NO_LOAD_CHECK='Both';
      NO_IO_CHECK='Both';
      NO_ASSERT_CHECK='TRUE';
      NO_DIR_CHECK='TRUE';
      ALLOW_CONNECT='TRUE';
    'VSS325':
      PIN_NUMBER='(0,0,0,0,0,0,0,0,0,0,0,0,0,0,0,0,0,0,0,0,0,0,0,0,0,0,0,0,0,0,0~
,0,0,0,0,0,0,AT63,0,0,0,0)';
      PINUSE='POWER';
      NO_LOAD_CHECK='Both';
      NO_IO_CHECK='Both';
      NO_ASSERT_CHECK='TRUE';
      NO_DIR_CHECK='TRUE';
      ALLOW_CONNECT='TRUE';
    'VSS324':
      PIN_NUMBER='(0,0,0,0,0,0,0,0,0,0,0,0,0,0,0,0,0,0,0,0,0,0,0,0,0,0,0,0,0,0,0~
,0,0,0,0,0,0,AT59,0,0,0,0)';
      PINUSE='POWER';
      NO_LOAD_CHECK='Both';
      NO_IO_CHECK='Both';
      NO_ASSERT_CHECK='TRUE';
      NO_DIR_CHECK='TRUE';
      ALLOW_CONNECT='TRUE';
    'VSS323':
      PIN_NUMBER='(0,0,0,0,0,0,0,0,0,0,0,0,0,0,0,0,0,0,0,0,0,0,0,0,0,0,0,0,0,0,0~
,0,0,0,0,0,0,AT57,0,0,0,0)';
      PINUSE='POWER';
      NO_LOAD_CHECK='Both';
      NO_IO_CHECK='Both';
      NO_ASSERT_CHECK='TRUE';
      NO_DIR_CHECK='TRUE';
      ALLOW_CONNECT='TRUE';
    'VSS322':
      PIN_NUMBER='(0,0,0,0,0,0,0,0,0,0,0,0,0,0,0,0,0,0,0,0,0,0,0,0,0,0,0,0,0,0,0~
,0,0,0,0,0,0,AT53,0,0,0,0)';
      PINUSE='POWER';
      NO_LOAD_CHECK='Both';
      NO_IO_CHECK='Both';
      NO_ASSERT_CHECK='TRUE';
      NO_DIR_CHECK='TRUE';
      ALLOW_CONNECT='TRUE';
    'VSS321':
      PIN_NUMBER='(0,0,0,0,0,0,0,0,0,0,0,0,0,0,0,0,0,0,0,0,0,0,0,0,0,0,0,0,0,0,0~
,0,0,0,0,0,0,AT51,0,0,0,0)';
      PINUSE='POWER';
      NO_LOAD_CHECK='Both';
      NO_IO_CHECK='Both';
      NO_ASSERT_CHECK='TRUE';
      NO_DIR_CHECK='TRUE';
      ALLOW_CONNECT='TRUE';
    'VSS320':
      PIN_NUMBER='(0,0,0,0,0,0,0,0,0,0,0,0,0,0,0,0,0,0,0,0,0,0,0,0,0,0,0,0,0,0,0~
,0,0,0,0,0,0,AT44,0,0,0,0)';
      PINUSE='POWER';
      NO_LOAD_CHECK='Both';
      NO_IO_CHECK='Both';
      NO_ASSERT_CHECK='TRUE';
      NO_DIR_CHECK='TRUE';
      ALLOW_CONNECT='TRUE';
    'VSS319':
      PIN_NUMBER='(0,0,0,0,0,0,0,0,0,0,0,0,0,0,0,0,0,0,0,0,0,0,0,0,0,0,0,0,0,0,0~
,0,0,0,0,0,0,AT40,0,0,0,0)';
      PINUSE='POWER';
      NO_LOAD_CHECK='Both';
      NO_IO_CHECK='Both';
      NO_ASSERT_CHECK='TRUE';
      NO_DIR_CHECK='TRUE';
      ALLOW_CONNECT='TRUE';
    'VSS318':
      PIN_NUMBER='(0,0,0,0,0,0,0,0,0,0,0,0,0,0,0,0,0,0,0,0,0,0,0,0,0,0,0,0,0,0,0~
,0,0,0,0,0,0,AT4,0,0,0,0)';
      PINUSE='POWER';
      NO_LOAD_CHECK='Both';
      NO_IO_CHECK='Both';
      NO_ASSERT_CHECK='TRUE';
      NO_DIR_CHECK='TRUE';
      ALLOW_CONNECT='TRUE';
    'VSS317':
      PIN_NUMBER='(0,0,0,0,0,0,0,0,0,0,0,0,0,0,0,0,0,0,0,0,0,0,0,0,0,0,0,0,0,0,0~
,0,0,0,0,0,0,AT38,0,0,0,0)';
      PINUSE='POWER';
      NO_LOAD_CHECK='Both';
      NO_IO_CHECK='Both';
      NO_ASSERT_CHECK='TRUE';
      NO_DIR_CHECK='TRUE';
      ALLOW_CONNECT='TRUE';
    'VSS316':
      PIN_NUMBER='(0,0,0,0,0,0,0,0,0,0,0,0,0,0,0,0,0,0,0,0,0,0,0,0,0,0,0,0,0,0,0~
,0,0,0,0,0,0,AT34,0,0,0,0)';
      PINUSE='POWER';
      NO_LOAD_CHECK='Both';
      NO_IO_CHECK='Both';
      NO_ASSERT_CHECK='TRUE';
      NO_DIR_CHECK='TRUE';
      ALLOW_CONNECT='TRUE';
    'VSS315':
      PIN_NUMBER='(0,0,0,0,0,0,0,0,0,0,0,0,0,0,0,0,0,0,0,0,0,0,0,0,0,0,0,0,0,0,0~
,0,0,0,0,0,0,AT32,0,0,0,0)';
      PINUSE='POWER';
      NO_LOAD_CHECK='Both';
      NO_IO_CHECK='Both';
      NO_ASSERT_CHECK='TRUE';
      NO_DIR_CHECK='TRUE';
      ALLOW_CONNECT='TRUE';
    'VSS314':
      PIN_NUMBER='(0,0,0,0,0,0,0,0,0,0,0,0,0,0,0,0,0,0,0,0,0,0,0,0,0,0,0,0,0,0,0~
,0,0,0,0,0,0,AT28,0,0,0,0)';
      PINUSE='POWER';
      NO_LOAD_CHECK='Both';
      NO_IO_CHECK='Both';
      NO_ASSERT_CHECK='TRUE';
      NO_DIR_CHECK='TRUE';
      ALLOW_CONNECT='TRUE';
    'VSS313':
      PIN_NUMBER='(0,0,0,0,0,0,0,0,0,0,0,0,0,0,0,0,0,0,0,0,0,0,0,0,0,0,0,0,0,0,0~
,0,0,0,0,0,0,AT26,0,0,0,0)';
      PINUSE='POWER';
      NO_LOAD_CHECK='Both';
      NO_IO_CHECK='Both';
      NO_ASSERT_CHECK='TRUE';
      NO_DIR_CHECK='TRUE';
      ALLOW_CONNECT='TRUE';
    'VSS312':
      PIN_NUMBER='(0,0,0,0,0,0,0,0,0,0,0,0,0,0,0,0,0,0,0,0,0,0,0,0,0,0,0,0,0,0,0~
,0,0,0,0,0,0,AT22,0,0,0,0)';
      PINUSE='POWER';
      NO_LOAD_CHECK='Both';
      NO_IO_CHECK='Both';
      NO_ASSERT_CHECK='TRUE';
      NO_DIR_CHECK='TRUE';
      ALLOW_CONNECT='TRUE';
    'VSS311':
      PIN_NUMBER='(0,0,0,0,0,0,0,0,0,0,0,0,0,0,0,0,0,0,0,0,0,0,0,0,0,0,0,0,0,0,0~
,0,0,0,0,0,0,AT20,0,0,0,0)';
      PINUSE='POWER';
      NO_LOAD_CHECK='Both';
      NO_IO_CHECK='Both';
      NO_ASSERT_CHECK='TRUE';
      NO_DIR_CHECK='TRUE';
      ALLOW_CONNECT='TRUE';
    'VSS310':
      PIN_NUMBER='(0,0,0,0,0,0,0,0,0,0,0,0,0,0,0,0,0,0,0,0,0,0,0,0,0,0,0,0,0,0,0~
,0,0,0,0,0,0,AT16,0,0,0,0)';
      PINUSE='POWER';
      NO_LOAD_CHECK='Both';
      NO_IO_CHECK='Both';
      NO_ASSERT_CHECK='TRUE';
      NO_DIR_CHECK='TRUE';
      ALLOW_CONNECT='TRUE';
    'VSS309':
      PIN_NUMBER='(0,0,0,0,0,0,0,0,0,0,0,0,0,0,0,0,0,0,0,0,0,0,0,0,0,0,0,0,0,0,0~
,0,0,0,0,0,0,AT12,0,0,0,0)';
      PINUSE='POWER';
      NO_LOAD_CHECK='Both';
      NO_IO_CHECK='Both';
      NO_ASSERT_CHECK='TRUE';
      NO_DIR_CHECK='TRUE';
      ALLOW_CONNECT='TRUE';
    'VSS308':
      PIN_NUMBER='(0,0,0,0,0,0,0,0,0,0,0,0,0,0,0,0,0,0,0,0,0,0,0,0,0,0,0,0,0,0,0~
,0,0,0,0,0,0,AR9,0,0,0,0)';
      PINUSE='POWER';
      NO_LOAD_CHECK='Both';
      NO_IO_CHECK='Both';
      NO_ASSERT_CHECK='TRUE';
      NO_DIR_CHECK='TRUE';
      ALLOW_CONNECT='TRUE';
    'VSS307':
      PIN_NUMBER='(0,0,0,0,0,0,0,0,0,0,0,0,0,0,0,0,0,0,0,0,0,0,0,0,0,0,0,0,0,0,0~
,0,0,0,0,0,0,AR88,0,0,0,0)';
      PINUSE='POWER';
      NO_LOAD_CHECK='Both';
      NO_IO_CHECK='Both';
      NO_ASSERT_CHECK='TRUE';
      NO_DIR_CHECK='TRUE';
      ALLOW_CONNECT='TRUE';
    'VSS306':
      PIN_NUMBER='(0,0,0,0,0,0,0,0,0,0,0,0,0,0,0,0,0,0,0,0,0,0,0,0,0,0,0,0,0,0,0~
,0,0,0,0,0,0,AR84,0,0,0,0)';
      PINUSE='POWER';
      NO_LOAD_CHECK='Both';
      NO_IO_CHECK='Both';
      NO_ASSERT_CHECK='TRUE';
      NO_DIR_CHECK='TRUE';
      ALLOW_CONNECT='TRUE';
    'VSS305':
      PIN_NUMBER='(0,0,0,0,0,0,0,0,0,0,0,0,0,0,0,0,0,0,0,0,0,0,0,0,0,0,0,0,0,0,0~
,0,0,0,0,0,0,AR82,0,0,0,0)';
      PINUSE='POWER';
      NO_LOAD_CHECK='Both';
      NO_IO_CHECK='Both';
      NO_ASSERT_CHECK='TRUE';
      NO_DIR_CHECK='TRUE';
      ALLOW_CONNECT='TRUE';
    'VSS304':
      PIN_NUMBER='(0,0,0,0,0,0,0,0,0,0,0,0,0,0,0,0,0,0,0,0,0,0,0,0,0,0,0,0,0,0,0~
,0,0,0,0,0,0,AR78,0,0,0,0)';
      PINUSE='POWER';
      NO_LOAD_CHECK='Both';
      NO_IO_CHECK='Both';
      NO_ASSERT_CHECK='TRUE';
      NO_DIR_CHECK='TRUE';
      ALLOW_CONNECT='TRUE';
    'VSS303':
      PIN_NUMBER='(0,0,0,0,0,0,0,0,0,0,0,0,0,0,0,0,0,0,0,0,0,0,0,0,0,0,0,0,0,0,0~
,0,0,0,0,0,0,AR74,0,0,0,0)';
      PINUSE='POWER';
      NO_LOAD_CHECK='Both';
      NO_IO_CHECK='Both';
      NO_ASSERT_CHECK='TRUE';
      NO_DIR_CHECK='TRUE';
      ALLOW_CONNECT='TRUE';
    'VSS302':
      PIN_NUMBER='(0,0,0,0,0,0,0,0,0,0,0,0,0,0,0,0,0,0,0,0,0,0,0,0,0,0,0,0,0,0,0~
,0,0,0,0,0,0,AR72,0,0,0,0)';
      PINUSE='POWER';
      NO_LOAD_CHECK='Both';
      NO_IO_CHECK='Both';
      NO_ASSERT_CHECK='TRUE';
      NO_DIR_CHECK='TRUE';
      ALLOW_CONNECT='TRUE';
    'VSS301':
      PIN_NUMBER='(0,0,0,0,0,0,0,0,0,0,0,0,0,0,0,0,0,0,0,0,0,0,0,0,0,0,0,0,0,0,0~
,0,0,0,0,0,0,AR68,0,0,0,0)';
      PINUSE='POWER';
      NO_LOAD_CHECK='Both';
      NO_IO_CHECK='Both';
      NO_ASSERT_CHECK='TRUE';
      NO_DIR_CHECK='TRUE';
      ALLOW_CONNECT='TRUE';
    'VSS300':
      PIN_NUMBER='(0,0,0,0,0,0,0,0,0,0,0,0,0,0,0,0,0,0,0,0,0,0,0,0,0,0,0,0,0,0,0~
,0,0,0,0,0,0,AR66,0,0,0,0)';
      PINUSE='POWER';
      NO_LOAD_CHECK='Both';
      NO_IO_CHECK='Both';
      NO_ASSERT_CHECK='TRUE';
      NO_DIR_CHECK='TRUE';
      ALLOW_CONNECT='TRUE';
    'VSS299':
      PIN_NUMBER='(0,0,0,0,0,0,0,0,0,0,0,0,0,0,0,0,0,0,0,0,0,0,0,0,0,0,0,0,0,0,0~
,0,0,0,0,0,0,AR62,0,0,0,0)';
      PINUSE='POWER';
      NO_LOAD_CHECK='Both';
      NO_IO_CHECK='Both';
      NO_ASSERT_CHECK='TRUE';
      NO_DIR_CHECK='TRUE';
      ALLOW_CONNECT='TRUE';
    'VSS298':
      PIN_NUMBER='(0,0,0,0,0,0,0,0,0,0,0,0,0,0,0,0,0,0,0,0,0,0,0,0,0,0,0,0,0,0,0~
,0,0,0,0,0,0,AR60,0,0,0,0)';
      PINUSE='POWER';
      NO_LOAD_CHECK='Both';
      NO_IO_CHECK='Both';
      NO_ASSERT_CHECK='TRUE';
      NO_DIR_CHECK='TRUE';
      ALLOW_CONNECT='TRUE';
    'VSS297':
      PIN_NUMBER='(0,0,0,0,0,0,0,0,0,0,0,0,0,0,0,0,0,0,0,0,0,0,0,0,0,0,0,0,0,0,0~
,0,0,0,0,0,0,AR56,0,0,0,0)';
      PINUSE='POWER';
      NO_LOAD_CHECK='Both';
      NO_IO_CHECK='Both';
      NO_ASSERT_CHECK='TRUE';
      NO_DIR_CHECK='TRUE';
      ALLOW_CONNECT='TRUE';
    'VSS296':
      PIN_NUMBER='(0,0,0,0,0,0,0,0,0,0,0,0,0,0,0,0,0,0,0,0,0,0,0,0,0,0,0,0,0,0,0~
,0,0,0,0,0,0,AR54,0,0,0,0)';
      PINUSE='POWER';
      NO_LOAD_CHECK='Both';
      NO_IO_CHECK='Both';
      NO_ASSERT_CHECK='TRUE';
      NO_DIR_CHECK='TRUE';
      ALLOW_CONNECT='TRUE';
    'VSS295':
      PIN_NUMBER='(0,0,0,0,0,0,0,0,0,0,0,0,0,0,0,0,0,0,0,0,0,0,0,0,0,0,0,0,0,0,0~
,0,0,0,0,0,0,AR50,0,0,0,0)';
      PINUSE='POWER';
      NO_LOAD_CHECK='Both';
      NO_IO_CHECK='Both';
      NO_ASSERT_CHECK='TRUE';
      NO_DIR_CHECK='TRUE';
      ALLOW_CONNECT='TRUE';
    'VSS294':
      PIN_NUMBER='(0,0,0,0,0,0,0,0,0,0,0,0,0,0,0,0,0,0,0,0,0,0,0,0,0,0,0,0,0,0,0~
,0,0,0,0,0,0,AR5,0,0,0,0)';
      PINUSE='POWER';
      NO_LOAD_CHECK='Both';
      NO_IO_CHECK='Both';
      NO_ASSERT_CHECK='TRUE';
      NO_DIR_CHECK='TRUE';
      ALLOW_CONNECT='TRUE';
    'VSS293':
      PIN_NUMBER='(0,0,0,0,0,0,0,0,0,0,0,0,0,0,0,0,0,0,0,0,0,0,0,0,0,0,0,0,0,0,0~
,0,0,0,0,0,0,AR48,0,0,0,0)';
      PINUSE='POWER';
      NO_LOAD_CHECK='Both';
      NO_IO_CHECK='Both';
      NO_ASSERT_CHECK='TRUE';
      NO_DIR_CHECK='TRUE';
      ALLOW_CONNECT='TRUE';
    'VSS292':
      PIN_NUMBER='(0,0,0,0,0,0,0,0,0,0,0,0,0,0,0,0,0,0,0,0,0,0,0,0,0,0,0,0,0,0,0~
,0,0,0,0,0,0,AR43,0,0,0,0)';
      PINUSE='POWER';
      NO_LOAD_CHECK='Both';
      NO_IO_CHECK='Both';
      NO_ASSERT_CHECK='TRUE';
      NO_DIR_CHECK='TRUE';
      ALLOW_CONNECT='TRUE';
    'VSS291':
      PIN_NUMBER='(0,0,0,0,0,0,0,0,0,0,0,0,0,0,0,0,0,0,0,0,0,0,0,0,0,0,0,0,0,0,0~
,0,0,0,0,0,0,AR41,0,0,0,0)';
      PINUSE='POWER';
      NO_LOAD_CHECK='Both';
      NO_IO_CHECK='Both';
      NO_ASSERT_CHECK='TRUE';
      NO_DIR_CHECK='TRUE';
      ALLOW_CONNECT='TRUE';
    'VSS290':
      PIN_NUMBER='(0,0,0,0,0,0,0,0,0,0,0,0,0,0,0,0,0,0,0,0,0,0,0,0,0,0,0,0,0,0,0~
,0,0,0,0,0,0,AR37,0,0,0,0)';
      PINUSE='POWER';
      NO_LOAD_CHECK='Both';
      NO_IO_CHECK='Both';
      NO_ASSERT_CHECK='TRUE';
      NO_DIR_CHECK='TRUE';
      ALLOW_CONNECT='TRUE';
    'VSS289':
      PIN_NUMBER='(0,0,0,0,0,0,0,0,0,0,0,0,0,0,0,0,0,0,0,0,0,0,0,0,0,0,0,0,0,0,0~
,0,0,0,0,0,0,AR35,0,0,0,0)';
      PINUSE='POWER';
      NO_LOAD_CHECK='Both';
      NO_IO_CHECK='Both';
      NO_ASSERT_CHECK='TRUE';
      NO_DIR_CHECK='TRUE';
      ALLOW_CONNECT='TRUE';
    'VSS288':
      PIN_NUMBER='(0,0,0,0,0,0,0,0,0,0,0,0,0,0,0,0,0,0,0,0,0,0,0,0,0,0,0,0,0,0,0~
,0,0,0,0,0,0,AR31,0,0,0,0)';
      PINUSE='POWER';
      NO_LOAD_CHECK='Both';
      NO_IO_CHECK='Both';
      NO_ASSERT_CHECK='TRUE';
      NO_DIR_CHECK='TRUE';
      ALLOW_CONNECT='TRUE';
    'VSS287':
      PIN_NUMBER='(0,0,0,0,0,0,0,0,0,0,0,0,0,0,0,0,0,0,0,0,0,0,0,0,0,0,0,0,0,0,0~
,0,0,0,0,0,0,AR29,0,0,0,0)';
      PINUSE='POWER';
      NO_LOAD_CHECK='Both';
      NO_IO_CHECK='Both';
      NO_ASSERT_CHECK='TRUE';
      NO_DIR_CHECK='TRUE';
      ALLOW_CONNECT='TRUE';
    'VSS286':
      PIN_NUMBER='(0,0,0,0,0,0,0,0,0,0,0,0,0,0,0,0,0,0,0,0,0,0,0,0,0,0,0,0,0,0,0~
,0,0,0,0,0,0,AR25,0,0,0,0)';
      PINUSE='POWER';
      NO_LOAD_CHECK='Both';
      NO_IO_CHECK='Both';
      NO_ASSERT_CHECK='TRUE';
      NO_DIR_CHECK='TRUE';
      ALLOW_CONNECT='TRUE';
    'VSS285':
      PIN_NUMBER='(0,0,0,0,0,0,0,0,0,0,0,0,0,0,0,0,0,0,0,0,0,0,0,0,0,0,0,0,0,0,0~
,0,0,0,0,0,0,AR23,0,0,0,0)';
      PINUSE='POWER';
      NO_LOAD_CHECK='Both';
      NO_IO_CHECK='Both';
      NO_ASSERT_CHECK='TRUE';
      NO_DIR_CHECK='TRUE';
      ALLOW_CONNECT='TRUE';
    'VSS284':
      PIN_NUMBER='(0,0,0,0,0,0,0,0,0,0,0,0,0,0,0,0,0,0,0,0,0,0,0,0,0,0,0,0,0,0,0~
,0,0,0,0,0,0,AR19,0,0,0,0)';
      PINUSE='POWER';
      NO_LOAD_CHECK='Both';
      NO_IO_CHECK='Both';
      NO_ASSERT_CHECK='TRUE';
      NO_DIR_CHECK='TRUE';
      ALLOW_CONNECT='TRUE';
    'VSS283':
      PIN_NUMBER='(0,0,0,0,0,0,0,0,0,0,0,0,0,0,0,0,0,0,0,0,0,0,0,0,0,0,0,0,0,0,0~
,0,0,0,0,0,0,AR13,0,0,0,0)';
      PINUSE='POWER';
      NO_LOAD_CHECK='Both';
      NO_IO_CHECK='Both';
      NO_ASSERT_CHECK='TRUE';
      NO_DIR_CHECK='TRUE';
      ALLOW_CONNECT='TRUE';
    'VSS282':
      PIN_NUMBER='(0,0,0,0,0,0,0,0,0,0,0,0,0,0,0,0,0,0,0,0,0,0,0,0,0,0,0,0,0,0,0~
,0,0,0,0,0,0,AR1,0,0,0,0)';
      PINUSE='POWER';
      NO_LOAD_CHECK='Both';
      NO_IO_CHECK='Both';
      NO_ASSERT_CHECK='TRUE';
      NO_DIR_CHECK='TRUE';
      ALLOW_CONNECT='TRUE';
    'VSS281':
      PIN_NUMBER='(0,0,0,0,0,0,0,0,0,0,0,0,0,0,0,0,0,0,0,0,0,0,0,0,0,0,0,0,0,0,0~
,0,0,0,0,0,0,AP91,0,0,0,0)';
      PINUSE='POWER';
      NO_LOAD_CHECK='Both';
      NO_IO_CHECK='Both';
      NO_ASSERT_CHECK='TRUE';
      NO_DIR_CHECK='TRUE';
      ALLOW_CONNECT='TRUE';
    'VSS280':
      PIN_NUMBER='(0,0,0,0,0,0,0,0,0,0,0,0,0,0,0,0,0,0,0,0,0,0,0,0,0,0,0,0,0,0,0~
,0,0,0,0,0,0,AP87,0,0,0,0)';
      PINUSE='POWER';
      NO_LOAD_CHECK='Both';
      NO_IO_CHECK='Both';
      NO_ASSERT_CHECK='TRUE';
      NO_DIR_CHECK='TRUE';
      ALLOW_CONNECT='TRUE';
    'VSS279':
      PIN_NUMBER='(0,0,0,0,0,0,0,0,0,0,0,0,0,0,0,0,0,0,0,0,0,0,0,0,0,0,0,0,0,0,0~
,0,0,0,0,0,0,AP83,0,0,0,0)';
      PINUSE='POWER';
      NO_LOAD_CHECK='Both';
      NO_IO_CHECK='Both';
      NO_ASSERT_CHECK='TRUE';
      NO_DIR_CHECK='TRUE';
      ALLOW_CONNECT='TRUE';
    'VSS278':
      PIN_NUMBER='(0,0,0,0,0,0,0,0,0,0,0,0,0,0,0,0,0,0,0,0,0,0,0,0,0,0,0,0,0,0,0~
,0,0,0,0,0,0,AP8,0,0,0,0)';
      PINUSE='POWER';
      NO_LOAD_CHECK='Both';
      NO_IO_CHECK='Both';
      NO_ASSERT_CHECK='TRUE';
      NO_DIR_CHECK='TRUE';
      ALLOW_CONNECT='TRUE';
    'VSS277':
      PIN_NUMBER='(0,0,0,0,0,0,0,0,0,0,0,0,0,0,0,0,0,0,0,0,0,0,0,0,0,0,0,0,0,0,0~
,0,0,0,0,0,0,AP79,0,0,0,0)';
      PINUSE='POWER';
      NO_LOAD_CHECK='Both';
      NO_IO_CHECK='Both';
      NO_ASSERT_CHECK='TRUE';
      NO_DIR_CHECK='TRUE';
      ALLOW_CONNECT='TRUE';
    'VSS276':
      PIN_NUMBER='(0,0,0,0,0,0,0,0,0,0,0,0,0,0,0,0,0,0,0,0,0,0,0,0,0,0,0,0,0,0,0~
,0,0,0,0,0,0,AP73,0,0,0,0)';
      PINUSE='POWER';
      NO_LOAD_CHECK='Both';
      NO_IO_CHECK='Both';
      NO_ASSERT_CHECK='TRUE';
      NO_DIR_CHECK='TRUE';
      ALLOW_CONNECT='TRUE';
    'VSS275':
      PIN_NUMBER='(0,0,0,0,0,0,0,0,0,0,0,0,0,0,0,0,0,0,0,0,0,0,0,0,0,0,0,0,0,0,0~
,0,0,0,0,0,0,AP67,0,0,0,0)';
      PINUSE='POWER';
      NO_LOAD_CHECK='Both';
      NO_IO_CHECK='Both';
      NO_ASSERT_CHECK='TRUE';
      NO_DIR_CHECK='TRUE';
      ALLOW_CONNECT='TRUE';
    'VSS274':
      PIN_NUMBER='(0,0,0,0,0,0,0,0,0,0,0,0,0,0,0,0,0,0,0,0,0,0,0,0,0,0,0,0,0,0,0~
,0,0,0,0,0,0,AP61,0,0,0,0)';
      PINUSE='POWER';
      NO_LOAD_CHECK='Both';
      NO_IO_CHECK='Both';
      NO_ASSERT_CHECK='TRUE';
      NO_DIR_CHECK='TRUE';
      ALLOW_CONNECT='TRUE';
    'VSS273':
      PIN_NUMBER='(0,0,0,0,0,0,0,0,0,0,0,0,0,0,0,0,0,0,0,0,0,0,0,0,0,0,0,0,0,0,0~
,0,0,0,0,0,0,AP55,0,0,0,0)';
      PINUSE='POWER';
      NO_LOAD_CHECK='Both';
      NO_IO_CHECK='Both';
      NO_ASSERT_CHECK='TRUE';
      NO_DIR_CHECK='TRUE';
      ALLOW_CONNECT='TRUE';
    'VSS272':
      PIN_NUMBER='(0,0,0,0,0,0,0,0,0,0,0,0,0,0,0,0,0,0,0,0,0,0,0,0,0,0,0,0,0,0,0~
,0,0,0,0,0,0,AP49,0,0,0,0)';
      PINUSE='POWER';
      NO_LOAD_CHECK='Both';
      NO_IO_CHECK='Both';
      NO_ASSERT_CHECK='TRUE';
      NO_DIR_CHECK='TRUE';
      ALLOW_CONNECT='TRUE';
    'VSS271':
      PIN_NUMBER='(0,0,0,0,0,0,0,0,0,0,0,0,0,0,0,0,0,0,0,0,0,0,0,0,0,0,0,0,0,0,0~
,0,0,0,0,0,0,AP42,0,0,0,0)';
      PINUSE='POWER';
      NO_LOAD_CHECK='Both';
      NO_IO_CHECK='Both';
      NO_ASSERT_CHECK='TRUE';
      NO_DIR_CHECK='TRUE';
      ALLOW_CONNECT='TRUE';
    'VSS270':
      PIN_NUMBER='(0,0,0,0,0,0,0,0,0,0,0,0,0,0,0,0,0,0,0,0,0,0,0,0,0,0,0,0,0,0,0~
,0,0,0,0,0,0,AP4,0,0,0,0)';
      PINUSE='POWER';
      NO_LOAD_CHECK='Both';
      NO_IO_CHECK='Both';
      NO_ASSERT_CHECK='TRUE';
      NO_DIR_CHECK='TRUE';
      ALLOW_CONNECT='TRUE';
    'VSS269':
      PIN_NUMBER='(0,0,0,0,0,0,0,0,0,0,0,0,0,0,0,0,0,0,0,0,0,0,0,0,0,0,0,0,0,0,0~
,0,0,0,0,0,0,AP36,0,0,0,0)';
      PINUSE='POWER';
      NO_LOAD_CHECK='Both';
      NO_IO_CHECK='Both';
      NO_ASSERT_CHECK='TRUE';
      NO_DIR_CHECK='TRUE';
      ALLOW_CONNECT='TRUE';
    'VSS268':
      PIN_NUMBER='(0,0,0,0,0,0,0,0,0,0,0,0,0,0,0,0,0,0,0,0,0,0,0,0,0,0,0,0,0,0,0~
,0,0,0,0,0,0,AP30,0,0,0,0)';
      PINUSE='POWER';
      NO_LOAD_CHECK='Both';
      NO_IO_CHECK='Both';
      NO_ASSERT_CHECK='TRUE';
      NO_DIR_CHECK='TRUE';
      ALLOW_CONNECT='TRUE';
    'VSS267':
      PIN_NUMBER='(0,0,0,0,0,0,0,0,0,0,0,0,0,0,0,0,0,0,0,0,0,0,0,0,0,0,0,0,0,0,0~
,0,0,0,0,0,0,AP24,0,0,0,0)';
      PINUSE='POWER';
      NO_LOAD_CHECK='Both';
      NO_IO_CHECK='Both';
      NO_ASSERT_CHECK='TRUE';
      NO_DIR_CHECK='TRUE';
      ALLOW_CONNECT='TRUE';
    'VSS266':
      PIN_NUMBER='(0,0,0,0,0,0,0,0,0,0,0,0,0,0,0,0,0,0,0,0,0,0,0,0,0,0,0,0,0,0,0~
,0,0,0,0,0,0,AP18,0,0,0,0)';
      PINUSE='POWER';
      NO_LOAD_CHECK='Both';
      NO_IO_CHECK='Both';
      NO_ASSERT_CHECK='TRUE';
      NO_DIR_CHECK='TRUE';
      ALLOW_CONNECT='TRUE';
    'VSS265':
      PIN_NUMBER='(0,0,0,0,0,0,0,0,0,0,0,0,0,0,0,0,0,0,0,0,0,0,0,0,0,0,0,0,0,0,0~
,0,0,0,0,0,0,AP16,0,0,0,0)';
      PINUSE='POWER';
      NO_LOAD_CHECK='Both';
      NO_IO_CHECK='Both';
      NO_ASSERT_CHECK='TRUE';
      NO_DIR_CHECK='TRUE';
      ALLOW_CONNECT='TRUE';
    'VSS264':
      PIN_NUMBER='(0,0,0,0,0,0,0,0,0,0,0,0,0,0,0,0,0,0,0,0,0,0,0,0,0,0,0,0,0,0,0~
,0,0,0,0,0,0,AP12,0,0,0,0)';
      PINUSE='POWER';
      NO_LOAD_CHECK='Both';
      NO_IO_CHECK='Both';
      NO_ASSERT_CHECK='TRUE';
      NO_DIR_CHECK='TRUE';
      ALLOW_CONNECT='TRUE';
    'VSS263':
      PIN_NUMBER='(0,0,0,0,0,0,0,0,0,0,0,0,0,0,0,0,0,0,0,0,0,0,0,0,0,0,0,0,0,0,0~
,0,0,0,0,0,0,AN88,0,0,0,0)';
      PINUSE='POWER';
      NO_LOAD_CHECK='Both';
      NO_IO_CHECK='Both';
      NO_ASSERT_CHECK='TRUE';
      NO_DIR_CHECK='TRUE';
      ALLOW_CONNECT='TRUE';
    'VSS262':
      PIN_NUMBER='(0,0,0,0,0,0,0,0,0,0,0,0,0,0,0,0,0,0,0,0,0,0,0,0,0,0,0,0,0,0,0~
,0,0,0,0,0,0,AN84,0,0,0,0)';
      PINUSE='POWER';
      NO_LOAD_CHECK='Both';
      NO_IO_CHECK='Both';
      NO_ASSERT_CHECK='TRUE';
      NO_DIR_CHECK='TRUE';
      ALLOW_CONNECT='TRUE';
    'VSS261':
      PIN_NUMBER='(0,0,0,0,0,0,0,0,0,0,0,0,0,0,0,0,0,0,0,0,0,0,0,0,0,0,0,0,0,0,0~
,0,0,0,0,0,0,AN52,0,0,0,0)';
      PINUSE='POWER';
      NO_LOAD_CHECK='Both';
      NO_IO_CHECK='Both';
      NO_ASSERT_CHECK='TRUE';
      NO_DIR_CHECK='TRUE';
      ALLOW_CONNECT='TRUE';
    'VSS260':
      PIN_NUMBER='(0,0,0,0,0,0,0,0,0,0,0,0,0,0,0,0,0,0,0,0,0,0,0,0,0,0,0,0,0,0,0~
,0,0,0,0,0,0,AM8,0,0,0,0)';
      PINUSE='POWER';
      NO_LOAD_CHECK='Both';
      NO_IO_CHECK='Both';
      NO_ASSERT_CHECK='TRUE';
      NO_DIR_CHECK='TRUE';
      ALLOW_CONNECT='TRUE';
    'VSS259':
      PIN_NUMBER='(0,0,0,0,0,0,0,0,0,0,0,0,0,0,0,0,0,0,0,0,0,0,0,0,0,0,0,0,0,0,0~
,0,0,0,0,0,0,AM77,0,0,0,0)';
      PINUSE='POWER';
      NO_LOAD_CHECK='Both';
      NO_IO_CHECK='Both';
      NO_ASSERT_CHECK='TRUE';
      NO_DIR_CHECK='TRUE';
      ALLOW_CONNECT='TRUE';
    'VSS258':
      PIN_NUMBER='(0,0,0,0,0,0,0,0,0,0,0,0,0,0,0,0,0,0,0,0,0,0,0,0,0,0,0,0,0,0,0~
,0,0,0,0,0,0,AM75,0,0,0,0)';
      PINUSE='POWER';
      NO_LOAD_CHECK='Both';
      NO_IO_CHECK='Both';
      NO_ASSERT_CHECK='TRUE';
      NO_DIR_CHECK='TRUE';
      ALLOW_CONNECT='TRUE';
    'VSS257':
      PIN_NUMBER='(0,0,0,0,0,0,0,0,0,0,0,0,0,0,0,0,0,0,0,0,0,0,0,0,0,0,0,0,0,0,0~
,0,0,0,0,0,0,AM73,0,0,0,0)';
      PINUSE='POWER';
      NO_LOAD_CHECK='Both';
      NO_IO_CHECK='Both';
      NO_ASSERT_CHECK='TRUE';
      NO_DIR_CHECK='TRUE';
      ALLOW_CONNECT='TRUE';
    'VSS256':
      PIN_NUMBER='(0,0,0,0,0,0,0,0,0,0,0,0,0,0,0,0,0,0,0,0,0,0,0,0,0,0,0,0,0,0,0~
,0,0,0,0,0,0,AM71,0,0,0,0)';
      PINUSE='POWER';
      NO_LOAD_CHECK='Both';
      NO_IO_CHECK='Both';
      NO_ASSERT_CHECK='TRUE';
      NO_DIR_CHECK='TRUE';
      ALLOW_CONNECT='TRUE';
    'VSS255':
      PIN_NUMBER='(0,0,0,0,0,0,0,0,0,0,0,0,0,0,0,0,0,0,0,0,0,0,0,0,0,0,0,0,0,0,0~
,0,0,0,0,0,0,AM69,0,0,0,0)';
      PINUSE='POWER';
      NO_LOAD_CHECK='Both';
      NO_IO_CHECK='Both';
      NO_ASSERT_CHECK='TRUE';
      NO_DIR_CHECK='TRUE';
      ALLOW_CONNECT='TRUE';
    'VSS254':
      PIN_NUMBER='(0,0,0,0,0,0,0,0,0,0,0,0,0,0,0,0,0,0,0,0,0,0,0,0,0,0,0,0,0,0,0~
,0,0,0,0,0,0,AM67,0,0,0,0)';
      PINUSE='POWER';
      NO_LOAD_CHECK='Both';
      NO_IO_CHECK='Both';
      NO_ASSERT_CHECK='TRUE';
      NO_DIR_CHECK='TRUE';
      ALLOW_CONNECT='TRUE';
    'VSS253':
      PIN_NUMBER='(0,0,0,0,0,0,0,0,0,0,0,0,0,0,0,0,0,0,0,0,0,0,0,0,0,0,0,0,0,0,0~
,0,0,0,0,0,0,AM65,0,0,0,0)';
      PINUSE='POWER';
      NO_LOAD_CHECK='Both';
      NO_IO_CHECK='Both';
      NO_ASSERT_CHECK='TRUE';
      NO_DIR_CHECK='TRUE';
      ALLOW_CONNECT='TRUE';
    'VSS252':
      PIN_NUMBER='(0,0,0,0,0,0,0,0,0,0,0,0,0,0,0,0,0,0,0,0,0,0,0,0,0,0,0,0,0,0,0~
,0,0,0,0,0,0,AM63,0,0,0,0)';
      PINUSE='POWER';
      NO_LOAD_CHECK='Both';
      NO_IO_CHECK='Both';
      NO_ASSERT_CHECK='TRUE';
      NO_DIR_CHECK='TRUE';
      ALLOW_CONNECT='TRUE';
    'VSS251':
      PIN_NUMBER='(0,0,0,0,0,0,0,0,0,0,0,0,0,0,0,0,0,0,0,0,0,0,0,0,0,0,0,0,0,0,0~
,0,0,0,0,0,0,AM61,0,0,0,0)';
      PINUSE='POWER';
      NO_LOAD_CHECK='Both';
      NO_IO_CHECK='Both';
      NO_ASSERT_CHECK='TRUE';
      NO_DIR_CHECK='TRUE';
      ALLOW_CONNECT='TRUE';
    'VSS250':
      PIN_NUMBER='(0,0,0,0,0,0,0,0,0,0,0,0,0,0,0,0,0,0,0,0,0,0,0,0,0,0,0,0,0,0,0~
,0,0,0,0,0,0,AM59,0,0,0,0)';
      PINUSE='POWER';
      NO_LOAD_CHECK='Both';
      NO_IO_CHECK='Both';
      NO_ASSERT_CHECK='TRUE';
      NO_DIR_CHECK='TRUE';
      ALLOW_CONNECT='TRUE';
    'VSS249':
      PIN_NUMBER='(0,0,0,0,0,0,0,0,0,0,0,0,0,0,0,0,0,0,0,0,0,0,0,0,0,0,0,0,0,0,0~
,0,0,0,0,0,0,AM57,0,0,0,0)';
      PINUSE='POWER';
      NO_LOAD_CHECK='Both';
      NO_IO_CHECK='Both';
      NO_ASSERT_CHECK='TRUE';
      NO_DIR_CHECK='TRUE';
      ALLOW_CONNECT='TRUE';
    'VSS248':
      PIN_NUMBER='(0,0,0,0,0,0,0,0,0,0,0,0,0,0,0,0,0,0,0,0,0,0,0,0,0,0,0,0,0,0,0~
,0,0,0,0,0,0,AM55,0,0,0,0)';
      PINUSE='POWER';
      NO_LOAD_CHECK='Both';
      NO_IO_CHECK='Both';
      NO_ASSERT_CHECK='TRUE';
      NO_DIR_CHECK='TRUE';
      ALLOW_CONNECT='TRUE';
    'VSS247':
      PIN_NUMBER='(0,0,0,0,0,0,0,0,0,0,0,0,0,0,0,0,0,0,0,0,0,0,0,0,0,0,0,0,0,0,0~
,0,0,0,0,0,0,AM53,0,0,0,0)';
      PINUSE='POWER';
      NO_LOAD_CHECK='Both';
      NO_IO_CHECK='Both';
      NO_ASSERT_CHECK='TRUE';
      NO_DIR_CHECK='TRUE';
      ALLOW_CONNECT='TRUE';
    'VSS246':
      PIN_NUMBER='(0,0,0,0,0,0,0,0,0,0,0,0,0,0,0,0,0,0,0,0,0,0,0,0,0,0,0,0,0,0,0~
,0,0,0,0,0,0,AM51,0,0,0,0)';
      PINUSE='POWER';
      NO_LOAD_CHECK='Both';
      NO_IO_CHECK='Both';
      NO_ASSERT_CHECK='TRUE';
      NO_DIR_CHECK='TRUE';
      ALLOW_CONNECT='TRUE';
    'VSS245':
      PIN_NUMBER='(0,0,0,0,0,0,0,0,0,0,0,0,0,0,0,0,0,0,0,0,0,0,0,0,0,0,0,0,0,0,0~
,0,0,0,0,0,0,AM49,0,0,0,0)';
      PINUSE='POWER';
      NO_LOAD_CHECK='Both';
      NO_IO_CHECK='Both';
      NO_ASSERT_CHECK='TRUE';
      NO_DIR_CHECK='TRUE';
      ALLOW_CONNECT='TRUE';
    'VSS244':
      PIN_NUMBER='(0,0,0,0,0,0,0,0,0,0,0,0,0,0,0,0,0,0,0,0,0,0,0,0,0,0,0,0,0,0,0~
,0,0,0,0,0,0,AM47,0,0,0,0)';
      PINUSE='POWER';
      NO_LOAD_CHECK='Both';
      NO_IO_CHECK='Both';
      NO_ASSERT_CHECK='TRUE';
      NO_DIR_CHECK='TRUE';
      ALLOW_CONNECT='TRUE';
    'VSS243':
      PIN_NUMBER='(0,0,0,0,0,0,0,0,0,0,0,0,0,0,0,0,0,0,0,0,0,0,0,0,0,0,0,0,0,0,0~
,0,0,0,0,0,0,AM44,0,0,0,0)';
      PINUSE='POWER';
      NO_LOAD_CHECK='Both';
      NO_IO_CHECK='Both';
      NO_ASSERT_CHECK='TRUE';
      NO_DIR_CHECK='TRUE';
      ALLOW_CONNECT='TRUE';
    'VSS242':
      PIN_NUMBER='(0,0,0,0,0,0,0,0,0,0,0,0,0,0,0,0,0,0,0,0,0,0,0,0,0,0,0,0,0,0,0~
,0,0,0,0,0,0,AM42,0,0,0,0)';
      PINUSE='POWER';
      NO_LOAD_CHECK='Both';
      NO_IO_CHECK='Both';
      NO_ASSERT_CHECK='TRUE';
      NO_DIR_CHECK='TRUE';
      ALLOW_CONNECT='TRUE';
    'VSS241':
      PIN_NUMBER='(0,0,0,0,0,0,0,0,0,0,0,0,0,0,0,0,0,0,0,0,0,0,0,0,0,0,0,0,0,0,0~
,0,0,0,0,0,0,AM40,0,0,0,0)';
      PINUSE='POWER';
      NO_LOAD_CHECK='Both';
      NO_IO_CHECK='Both';
      NO_ASSERT_CHECK='TRUE';
      NO_DIR_CHECK='TRUE';
      ALLOW_CONNECT='TRUE';
    'VSS240':
      PIN_NUMBER='(0,0,0,0,0,0,0,0,0,0,0,0,0,0,0,0,0,0,0,0,0,0,0,0,0,0,0,0,0,0,0~
,0,0,0,0,0,0,AM4,0,0,0,0)';
      PINUSE='POWER';
      NO_LOAD_CHECK='Both';
      NO_IO_CHECK='Both';
      NO_ASSERT_CHECK='TRUE';
      NO_DIR_CHECK='TRUE';
      ALLOW_CONNECT='TRUE';
    'VSS239':
      PIN_NUMBER='(0,0,0,0,0,0,0,0,0,0,0,0,0,0,0,0,0,0,0,0,0,0,0,0,0,0,0,0,0,0,0~
,0,0,0,0,0,0,AM38,0,0,0,0)';
      PINUSE='POWER';
      NO_LOAD_CHECK='Both';
      NO_IO_CHECK='Both';
      NO_ASSERT_CHECK='TRUE';
      NO_DIR_CHECK='TRUE';
      ALLOW_CONNECT='TRUE';
    'VSS238':
      PIN_NUMBER='(0,0,0,0,0,0,0,0,0,0,0,0,0,0,0,0,0,0,0,0,0,0,0,0,0,0,0,0,0,0,0~
,0,0,0,0,0,0,AM36,0,0,0,0)';
      PINUSE='POWER';
      NO_LOAD_CHECK='Both';
      NO_IO_CHECK='Both';
      NO_ASSERT_CHECK='TRUE';
      NO_DIR_CHECK='TRUE';
      ALLOW_CONNECT='TRUE';
    'VSS237':
      PIN_NUMBER='(0,0,0,0,0,0,0,0,0,0,0,0,0,0,0,0,0,0,0,0,0,0,0,0,0,0,0,0,0,0,0~
,0,0,0,0,0,0,AM34,0,0,0,0)';
      PINUSE='POWER';
      NO_LOAD_CHECK='Both';
      NO_IO_CHECK='Both';
      NO_ASSERT_CHECK='TRUE';
      NO_DIR_CHECK='TRUE';
      ALLOW_CONNECT='TRUE';
    'VSS236':
      PIN_NUMBER='(0,0,0,0,0,0,0,0,0,0,0,0,0,0,0,0,0,0,0,0,0,0,0,0,0,0,0,0,0,0,0~
,0,0,0,0,0,0,AM32,0,0,0,0)';
      PINUSE='POWER';
      NO_LOAD_CHECK='Both';
      NO_IO_CHECK='Both';
      NO_ASSERT_CHECK='TRUE';
      NO_DIR_CHECK='TRUE';
      ALLOW_CONNECT='TRUE';
    'VSS235':
      PIN_NUMBER='(0,0,0,0,0,0,0,0,0,0,0,0,0,0,0,0,0,0,0,0,0,0,0,0,0,0,0,0,0,0,0~
,0,0,0,0,0,0,AM30,0,0,0,0)';
      PINUSE='POWER';
      NO_LOAD_CHECK='Both';
      NO_IO_CHECK='Both';
      NO_ASSERT_CHECK='TRUE';
      NO_DIR_CHECK='TRUE';
      ALLOW_CONNECT='TRUE';
    'VSS234':
      PIN_NUMBER='(0,0,0,0,0,0,0,0,0,0,0,0,0,0,0,0,0,0,0,0,0,0,0,0,0,0,0,0,0,0,0~
,0,0,0,0,0,0,AM28,0,0,0,0)';
      PINUSE='POWER';
      NO_LOAD_CHECK='Both';
      NO_IO_CHECK='Both';
      NO_ASSERT_CHECK='TRUE';
      NO_DIR_CHECK='TRUE';
      ALLOW_CONNECT='TRUE';
    'VSS233':
      PIN_NUMBER='(0,0,0,0,0,0,0,0,0,0,0,0,0,0,0,0,0,0,0,0,0,0,0,0,0,0,0,0,0,0,0~
,0,0,0,0,0,0,AM26,0,0,0,0)';
      PINUSE='POWER';
      NO_LOAD_CHECK='Both';
      NO_IO_CHECK='Both';
      NO_ASSERT_CHECK='TRUE';
      NO_DIR_CHECK='TRUE';
      ALLOW_CONNECT='TRUE';
    'VSS232':
      PIN_NUMBER='(0,0,0,0,0,0,0,0,0,0,0,0,0,0,0,0,0,0,0,0,0,0,0,0,0,0,0,0,0,0,0~
,0,0,0,0,0,0,AM24,0,0,0,0)';
      PINUSE='POWER';
      NO_LOAD_CHECK='Both';
      NO_IO_CHECK='Both';
      NO_ASSERT_CHECK='TRUE';
      NO_DIR_CHECK='TRUE';
      ALLOW_CONNECT='TRUE';
    'VSS231':
      PIN_NUMBER='(0,0,0,0,0,0,0,0,0,0,0,0,0,0,0,0,0,0,0,0,0,0,0,0,0,0,0,0,0,0,0~
,0,0,0,0,0,0,AM22,0,0,0,0)';
      PINUSE='POWER';
      NO_LOAD_CHECK='Both';
      NO_IO_CHECK='Both';
      NO_ASSERT_CHECK='TRUE';
      NO_DIR_CHECK='TRUE';
      ALLOW_CONNECT='TRUE';
    'VSS230':
      PIN_NUMBER='(0,0,0,0,0,0,0,0,0,0,0,0,0,0,0,0,0,0,0,0,0,0,0,0,0,0,0,0,0,0,0~
,0,0,0,0,0,0,AM20,0,0,0,0)';
      PINUSE='POWER';
      NO_LOAD_CHECK='Both';
      NO_IO_CHECK='Both';
      NO_ASSERT_CHECK='TRUE';
      NO_DIR_CHECK='TRUE';
      ALLOW_CONNECT='TRUE';
    'VSS229':
      PIN_NUMBER='(0,0,0,0,0,0,0,0,0,0,0,0,0,0,0,0,0,0,0,0,0,0,0,0,0,0,0,0,0,0,0~
,0,0,0,0,0,0,AM18,0,0,0,0)';
      PINUSE='POWER';
      NO_LOAD_CHECK='Both';
      NO_IO_CHECK='Both';
      NO_ASSERT_CHECK='TRUE';
      NO_DIR_CHECK='TRUE';
      ALLOW_CONNECT='TRUE';
    'VSS228':
      PIN_NUMBER='(0,0,0,0,0,0,0,0,0,0,0,0,0,0,0,0,0,0,0,0,0,0,0,0,0,0,0,0,0,0,0~
,0,0,0,0,0,0,AM16,0,0,0,0)';
      PINUSE='POWER';
      NO_LOAD_CHECK='Both';
      NO_IO_CHECK='Both';
      NO_ASSERT_CHECK='TRUE';
      NO_DIR_CHECK='TRUE';
      ALLOW_CONNECT='TRUE';
    'VSS227':
      PIN_NUMBER='(0,0,0,0,0,0,0,0,0,0,0,0,0,0,0,0,0,0,0,0,0,0,0,0,0,0,0,0,0,0,0~
,0,0,0,0,0,0,AM12,0,0,0,0)';
      PINUSE='POWER';
      NO_LOAD_CHECK='Both';
      NO_IO_CHECK='Both';
      NO_ASSERT_CHECK='TRUE';
      NO_DIR_CHECK='TRUE';
      ALLOW_CONNECT='TRUE';
    'VSS226':
      PIN_NUMBER='(0,0,0,0,0,0,0,0,0,0,0,0,0,0,0,0,0,0,0,0,0,0,0,0,0,0,0,0,0,0,0~
,0,0,0,0,0,0,AL9,0,0,0,0)';
      PINUSE='POWER';
      NO_LOAD_CHECK='Both';
      NO_IO_CHECK='Both';
      NO_ASSERT_CHECK='TRUE';
      NO_DIR_CHECK='TRUE';
      ALLOW_CONNECT='TRUE';
    'VSS225':
      PIN_NUMBER='(0,0,0,0,0,0,0,0,0,0,0,0,0,0,0,0,0,0,0,0,0,0,0,0,0,0,0,0,0,0,0~
,0,0,0,0,0,0,AL88,0,0,0,0)';
      PINUSE='POWER';
      NO_LOAD_CHECK='Both';
      NO_IO_CHECK='Both';
      NO_ASSERT_CHECK='TRUE';
      NO_DIR_CHECK='TRUE';
      ALLOW_CONNECT='TRUE';
    'VSS224':
      PIN_NUMBER='(0,0,0,0,0,0,0,0,0,0,0,0,0,0,0,0,0,0,0,0,0,0,0,0,0,0,0,0,0,0,0~
,0,0,0,0,0,0,AL84,0,0,0,0)';
      PINUSE='POWER';
      NO_LOAD_CHECK='Both';
      NO_IO_CHECK='Both';
      NO_ASSERT_CHECK='TRUE';
      NO_DIR_CHECK='TRUE';
      ALLOW_CONNECT='TRUE';
    'VSS223':
      PIN_NUMBER='(0,0,0,0,0,0,0,0,0,0,0,0,0,0,0,0,0,0,0,0,0,0,0,0,0,0,0,0,0,0,0~
,0,0,0,0,0,0,AL82,0,0,0,0)';
      PINUSE='POWER';
      NO_LOAD_CHECK='Both';
      NO_IO_CHECK='Both';
      NO_ASSERT_CHECK='TRUE';
      NO_DIR_CHECK='TRUE';
      ALLOW_CONNECT='TRUE';
    'VSS222':
      PIN_NUMBER='(0,0,0,0,0,0,0,0,0,0,0,0,0,0,0,0,0,0,0,0,0,0,0,0,0,0,0,0,0,0,0~
,0,0,0,0,0,0,AL80,0,0,0,0)';
      PINUSE='POWER';
      NO_LOAD_CHECK='Both';
      NO_IO_CHECK='Both';
      NO_ASSERT_CHECK='TRUE';
      NO_DIR_CHECK='TRUE';
      ALLOW_CONNECT='TRUE';
    'VSS221':
      PIN_NUMBER='(0,0,0,0,0,0,0,0,0,0,0,0,0,0,0,0,0,0,0,0,0,0,0,0,0,0,0,0,0,0,0~
,0,0,0,0,0,0,AL52,0,0,0,0)';
      PINUSE='POWER';
      NO_LOAD_CHECK='Both';
      NO_IO_CHECK='Both';
      NO_ASSERT_CHECK='TRUE';
      NO_DIR_CHECK='TRUE';
      ALLOW_CONNECT='TRUE';
    'VSS220':
      PIN_NUMBER='(0,0,0,0,0,0,0,0,0,0,0,0,0,0,0,0,0,0,0,0,0,0,0,0,0,0,0,0,0,0,0~
,0,0,0,0,0,0,AL5,0,0,0,0)';
      PINUSE='POWER';
      NO_LOAD_CHECK='Both';
      NO_IO_CHECK='Both';
      NO_ASSERT_CHECK='TRUE';
      NO_DIR_CHECK='TRUE';
      ALLOW_CONNECT='TRUE';
    'VSS219':
      PIN_NUMBER='(0,0,0,0,0,0,0,0,0,0,0,0,0,0,0,0,0,0,0,0,0,0,0,0,0,0,0,0,0,0,0~
,0,0,0,0,0,0,AL17,0,0,0,0)';
      PINUSE='POWER';
      NO_LOAD_CHECK='Both';
      NO_IO_CHECK='Both';
      NO_ASSERT_CHECK='TRUE';
      NO_DIR_CHECK='TRUE';
      ALLOW_CONNECT='TRUE';
    'VSS218':
      PIN_NUMBER='(0,0,0,0,0,0,0,0,0,0,0,0,0,0,0,0,0,0,0,0,0,0,0,0,0,0,0,0,0,0,0~
,0,0,0,0,0,0,AL13,0,0,0,0)';
      PINUSE='POWER';
      NO_LOAD_CHECK='Both';
      NO_IO_CHECK='Both';
      NO_ASSERT_CHECK='TRUE';
      NO_DIR_CHECK='TRUE';
      ALLOW_CONNECT='TRUE';
    'VSS217':
      PIN_NUMBER='(0,0,0,0,0,0,0,0,0,0,0,0,0,0,0,0,0,0,0,0,0,0,0,0,0,0,0,0,0,0,0~
,0,0,0,0,0,0,AL1,0,0,0,0)';
      PINUSE='POWER';
      NO_LOAD_CHECK='Both';
      NO_IO_CHECK='Both';
      NO_ASSERT_CHECK='TRUE';
      NO_DIR_CHECK='TRUE';
      ALLOW_CONNECT='TRUE';
    'VSS216':
      PIN_NUMBER='(0,0,0,0,0,0,0,0,0,0,0,0,0,0,0,0,0,0,0,0,0,0,0,0,0,0,0,0,0,0,0~
,0,0,0,0,0,0,AK91,0,0,0,0)';
      PINUSE='POWER';
      NO_LOAD_CHECK='Both';
      NO_IO_CHECK='Both';
      NO_ASSERT_CHECK='TRUE';
      NO_DIR_CHECK='TRUE';
      ALLOW_CONNECT='TRUE';
    'VSS215':
      PIN_NUMBER='(0,0,0,0,0,0,0,0,0,0,0,0,0,0,0,0,0,0,0,0,0,0,0,0,0,0,0,0,0,0,0~
,0,0,0,0,0,0,AK87,0,0,0,0)';
      PINUSE='POWER';
      NO_LOAD_CHECK='Both';
      NO_IO_CHECK='Both';
      NO_ASSERT_CHECK='TRUE';
      NO_DIR_CHECK='TRUE';
      ALLOW_CONNECT='TRUE';
    'VSS214':
      PIN_NUMBER='(0,0,0,0,0,0,0,0,0,0,0,0,0,0,0,0,0,0,0,0,0,0,0,0,0,0,0,0,0,0,0~
,0,0,0,0,0,0,AK83,0,0,0,0)';
      PINUSE='POWER';
      NO_LOAD_CHECK='Both';
      NO_IO_CHECK='Both';
      NO_ASSERT_CHECK='TRUE';
      NO_DIR_CHECK='TRUE';
      ALLOW_CONNECT='TRUE';
    'VSS213':
      PIN_NUMBER='(0,0,0,0,0,0,0,0,0,0,0,0,0,0,0,0,0,0,0,0,0,0,0,0,0,0,0,0,0,0,0~
,0,0,0,0,0,0,AK81,0,0,0,0)';
      PINUSE='POWER';
      NO_LOAD_CHECK='Both';
      NO_IO_CHECK='Both';
      NO_ASSERT_CHECK='TRUE';
      NO_DIR_CHECK='TRUE';
      ALLOW_CONNECT='TRUE';
    'VSS212':
      PIN_NUMBER='(0,0,0,0,0,0,0,0,0,0,0,0,0,0,0,0,0,0,0,0,0,0,0,0,0,0,0,0,0,0,0~
,0,0,0,0,0,0,AK8,0,0,0,0)';
      PINUSE='POWER';
      NO_LOAD_CHECK='Both';
      NO_IO_CHECK='Both';
      NO_ASSERT_CHECK='TRUE';
      NO_DIR_CHECK='TRUE';
      ALLOW_CONNECT='TRUE';
    'VSS211':
      PIN_NUMBER='(0,0,0,0,0,0,0,0,0,0,0,0,0,0,0,0,0,0,0,0,0,0,0,0,0,0,0,0,0,0,0~
,0,0,0,0,0,0,AK79,0,0,0,0)';
      PINUSE='POWER';
      NO_LOAD_CHECK='Both';
      NO_IO_CHECK='Both';
      NO_ASSERT_CHECK='TRUE';
      NO_DIR_CHECK='TRUE';
      ALLOW_CONNECT='TRUE';
    'VSS210':
      PIN_NUMBER='(0,0,0,0,0,0,0,0,0,0,0,0,0,0,0,0,0,0,0,0,0,0,0,0,0,0,0,0,0,0,0~
,0,0,0,0,0,0,AK73,0,0,0,0)';
      PINUSE='POWER';
      NO_LOAD_CHECK='Both';
      NO_IO_CHECK='Both';
      NO_ASSERT_CHECK='TRUE';
      NO_DIR_CHECK='TRUE';
      ALLOW_CONNECT='TRUE';
    'VSS209':
      PIN_NUMBER='(0,0,0,0,0,0,0,0,0,0,0,0,0,0,0,0,0,0,0,0,0,0,0,0,0,0,0,0,0,0,0~
,0,0,0,0,0,0,AK67,0,0,0,0)';
      PINUSE='POWER';
      NO_LOAD_CHECK='Both';
      NO_IO_CHECK='Both';
      NO_ASSERT_CHECK='TRUE';
      NO_DIR_CHECK='TRUE';
      ALLOW_CONNECT='TRUE';
    'VSS208':
      PIN_NUMBER='(0,0,0,0,0,0,0,0,0,0,0,0,0,0,0,0,0,0,0,0,0,0,0,0,0,0,0,0,0,0,0~
,0,0,0,0,0,0,AK61,0,0,0,0)';
      PINUSE='POWER';
      NO_LOAD_CHECK='Both';
      NO_IO_CHECK='Both';
      NO_ASSERT_CHECK='TRUE';
      NO_DIR_CHECK='TRUE';
      ALLOW_CONNECT='TRUE';
    'VSS207':
      PIN_NUMBER='(0,0,0,0,0,0,0,0,0,0,0,0,0,0,0,0,0,0,0,0,0,0,0,0,0,0,0,0,0,0,0~
,0,0,0,0,0,0,AK55,0,0,0,0)';
      PINUSE='POWER';
      NO_LOAD_CHECK='Both';
      NO_IO_CHECK='Both';
      NO_ASSERT_CHECK='TRUE';
      NO_DIR_CHECK='TRUE';
      ALLOW_CONNECT='TRUE';
    'VSS206':
      PIN_NUMBER='(0,0,0,0,0,0,0,0,0,0,0,0,0,0,0,0,0,0,0,0,0,0,0,0,0,0,0,0,0,0,0~
,0,0,0,0,0,0,AK49,0,0,0,0)';
      PINUSE='POWER';
      NO_LOAD_CHECK='Both';
      NO_IO_CHECK='Both';
      NO_ASSERT_CHECK='TRUE';
      NO_DIR_CHECK='TRUE';
      ALLOW_CONNECT='TRUE';
    'VSS205':
      PIN_NUMBER='(0,0,0,0,0,0,0,0,0,0,0,0,0,0,0,0,0,0,0,0,0,0,0,0,0,0,0,0,0,0,0~
,0,0,0,0,0,0,AK42,0,0,0,0)';
      PINUSE='POWER';
      NO_LOAD_CHECK='Both';
      NO_IO_CHECK='Both';
      NO_ASSERT_CHECK='TRUE';
      NO_DIR_CHECK='TRUE';
      ALLOW_CONNECT='TRUE';
    'VSS204':
      PIN_NUMBER='(0,0,0,0,0,0,0,0,0,0,0,0,0,0,0,0,0,0,0,0,0,0,0,0,0,0,0,0,0,0,0~
,0,0,0,0,0,0,AK4,0,0,0,0)';
      PINUSE='POWER';
      NO_LOAD_CHECK='Both';
      NO_IO_CHECK='Both';
      NO_ASSERT_CHECK='TRUE';
      NO_DIR_CHECK='TRUE';
      ALLOW_CONNECT='TRUE';
    'VSS203':
      PIN_NUMBER='(0,0,0,0,0,0,0,0,0,0,0,0,0,0,0,0,0,0,0,0,0,0,0,0,0,0,0,0,0,0,0~
,0,0,0,0,0,0,AK36,0,0,0,0)';
      PINUSE='POWER';
      NO_LOAD_CHECK='Both';
      NO_IO_CHECK='Both';
      NO_ASSERT_CHECK='TRUE';
      NO_DIR_CHECK='TRUE';
      ALLOW_CONNECT='TRUE';
    'VSS202':
      PIN_NUMBER='(0,0,0,0,0,0,0,0,0,0,0,0,0,0,0,0,0,0,0,0,0,0,0,0,0,0,0,0,0,0,0~
,0,0,0,0,0,0,AK30,0,0,0,0)';
      PINUSE='POWER';
      NO_LOAD_CHECK='Both';
      NO_IO_CHECK='Both';
      NO_ASSERT_CHECK='TRUE';
      NO_DIR_CHECK='TRUE';
      ALLOW_CONNECT='TRUE';
    'VSS201':
      PIN_NUMBER='(0,0,0,0,0,0,0,0,0,0,0,0,0,0,0,0,0,0,0,0,0,0,0,0,0,0,0,0,0,0,0~
,0,0,0,0,0,0,AK24,0,0,0,0)';
      PINUSE='POWER';
      NO_LOAD_CHECK='Both';
      NO_IO_CHECK='Both';
      NO_ASSERT_CHECK='TRUE';
      NO_DIR_CHECK='TRUE';
      ALLOW_CONNECT='TRUE';
    'VSS200':
      PIN_NUMBER='(0,0,0,0,0,0,0,0,0,0,0,0,0,0,0,0,0,0,0,0,0,0,0,0,0,0,0,0,0,0,0~
,0,0,0,0,0,0,AK18,0,0,0,0)';
      PINUSE='POWER';
      NO_LOAD_CHECK='Both';
      NO_IO_CHECK='Both';
      NO_ASSERT_CHECK='TRUE';
      NO_DIR_CHECK='TRUE';
      ALLOW_CONNECT='TRUE';
    'VSS199':
      PIN_NUMBER='(0,0,0,0,0,0,0,0,0,0,0,0,0,0,0,0,0,0,0,0,0,0,0,0,0,0,0,0,0,0,0~
,0,0,0,0,0,0,AK16,0,0,0,0)';
      PINUSE='POWER';
      NO_LOAD_CHECK='Both';
      NO_IO_CHECK='Both';
      NO_ASSERT_CHECK='TRUE';
      NO_DIR_CHECK='TRUE';
      ALLOW_CONNECT='TRUE';
    'VSS198':
      PIN_NUMBER='(0,0,0,0,0,0,0,0,0,0,0,0,0,0,0,0,0,0,0,0,0,0,0,0,0,0,0,0,0,0,0~
,0,0,0,0,0,0,AK12,0,0,0,0)';
      PINUSE='POWER';
      NO_LOAD_CHECK='Both';
      NO_IO_CHECK='Both';
      NO_ASSERT_CHECK='TRUE';
      NO_DIR_CHECK='TRUE';
      ALLOW_CONNECT='TRUE';
    'VSS197':
      PIN_NUMBER='(0,0,0,0,0,0,0,0,0,0,0,0,0,0,0,0,0,0,0,0,0,0,0,0,0,0,0,0,0,0,0~
,0,0,0,0,0,0,0,AJ88,0,0,0)';
      PINUSE='POWER';
      NO_LOAD_CHECK='Both';
      NO_IO_CHECK='Both';
      NO_ASSERT_CHECK='TRUE';
      NO_DIR_CHECK='TRUE';
      ALLOW_CONNECT='TRUE';
    'VSS196':
      PIN_NUMBER='(0,0,0,0,0,0,0,0,0,0,0,0,0,0,0,0,0,0,0,0,0,0,0,0,0,0,0,0,0,0,0~
,0,0,0,0,0,0,0,AJ84,0,0,0)';
      PINUSE='POWER';
      NO_LOAD_CHECK='Both';
      NO_IO_CHECK='Both';
      NO_ASSERT_CHECK='TRUE';
      NO_DIR_CHECK='TRUE';
      ALLOW_CONNECT='TRUE';
    'VSS195':
      PIN_NUMBER='(0,0,0,0,0,0,0,0,0,0,0,0,0,0,0,0,0,0,0,0,0,0,0,0,0,0,0,0,0,0,0~
,0,0,0,0,0,0,0,AJ78,0,0,0)';
      PINUSE='POWER';
      NO_LOAD_CHECK='Both';
      NO_IO_CHECK='Both';
      NO_ASSERT_CHECK='TRUE';
      NO_DIR_CHECK='TRUE';
      ALLOW_CONNECT='TRUE';
    'VSS194':
      PIN_NUMBER='(0,0,0,0,0,0,0,0,0,0,0,0,0,0,0,0,0,0,0,0,0,0,0,0,0,0,0,0,0,0,0~
,0,0,0,0,0,0,0,AJ74,0,0,0)';
      PINUSE='POWER';
      NO_LOAD_CHECK='Both';
      NO_IO_CHECK='Both';
      NO_ASSERT_CHECK='TRUE';
      NO_DIR_CHECK='TRUE';
      ALLOW_CONNECT='TRUE';
    'VSS193':
      PIN_NUMBER='(0,0,0,0,0,0,0,0,0,0,0,0,0,0,0,0,0,0,0,0,0,0,0,0,0,0,0,0,0,0,0~
,0,0,0,0,0,0,0,AJ72,0,0,0)';
      PINUSE='POWER';
      NO_LOAD_CHECK='Both';
      NO_IO_CHECK='Both';
      NO_ASSERT_CHECK='TRUE';
      NO_DIR_CHECK='TRUE';
      ALLOW_CONNECT='TRUE';
    'VSS192':
      PIN_NUMBER='(0,0,0,0,0,0,0,0,0,0,0,0,0,0,0,0,0,0,0,0,0,0,0,0,0,0,0,0,0,0,0~
,0,0,0,0,0,0,0,AJ68,0,0,0)';
      PINUSE='POWER';
      NO_LOAD_CHECK='Both';
      NO_IO_CHECK='Both';
      NO_ASSERT_CHECK='TRUE';
      NO_DIR_CHECK='TRUE';
      ALLOW_CONNECT='TRUE';
    'VSS191':
      PIN_NUMBER='(0,0,0,0,0,0,0,0,0,0,0,0,0,0,0,0,0,0,0,0,0,0,0,0,0,0,0,0,0,0,0~
,0,0,0,0,0,0,0,AJ66,0,0,0)';
      PINUSE='POWER';
      NO_LOAD_CHECK='Both';
      NO_IO_CHECK='Both';
      NO_ASSERT_CHECK='TRUE';
      NO_DIR_CHECK='TRUE';
      ALLOW_CONNECT='TRUE';
    'VSS190':
      PIN_NUMBER='(0,0,0,0,0,0,0,0,0,0,0,0,0,0,0,0,0,0,0,0,0,0,0,0,0,0,0,0,0,0,0~
,0,0,0,0,0,0,0,AJ62,0,0,0)';
      PINUSE='POWER';
      NO_LOAD_CHECK='Both';
      NO_IO_CHECK='Both';
      NO_ASSERT_CHECK='TRUE';
      NO_DIR_CHECK='TRUE';
      ALLOW_CONNECT='TRUE';
    'VSS189':
      PIN_NUMBER='(0,0,0,0,0,0,0,0,0,0,0,0,0,0,0,0,0,0,0,0,0,0,0,0,0,0,0,0,0,0,0~
,0,0,0,0,0,0,0,AJ60,0,0,0)';
      PINUSE='POWER';
      NO_LOAD_CHECK='Both';
      NO_IO_CHECK='Both';
      NO_ASSERT_CHECK='TRUE';
      NO_DIR_CHECK='TRUE';
      ALLOW_CONNECT='TRUE';
    'VSS188':
      PIN_NUMBER='(0,0,0,0,0,0,0,0,0,0,0,0,0,0,0,0,0,0,0,0,0,0,0,0,0,0,0,0,0,0,0~
,0,0,0,0,0,0,0,AJ56,0,0,0)';
      PINUSE='POWER';
      NO_LOAD_CHECK='Both';
      NO_IO_CHECK='Both';
      NO_ASSERT_CHECK='TRUE';
      NO_DIR_CHECK='TRUE';
      ALLOW_CONNECT='TRUE';
    'VSS187':
      PIN_NUMBER='(0,0,0,0,0,0,0,0,0,0,0,0,0,0,0,0,0,0,0,0,0,0,0,0,0,0,0,0,0,0,0~
,0,0,0,0,0,0,0,AJ54,0,0,0)';
      PINUSE='POWER';
      NO_LOAD_CHECK='Both';
      NO_IO_CHECK='Both';
      NO_ASSERT_CHECK='TRUE';
      NO_DIR_CHECK='TRUE';
      ALLOW_CONNECT='TRUE';
    'VSS186':
      PIN_NUMBER='(0,0,0,0,0,0,0,0,0,0,0,0,0,0,0,0,0,0,0,0,0,0,0,0,0,0,0,0,0,0,0~
,0,0,0,0,0,0,0,AJ50,0,0,0)';
      PINUSE='POWER';
      NO_LOAD_CHECK='Both';
      NO_IO_CHECK='Both';
      NO_ASSERT_CHECK='TRUE';
      NO_DIR_CHECK='TRUE';
      ALLOW_CONNECT='TRUE';
    'VSS185':
      PIN_NUMBER='(0,0,0,0,0,0,0,0,0,0,0,0,0,0,0,0,0,0,0,0,0,0,0,0,0,0,0,0,0,0,0~
,0,0,0,0,0,0,0,AJ48,0,0,0)';
      PINUSE='POWER';
      NO_LOAD_CHECK='Both';
      NO_IO_CHECK='Both';
      NO_ASSERT_CHECK='TRUE';
      NO_DIR_CHECK='TRUE';
      ALLOW_CONNECT='TRUE';
    'VSS184':
      PIN_NUMBER='(0,0,0,0,0,0,0,0,0,0,0,0,0,0,0,0,0,0,0,0,0,0,0,0,0,0,0,0,0,0,0~
,0,0,0,0,0,0,0,AJ43,0,0,0)';
      PINUSE='POWER';
      NO_LOAD_CHECK='Both';
      NO_IO_CHECK='Both';
      NO_ASSERT_CHECK='TRUE';
      NO_DIR_CHECK='TRUE';
      ALLOW_CONNECT='TRUE';
    'VSS183':
      PIN_NUMBER='(0,0,0,0,0,0,0,0,0,0,0,0,0,0,0,0,0,0,0,0,0,0,0,0,0,0,0,0,0,0,0~
,0,0,0,0,0,0,0,AJ41,0,0,0)';
      PINUSE='POWER';
      NO_LOAD_CHECK='Both';
      NO_IO_CHECK='Both';
      NO_ASSERT_CHECK='TRUE';
      NO_DIR_CHECK='TRUE';
      ALLOW_CONNECT='TRUE';
    'VSS182':
      PIN_NUMBER='(0,0,0,0,0,0,0,0,0,0,0,0,0,0,0,0,0,0,0,0,0,0,0,0,0,0,0,0,0,0,0~
,0,0,0,0,0,0,0,AJ37,0,0,0)';
      PINUSE='POWER';
      NO_LOAD_CHECK='Both';
      NO_IO_CHECK='Both';
      NO_ASSERT_CHECK='TRUE';
      NO_DIR_CHECK='TRUE';
      ALLOW_CONNECT='TRUE';
    'VSS181':
      PIN_NUMBER='(0,0,0,0,0,0,0,0,0,0,0,0,0,0,0,0,0,0,0,0,0,0,0,0,0,0,0,0,0,0,0~
,0,0,0,0,0,0,0,AJ35,0,0,0)';
      PINUSE='POWER';
      NO_LOAD_CHECK='Both';
      NO_IO_CHECK='Both';
      NO_ASSERT_CHECK='TRUE';
      NO_DIR_CHECK='TRUE';
      ALLOW_CONNECT='TRUE';
    'VSS180':
      PIN_NUMBER='(0,0,0,0,0,0,0,0,0,0,0,0,0,0,0,0,0,0,0,0,0,0,0,0,0,0,0,0,0,0,0~
,0,0,0,0,0,0,0,AJ31,0,0,0)';
      PINUSE='POWER';
      NO_LOAD_CHECK='Both';
      NO_IO_CHECK='Both';
      NO_ASSERT_CHECK='TRUE';
      NO_DIR_CHECK='TRUE';
      ALLOW_CONNECT='TRUE';
    'VSS179':
      PIN_NUMBER='(0,0,0,0,0,0,0,0,0,0,0,0,0,0,0,0,0,0,0,0,0,0,0,0,0,0,0,0,0,0,0~
,0,0,0,0,0,0,0,AJ29,0,0,0)';
      PINUSE='POWER';
      NO_LOAD_CHECK='Both';
      NO_IO_CHECK='Both';
      NO_ASSERT_CHECK='TRUE';
      NO_DIR_CHECK='TRUE';
      ALLOW_CONNECT='TRUE';
    'VSS178':
      PIN_NUMBER='(0,0,0,0,0,0,0,0,0,0,0,0,0,0,0,0,0,0,0,0,0,0,0,0,0,0,0,0,0,0,0~
,0,0,0,0,0,0,0,AJ25,0,0,0)';
      PINUSE='POWER';
      NO_LOAD_CHECK='Both';
      NO_IO_CHECK='Both';
      NO_ASSERT_CHECK='TRUE';
      NO_DIR_CHECK='TRUE';
      ALLOW_CONNECT='TRUE';
    'VSS177':
      PIN_NUMBER='(0,0,0,0,0,0,0,0,0,0,0,0,0,0,0,0,0,0,0,0,0,0,0,0,0,0,0,0,0,0,0~
,0,0,0,0,0,0,0,AJ23,0,0,0)';
      PINUSE='POWER';
      NO_LOAD_CHECK='Both';
      NO_IO_CHECK='Both';
      NO_ASSERT_CHECK='TRUE';
      NO_DIR_CHECK='TRUE';
      ALLOW_CONNECT='TRUE';
    'VSS176':
      PIN_NUMBER='(0,0,0,0,0,0,0,0,0,0,0,0,0,0,0,0,0,0,0,0,0,0,0,0,0,0,0,0,0,0,0~
,0,0,0,0,0,0,0,AJ19,0,0,0)';
      PINUSE='POWER';
      NO_LOAD_CHECK='Both';
      NO_IO_CHECK='Both';
      NO_ASSERT_CHECK='TRUE';
      NO_DIR_CHECK='TRUE';
      ALLOW_CONNECT='TRUE';
    'VSS175':
      PIN_NUMBER='(0,0,0,0,0,0,0,0,0,0,0,0,0,0,0,0,0,0,0,0,0,0,0,0,0,0,0,0,0,0,0~
,0,0,0,0,0,0,0,AH83,0,0,0)';
      PINUSE='POWER';
      NO_LOAD_CHECK='Both';
      NO_IO_CHECK='Both';
      NO_ASSERT_CHECK='TRUE';
      NO_DIR_CHECK='TRUE';
      ALLOW_CONNECT='TRUE';
    'VSS174':
      PIN_NUMBER='(0,0,0,0,0,0,0,0,0,0,0,0,0,0,0,0,0,0,0,0,0,0,0,0,0,0,0,0,0,0,0~
,0,0,0,0,0,0,0,AH8,0,0,0)';
      PINUSE='POWER';
      NO_LOAD_CHECK='Both';
      NO_IO_CHECK='Both';
      NO_ASSERT_CHECK='TRUE';
      NO_DIR_CHECK='TRUE';
      ALLOW_CONNECT='TRUE';
    'VSS173':
      PIN_NUMBER='(0,0,0,0,0,0,0,0,0,0,0,0,0,0,0,0,0,0,0,0,0,0,0,0,0,0,0,0,0,0,0~
,0,0,0,0,0,0,0,AH79,0,0,0)';
      PINUSE='POWER';
      NO_LOAD_CHECK='Both';
      NO_IO_CHECK='Both';
      NO_ASSERT_CHECK='TRUE';
      NO_DIR_CHECK='TRUE';
      ALLOW_CONNECT='TRUE';
    'VSS172':
      PIN_NUMBER='(0,0,0,0,0,0,0,0,0,0,0,0,0,0,0,0,0,0,0,0,0,0,0,0,0,0,0,0,0,0,0~
,0,0,0,0,0,0,0,AH77,0,0,0)';
      PINUSE='POWER';
      NO_LOAD_CHECK='Both';
      NO_IO_CHECK='Both';
      NO_ASSERT_CHECK='TRUE';
      NO_DIR_CHECK='TRUE';
      ALLOW_CONNECT='TRUE';
    'VSS171':
      PIN_NUMBER='(0,0,0,0,0,0,0,0,0,0,0,0,0,0,0,0,0,0,0,0,0,0,0,0,0,0,0,0,0,0,0~
,0,0,0,0,0,0,0,AH75,0,0,0)';
      PINUSE='POWER';
      NO_LOAD_CHECK='Both';
      NO_IO_CHECK='Both';
      NO_ASSERT_CHECK='TRUE';
      NO_DIR_CHECK='TRUE';
      ALLOW_CONNECT='TRUE';
    'VSS170':
      PIN_NUMBER='(0,0,0,0,0,0,0,0,0,0,0,0,0,0,0,0,0,0,0,0,0,0,0,0,0,0,0,0,0,0,0~
,0,0,0,0,0,0,0,AH71,0,0,0)';
      PINUSE='POWER';
      NO_LOAD_CHECK='Both';
      NO_IO_CHECK='Both';
      NO_ASSERT_CHECK='TRUE';
      NO_DIR_CHECK='TRUE';
      ALLOW_CONNECT='TRUE';
    'VSS169':
      PIN_NUMBER='(0,0,0,0,0,0,0,0,0,0,0,0,0,0,0,0,0,0,0,0,0,0,0,0,0,0,0,0,0,0,0~
,0,0,0,0,0,0,0,AH69,0,0,0)';
      PINUSE='POWER';
      NO_LOAD_CHECK='Both';
      NO_IO_CHECK='Both';
      NO_ASSERT_CHECK='TRUE';
      NO_DIR_CHECK='TRUE';
      ALLOW_CONNECT='TRUE';
    'VSS168':
      PIN_NUMBER='(0,0,0,0,0,0,0,0,0,0,0,0,0,0,0,0,0,0,0,0,0,0,0,0,0,0,0,0,0,0,0~
,0,0,0,0,0,0,0,AH65,0,0,0)';
      PINUSE='POWER';
      NO_LOAD_CHECK='Both';
      NO_IO_CHECK='Both';
      NO_ASSERT_CHECK='TRUE';
      NO_DIR_CHECK='TRUE';
      ALLOW_CONNECT='TRUE';
    'VSS167':
      PIN_NUMBER='(0,0,0,0,0,0,0,0,0,0,0,0,0,0,0,0,0,0,0,0,0,0,0,0,0,0,0,0,0,0,0~
,0,0,0,0,0,0,0,AH63,0,0,0)';
      PINUSE='POWER';
      NO_LOAD_CHECK='Both';
      NO_IO_CHECK='Both';
      NO_ASSERT_CHECK='TRUE';
      NO_DIR_CHECK='TRUE';
      ALLOW_CONNECT='TRUE';
    'VSS166':
      PIN_NUMBER='(0,0,0,0,0,0,0,0,0,0,0,0,0,0,0,0,0,0,0,0,0,0,0,0,0,0,0,0,0,0,0~
,0,0,0,0,0,0,0,AH59,0,0,0)';
      PINUSE='POWER';
      NO_LOAD_CHECK='Both';
      NO_IO_CHECK='Both';
      NO_ASSERT_CHECK='TRUE';
      NO_DIR_CHECK='TRUE';
      ALLOW_CONNECT='TRUE';
    'VSS165':
      PIN_NUMBER='(0,0,0,0,0,0,0,0,0,0,0,0,0,0,0,0,0,0,0,0,0,0,0,0,0,0,0,0,0,0,0~
,0,0,0,0,0,0,0,AH57,0,0,0)';
      PINUSE='POWER';
      NO_LOAD_CHECK='Both';
      NO_IO_CHECK='Both';
      NO_ASSERT_CHECK='TRUE';
      NO_DIR_CHECK='TRUE';
      ALLOW_CONNECT='TRUE';
    'VSS164':
      PIN_NUMBER='(0,0,0,0,0,0,0,0,0,0,0,0,0,0,0,0,0,0,0,0,0,0,0,0,0,0,0,0,0,0,0~
,0,0,0,0,0,0,0,AH53,0,0,0)';
      PINUSE='POWER';
      NO_LOAD_CHECK='Both';
      NO_IO_CHECK='Both';
      NO_ASSERT_CHECK='TRUE';
      NO_DIR_CHECK='TRUE';
      ALLOW_CONNECT='TRUE';
    'VSS163':
      PIN_NUMBER='(0,0,0,0,0,0,0,0,0,0,0,0,0,0,0,0,0,0,0,0,0,0,0,0,0,0,0,0,0,0,0~
,0,0,0,0,0,0,0,AH51,0,0,0)';
      PINUSE='POWER';
      NO_LOAD_CHECK='Both';
      NO_IO_CHECK='Both';
      NO_ASSERT_CHECK='TRUE';
      NO_DIR_CHECK='TRUE';
      ALLOW_CONNECT='TRUE';
    'VSS162':
      PIN_NUMBER='(0,0,0,0,0,0,0,0,0,0,0,0,0,0,0,0,0,0,0,0,0,0,0,0,0,0,0,0,0,0,0~
,0,0,0,0,0,0,0,AH47,0,0,0)';
      PINUSE='POWER';
      NO_LOAD_CHECK='Both';
      NO_IO_CHECK='Both';
      NO_ASSERT_CHECK='TRUE';
      NO_DIR_CHECK='TRUE';
      ALLOW_CONNECT='TRUE';
    'VSS161':
      PIN_NUMBER='(0,0,0,0,0,0,0,0,0,0,0,0,0,0,0,0,0,0,0,0,0,0,0,0,0,0,0,0,0,0,0~
,0,0,0,0,0,0,0,AH44,0,0,0)';
      PINUSE='POWER';
      NO_LOAD_CHECK='Both';
      NO_IO_CHECK='Both';
      NO_ASSERT_CHECK='TRUE';
      NO_DIR_CHECK='TRUE';
      ALLOW_CONNECT='TRUE';
    'VSS160':
      PIN_NUMBER='(0,0,0,0,0,0,0,0,0,0,0,0,0,0,0,0,0,0,0,0,0,0,0,0,0,0,0,0,0,0,0~
,0,0,0,0,0,0,0,AH40,0,0,0)';
      PINUSE='POWER';
      NO_LOAD_CHECK='Both';
      NO_IO_CHECK='Both';
      NO_ASSERT_CHECK='TRUE';
      NO_DIR_CHECK='TRUE';
      ALLOW_CONNECT='TRUE';
    'VSS159':
      PIN_NUMBER='(0,0,0,0,0,0,0,0,0,0,0,0,0,0,0,0,0,0,0,0,0,0,0,0,0,0,0,0,0,0,0~
,0,0,0,0,0,0,0,AH4,0,0,0)';
      PINUSE='POWER';
      NO_LOAD_CHECK='Both';
      NO_IO_CHECK='Both';
      NO_ASSERT_CHECK='TRUE';
      NO_DIR_CHECK='TRUE';
      ALLOW_CONNECT='TRUE';
    'VSS158':
      PIN_NUMBER='(0,0,0,0,0,0,0,0,0,0,0,0,0,0,0,0,0,0,0,0,0,0,0,0,0,0,0,0,0,0,0~
,0,0,0,0,0,0,0,AH38,0,0,0)';
      PINUSE='POWER';
      NO_LOAD_CHECK='Both';
      NO_IO_CHECK='Both';
      NO_ASSERT_CHECK='TRUE';
      NO_DIR_CHECK='TRUE';
      ALLOW_CONNECT='TRUE';
    'VSS157':
      PIN_NUMBER='(0,0,0,0,0,0,0,0,0,0,0,0,0,0,0,0,0,0,0,0,0,0,0,0,0,0,0,0,0,0,0~
,0,0,0,0,0,0,0,AH34,0,0,0)';
      PINUSE='POWER';
      NO_LOAD_CHECK='Both';
      NO_IO_CHECK='Both';
      NO_ASSERT_CHECK='TRUE';
      NO_DIR_CHECK='TRUE';
      ALLOW_CONNECT='TRUE';
    'VSS156':
      PIN_NUMBER='(0,0,0,0,0,0,0,0,0,0,0,0,0,0,0,0,0,0,0,0,0,0,0,0,0,0,0,0,0,0,0~
,0,0,0,0,0,0,0,AH32,0,0,0)';
      PINUSE='POWER';
      NO_LOAD_CHECK='Both';
      NO_IO_CHECK='Both';
      NO_ASSERT_CHECK='TRUE';
      NO_DIR_CHECK='TRUE';
      ALLOW_CONNECT='TRUE';
    'VSS155':
      PIN_NUMBER='(0,0,0,0,0,0,0,0,0,0,0,0,0,0,0,0,0,0,0,0,0,0,0,0,0,0,0,0,0,0,0~
,0,0,0,0,0,0,0,AH28,0,0,0)';
      PINUSE='POWER';
      NO_LOAD_CHECK='Both';
      NO_IO_CHECK='Both';
      NO_ASSERT_CHECK='TRUE';
      NO_DIR_CHECK='TRUE';
      ALLOW_CONNECT='TRUE';
    'VSS154':
      PIN_NUMBER='(0,0,0,0,0,0,0,0,0,0,0,0,0,0,0,0,0,0,0,0,0,0,0,0,0,0,0,0,0,0,0~
,0,0,0,0,0,0,0,AH26,0,0,0)';
      PINUSE='POWER';
      NO_LOAD_CHECK='Both';
      NO_IO_CHECK='Both';
      NO_ASSERT_CHECK='TRUE';
      NO_DIR_CHECK='TRUE';
      ALLOW_CONNECT='TRUE';
    'VSS153':
      PIN_NUMBER='(0,0,0,0,0,0,0,0,0,0,0,0,0,0,0,0,0,0,0,0,0,0,0,0,0,0,0,0,0,0,0~
,0,0,0,0,0,0,0,AH22,0,0,0)';
      PINUSE='POWER';
      NO_LOAD_CHECK='Both';
      NO_IO_CHECK='Both';
      NO_ASSERT_CHECK='TRUE';
      NO_DIR_CHECK='TRUE';
      ALLOW_CONNECT='TRUE';
    'VSS152':
      PIN_NUMBER='(0,0,0,0,0,0,0,0,0,0,0,0,0,0,0,0,0,0,0,0,0,0,0,0,0,0,0,0,0,0,0~
,0,0,0,0,0,0,0,AH20,0,0,0)';
      PINUSE='POWER';
      NO_LOAD_CHECK='Both';
      NO_IO_CHECK='Both';
      NO_ASSERT_CHECK='TRUE';
      NO_DIR_CHECK='TRUE';
      ALLOW_CONNECT='TRUE';
    'VSS151':
      PIN_NUMBER='(0,0,0,0,0,0,0,0,0,0,0,0,0,0,0,0,0,0,0,0,0,0,0,0,0,0,0,0,0,0,0~
,0,0,0,0,0,0,0,AH16,0,0,0)';
      PINUSE='POWER';
      NO_LOAD_CHECK='Both';
      NO_IO_CHECK='Both';
      NO_ASSERT_CHECK='TRUE';
      NO_DIR_CHECK='TRUE';
      ALLOW_CONNECT='TRUE';
    'VSS150':
      PIN_NUMBER='(0,0,0,0,0,0,0,0,0,0,0,0,0,0,0,0,0,0,0,0,0,0,0,0,0,0,0,0,0,0,0~
,0,0,0,0,0,0,0,AH12,0,0,0)';
      PINUSE='POWER';
      NO_LOAD_CHECK='Both';
      NO_IO_CHECK='Both';
      NO_ASSERT_CHECK='TRUE';
      NO_DIR_CHECK='TRUE';
      ALLOW_CONNECT='TRUE';
    'VSS149':
      PIN_NUMBER='(0,0,0,0,0,0,0,0,0,0,0,0,0,0,0,0,0,0,0,0,0,0,0,0,0,0,0,0,0,0,0~
,0,0,0,0,0,0,0,AG9,0,0,0)';
      PINUSE='POWER';
      NO_LOAD_CHECK='Both';
      NO_IO_CHECK='Both';
      NO_ASSERT_CHECK='TRUE';
      NO_DIR_CHECK='TRUE';
      ALLOW_CONNECT='TRUE';
    'VSS148':
      PIN_NUMBER='(0,0,0,0,0,0,0,0,0,0,0,0,0,0,0,0,0,0,0,0,0,0,0,0,0,0,0,0,0,0,0~
,0,0,0,0,0,0,0,AG88,0,0,0)';
      PINUSE='POWER';
      NO_LOAD_CHECK='Both';
      NO_IO_CHECK='Both';
      NO_ASSERT_CHECK='TRUE';
      NO_DIR_CHECK='TRUE';
      ALLOW_CONNECT='TRUE';
    'VSS147':
      PIN_NUMBER='(0,0,0,0,0,0,0,0,0,0,0,0,0,0,0,0,0,0,0,0,0,0,0,0,0,0,0,0,0,0,0~
,0,0,0,0,0,0,0,AG84,0,0,0)';
      PINUSE='POWER';
      NO_LOAD_CHECK='Both';
      NO_IO_CHECK='Both';
      NO_ASSERT_CHECK='TRUE';
      NO_DIR_CHECK='TRUE';
      ALLOW_CONNECT='TRUE';
    'VSS146':
      PIN_NUMBER='(0,0,0,0,0,0,0,0,0,0,0,0,0,0,0,0,0,0,0,0,0,0,0,0,0,0,0,0,0,0,0~
,0,0,0,0,0,0,0,AG76,0,0,0)';
      PINUSE='POWER';
      NO_LOAD_CHECK='Both';
      NO_IO_CHECK='Both';
      NO_ASSERT_CHECK='TRUE';
      NO_DIR_CHECK='TRUE';
      ALLOW_CONNECT='TRUE';
    'VSS145':
      PIN_NUMBER='(0,0,0,0,0,0,0,0,0,0,0,0,0,0,0,0,0,0,0,0,0,0,0,0,0,0,0,0,0,0,0~
,0,0,0,0,0,0,0,AG70,0,0,0)';
      PINUSE='POWER';
      NO_LOAD_CHECK='Both';
      NO_IO_CHECK='Both';
      NO_ASSERT_CHECK='TRUE';
      NO_DIR_CHECK='TRUE';
      ALLOW_CONNECT='TRUE';
    'VSS144':
      PIN_NUMBER='(0,0,0,0,0,0,0,0,0,0,0,0,0,0,0,0,0,0,0,0,0,0,0,0,0,0,0,0,0,0,0~
,0,0,0,0,0,0,0,AG64,0,0,0)';
      PINUSE='POWER';
      NO_LOAD_CHECK='Both';
      NO_IO_CHECK='Both';
      NO_ASSERT_CHECK='TRUE';
      NO_DIR_CHECK='TRUE';
      ALLOW_CONNECT='TRUE';
    'VSS143':
      PIN_NUMBER='(0,0,0,0,0,0,0,0,0,0,0,0,0,0,0,0,0,0,0,0,0,0,0,0,0,0,0,0,0,0,0~
,0,0,0,0,0,0,0,AG58,0,0,0)';
      PINUSE='POWER';
      NO_LOAD_CHECK='Both';
      NO_IO_CHECK='Both';
      NO_ASSERT_CHECK='TRUE';
      NO_DIR_CHECK='TRUE';
      ALLOW_CONNECT='TRUE';
    'VSS142':
      PIN_NUMBER='(0,0,0,0,0,0,0,0,0,0,0,0,0,0,0,0,0,0,0,0,0,0,0,0,0,0,0,0,0,0,0~
,0,0,0,0,0,0,0,AG52,0,0,0)';
      PINUSE='POWER';
      NO_LOAD_CHECK='Both';
      NO_IO_CHECK='Both';
      NO_ASSERT_CHECK='TRUE';
      NO_DIR_CHECK='TRUE';
      ALLOW_CONNECT='TRUE';
    'VSS141':
      PIN_NUMBER='(0,0,0,0,0,0,0,0,0,0,0,0,0,0,0,0,0,0,0,0,0,0,0,0,0,0,0,0,0,0,0~
,0,0,0,0,0,0,0,AG5,0,0,0)';
      PINUSE='POWER';
      NO_LOAD_CHECK='Both';
      NO_IO_CHECK='Both';
      NO_ASSERT_CHECK='TRUE';
      NO_DIR_CHECK='TRUE';
      ALLOW_CONNECT='TRUE';
    'VSS140':
      PIN_NUMBER='(0,0,0,0,0,0,0,0,0,0,0,0,0,0,0,0,0,0,0,0,0,0,0,0,0,0,0,0,0,0,0~
,0,0,0,0,0,0,0,AG45,0,0,0)';
      PINUSE='POWER';
      NO_LOAD_CHECK='Both';
      NO_IO_CHECK='Both';
      NO_ASSERT_CHECK='TRUE';
      NO_DIR_CHECK='TRUE';
      ALLOW_CONNECT='TRUE';
    'VSS139':
      PIN_NUMBER='(0,0,0,0,0,0,0,0,0,0,0,0,0,0,0,0,0,0,0,0,0,0,0,0,0,0,0,0,0,0,0~
,0,0,0,0,0,0,0,AG39,0,0,0)';
      PINUSE='POWER';
      NO_LOAD_CHECK='Both';
      NO_IO_CHECK='Both';
      NO_ASSERT_CHECK='TRUE';
      NO_DIR_CHECK='TRUE';
      ALLOW_CONNECT='TRUE';
    'VSS138':
      PIN_NUMBER='(0,0,0,0,0,0,0,0,0,0,0,0,0,0,0,0,0,0,0,0,0,0,0,0,0,0,0,0,0,0,0~
,0,0,0,0,0,0,0,AG33,0,0,0)';
      PINUSE='POWER';
      NO_LOAD_CHECK='Both';
      NO_IO_CHECK='Both';
      NO_ASSERT_CHECK='TRUE';
      NO_DIR_CHECK='TRUE';
      ALLOW_CONNECT='TRUE';
    'VSS137':
      PIN_NUMBER='(0,0,0,0,0,0,0,0,0,0,0,0,0,0,0,0,0,0,0,0,0,0,0,0,0,0,0,0,0,0,0~
,0,0,0,0,0,0,0,AG27,0,0,0)';
      PINUSE='POWER';
      NO_LOAD_CHECK='Both';
      NO_IO_CHECK='Both';
      NO_ASSERT_CHECK='TRUE';
      NO_DIR_CHECK='TRUE';
      ALLOW_CONNECT='TRUE';
    'VSS136':
      PIN_NUMBER='(0,0,0,0,0,0,0,0,0,0,0,0,0,0,0,0,0,0,0,0,0,0,0,0,0,0,0,0,0,0,0~
,0,0,0,0,0,0,0,AG21,0,0,0)';
      PINUSE='POWER';
      NO_LOAD_CHECK='Both';
      NO_IO_CHECK='Both';
      NO_ASSERT_CHECK='TRUE';
      NO_DIR_CHECK='TRUE';
      ALLOW_CONNECT='TRUE';
    'VSS135':
      PIN_NUMBER='(0,0,0,0,0,0,0,0,0,0,0,0,0,0,0,0,0,0,0,0,0,0,0,0,0,0,0,0,0,0,0~
,0,0,0,0,0,0,0,AG13,0,0,0)';
      PINUSE='POWER';
      NO_LOAD_CHECK='Both';
      NO_IO_CHECK='Both';
      NO_ASSERT_CHECK='TRUE';
      NO_DIR_CHECK='TRUE';
      ALLOW_CONNECT='TRUE';
    'VSS134':
      PIN_NUMBER='(0,0,0,0,0,0,0,0,0,0,0,0,0,0,0,0,0,0,0,0,0,0,0,0,0,0,0,0,0,0,0~
,0,0,0,0,0,0,0,AG1,0,0,0)';
      PINUSE='POWER';
      NO_LOAD_CHECK='Both';
      NO_IO_CHECK='Both';
      NO_ASSERT_CHECK='TRUE';
      NO_DIR_CHECK='TRUE';
      ALLOW_CONNECT='TRUE';
    'VSS133':
      PIN_NUMBER='(0,0,0,0,0,0,0,0,0,0,0,0,0,0,0,0,0,0,0,0,0,0,0,0,0,0,0,0,0,0,0~
,0,0,0,0,0,0,0,AF91,0,0,0)';
      PINUSE='POWER';
      NO_LOAD_CHECK='Both';
      NO_IO_CHECK='Both';
      NO_ASSERT_CHECK='TRUE';
      NO_DIR_CHECK='TRUE';
      ALLOW_CONNECT='TRUE';
    'VSS132':
      PIN_NUMBER='(0,0,0,0,0,0,0,0,0,0,0,0,0,0,0,0,0,0,0,0,0,0,0,0,0,0,0,0,0,0,0~
,0,0,0,0,0,0,0,AF87,0,0,0)';
      PINUSE='POWER';
      NO_LOAD_CHECK='Both';
      NO_IO_CHECK='Both';
      NO_ASSERT_CHECK='TRUE';
      NO_DIR_CHECK='TRUE';
      ALLOW_CONNECT='TRUE';
    'VSS131':
      PIN_NUMBER='(0,0,0,0,0,0,0,0,0,0,0,0,0,0,0,0,0,0,0,0,0,0,0,0,0,0,0,0,0,0,0~
,0,0,0,0,0,0,0,AF81,0,0,0)';
      PINUSE='POWER';
      NO_LOAD_CHECK='Both';
      NO_IO_CHECK='Both';
      NO_ASSERT_CHECK='TRUE';
      NO_DIR_CHECK='TRUE';
      ALLOW_CONNECT='TRUE';
    'VSS130':
      PIN_NUMBER='(0,0,0,0,0,0,0,0,0,0,0,0,0,0,0,0,0,0,0,0,0,0,0,0,0,0,0,0,0,0,0~
,0,0,0,0,0,0,0,AF8,0,0,0)';
      PINUSE='POWER';
      NO_LOAD_CHECK='Both';
      NO_IO_CHECK='Both';
      NO_ASSERT_CHECK='TRUE';
      NO_DIR_CHECK='TRUE';
      ALLOW_CONNECT='TRUE';
    'VSS129':
      PIN_NUMBER='(0,0,0,0,0,0,0,0,0,0,0,0,0,0,0,0,0,0,0,0,0,0,0,0,0,0,0,0,0,0,0~
,0,0,0,0,0,0,0,AF42,0,0,0)';
      PINUSE='POWER';
      NO_LOAD_CHECK='Both';
      NO_IO_CHECK='Both';
      NO_ASSERT_CHECK='TRUE';
      NO_DIR_CHECK='TRUE';
      ALLOW_CONNECT='TRUE';
    'VSS128':
      PIN_NUMBER='(0,0,0,0,0,0,0,0,0,0,0,0,0,0,0,0,0,0,0,0,0,0,0,0,0,0,0,0,0,0,0~
,0,0,0,0,0,0,0,AF4,0,0,0)';
      PINUSE='POWER';
      NO_LOAD_CHECK='Both';
      NO_IO_CHECK='Both';
      NO_ASSERT_CHECK='TRUE';
      NO_DIR_CHECK='TRUE';
      ALLOW_CONNECT='TRUE';
    'VSS127':
      PIN_NUMBER='(0,0,0,0,0,0,0,0,0,0,0,0,0,0,0,0,0,0,0,0,0,0,0,0,0,0,0,0,0,0,0~
,0,0,0,0,0,0,0,AF16,0,0,0)';
      PINUSE='POWER';
      NO_LOAD_CHECK='Both';
      NO_IO_CHECK='Both';
      NO_ASSERT_CHECK='TRUE';
      NO_DIR_CHECK='TRUE';
      ALLOW_CONNECT='TRUE';
    'VSS126':
      PIN_NUMBER='(0,0,0,0,0,0,0,0,0,0,0,0,0,0,0,0,0,0,0,0,0,0,0,0,0,0,0,0,0,0,0~
,0,0,0,0,0,0,0,AF12,0,0,0)';
      PINUSE='POWER';
      NO_LOAD_CHECK='Both';
      NO_IO_CHECK='Both';
      NO_ASSERT_CHECK='TRUE';
      NO_DIR_CHECK='TRUE';
      ALLOW_CONNECT='TRUE';
    'VSS125':
      PIN_NUMBER='(0,0,0,0,0,0,0,0,0,0,0,0,0,0,0,0,0,0,0,0,0,0,0,0,0,0,0,0,0,0,0~
,0,0,0,0,0,0,0,AE88,0,0,0)';
      PINUSE='POWER';
      NO_LOAD_CHECK='Both';
      NO_IO_CHECK='Both';
      NO_ASSERT_CHECK='TRUE';
      NO_DIR_CHECK='TRUE';
      ALLOW_CONNECT='TRUE';
    'VSS124':
      PIN_NUMBER='(0,0,0,0,0,0,0,0,0,0,0,0,0,0,0,0,0,0,0,0,0,0,0,0,0,0,0,0,0,0,0~
,0,0,0,0,0,0,0,AE84,0,0,0)';
      PINUSE='POWER';
      NO_LOAD_CHECK='Both';
      NO_IO_CHECK='Both';
      NO_ASSERT_CHECK='TRUE';
      NO_DIR_CHECK='TRUE';
      ALLOW_CONNECT='TRUE';
    'VSS123':
      PIN_NUMBER='(0,0,0,0,0,0,0,0,0,0,0,0,0,0,0,0,0,0,0,0,0,0,0,0,0,0,0,0,0,0,0~
,0,0,0,0,0,0,0,AE78,0,0,0)';
      PINUSE='POWER';
      NO_LOAD_CHECK='Both';
      NO_IO_CHECK='Both';
      NO_ASSERT_CHECK='TRUE';
      NO_DIR_CHECK='TRUE';
      ALLOW_CONNECT='TRUE';
    'VSS122':
      PIN_NUMBER='(0,0,0,0,0,0,0,0,0,0,0,0,0,0,0,0,0,0,0,0,0,0,0,0,0,0,0,0,0,0,0~
,0,0,0,0,0,0,0,AE76,0,0,0)';
      PINUSE='POWER';
      NO_LOAD_CHECK='Both';
      NO_IO_CHECK='Both';
      NO_ASSERT_CHECK='TRUE';
      NO_DIR_CHECK='TRUE';
      ALLOW_CONNECT='TRUE';
    'VSS121':
      PIN_NUMBER='(0,0,0,0,0,0,0,0,0,0,0,0,0,0,0,0,0,0,0,0,0,0,0,0,0,0,0,0,0,0,0~
,0,0,0,0,0,0,0,AE74,0,0,0)';
      PINUSE='POWER';
      NO_LOAD_CHECK='Both';
      NO_IO_CHECK='Both';
      NO_ASSERT_CHECK='TRUE';
      NO_DIR_CHECK='TRUE';
      ALLOW_CONNECT='TRUE';
    'VSS120':
      PIN_NUMBER='(0,0,0,0,0,0,0,0,0,0,0,0,0,0,0,0,0,0,0,0,0,0,0,0,0,0,0,0,0,0,0~
,0,0,0,0,0,0,0,AE72,0,0,0)';
      PINUSE='POWER';
      NO_LOAD_CHECK='Both';
      NO_IO_CHECK='Both';
      NO_ASSERT_CHECK='TRUE';
      NO_DIR_CHECK='TRUE';
      ALLOW_CONNECT='TRUE';
    'VSS119':
      PIN_NUMBER='(0,0,0,0,0,0,0,0,0,0,0,0,0,0,0,0,0,0,0,0,0,0,0,0,0,0,0,0,0,0,0~
,0,0,0,0,0,0,0,AE70,0,0,0)';
      PINUSE='POWER';
      NO_LOAD_CHECK='Both';
      NO_IO_CHECK='Both';
      NO_ASSERT_CHECK='TRUE';
      NO_DIR_CHECK='TRUE';
      ALLOW_CONNECT='TRUE';
    'VSS118':
      PIN_NUMBER='(0,0,0,0,0,0,0,0,0,0,0,0,0,0,0,0,0,0,0,0,0,0,0,0,0,0,0,0,0,0,0~
,0,0,0,0,0,0,0,AE68,0,0,0)';
      PINUSE='POWER';
      NO_LOAD_CHECK='Both';
      NO_IO_CHECK='Both';
      NO_ASSERT_CHECK='TRUE';
      NO_DIR_CHECK='TRUE';
      ALLOW_CONNECT='TRUE';
    'VSS117':
      PIN_NUMBER='(0,0,0,0,0,0,0,0,0,0,0,0,0,0,0,0,0,0,0,0,0,0,0,0,0,0,0,0,0,0,0~
,0,0,0,0,0,0,0,AE66,0,0,0)';
      PINUSE='POWER';
      NO_LOAD_CHECK='Both';
      NO_IO_CHECK='Both';
      NO_ASSERT_CHECK='TRUE';
      NO_DIR_CHECK='TRUE';
      ALLOW_CONNECT='TRUE';
    'VSS116':
      PIN_NUMBER='(0,0,0,0,0,0,0,0,0,0,0,0,0,0,0,0,0,0,0,0,0,0,0,0,0,0,0,0,0,0,0~
,0,0,0,0,0,0,0,AE64,0,0,0)';
      PINUSE='POWER';
      NO_LOAD_CHECK='Both';
      NO_IO_CHECK='Both';
      NO_ASSERT_CHECK='TRUE';
      NO_DIR_CHECK='TRUE';
      ALLOW_CONNECT='TRUE';
    'VSS115':
      PIN_NUMBER='(0,0,0,0,0,0,0,0,0,0,0,0,0,0,0,0,0,0,0,0,0,0,0,0,0,0,0,0,0,0,0~
,0,0,0,0,0,0,0,AE62,0,0,0)';
      PINUSE='POWER';
      NO_LOAD_CHECK='Both';
      NO_IO_CHECK='Both';
      NO_ASSERT_CHECK='TRUE';
      NO_DIR_CHECK='TRUE';
      ALLOW_CONNECT='TRUE';
    'VSS114':
      PIN_NUMBER='(0,0,0,0,0,0,0,0,0,0,0,0,0,0,0,0,0,0,0,0,0,0,0,0,0,0,0,0,0,0,0~
,0,0,0,0,0,0,0,AE60,0,0,0)';
      PINUSE='POWER';
      NO_LOAD_CHECK='Both';
      NO_IO_CHECK='Both';
      NO_ASSERT_CHECK='TRUE';
      NO_DIR_CHECK='TRUE';
      ALLOW_CONNECT='TRUE';
    'VSS113':
      PIN_NUMBER='(0,0,0,0,0,0,0,0,0,0,0,0,0,0,0,0,0,0,0,0,0,0,0,0,0,0,0,0,0,0,0~
,0,0,0,0,0,0,0,AE58,0,0,0)';
      PINUSE='POWER';
      NO_LOAD_CHECK='Both';
      NO_IO_CHECK='Both';
      NO_ASSERT_CHECK='TRUE';
      NO_DIR_CHECK='TRUE';
      ALLOW_CONNECT='TRUE';
    'VSS112':
      PIN_NUMBER='(0,0,0,0,0,0,0,0,0,0,0,0,0,0,0,0,0,0,0,0,0,0,0,0,0,0,0,0,0,0,0~
,0,0,0,0,0,0,0,AE56,0,0,0)';
      PINUSE='POWER';
      NO_LOAD_CHECK='Both';
      NO_IO_CHECK='Both';
      NO_ASSERT_CHECK='TRUE';
      NO_DIR_CHECK='TRUE';
      ALLOW_CONNECT='TRUE';
    'VSS111':
      PIN_NUMBER='(0,0,0,0,0,0,0,0,0,0,0,0,0,0,0,0,0,0,0,0,0,0,0,0,0,0,0,0,0,0,0~
,0,0,0,0,0,0,0,AE54,0,0,0)';
      PINUSE='POWER';
      NO_LOAD_CHECK='Both';
      NO_IO_CHECK='Both';
      NO_ASSERT_CHECK='TRUE';
      NO_DIR_CHECK='TRUE';
      ALLOW_CONNECT='TRUE';
    'VSS110':
      PIN_NUMBER='(0,0,0,0,0,0,0,0,0,0,0,0,0,0,0,0,0,0,0,0,0,0,0,0,0,0,0,0,0,0,0~
,0,0,0,0,0,0,0,AE52,0,0,0)';
      PINUSE='POWER';
      NO_LOAD_CHECK='Both';
      NO_IO_CHECK='Both';
      NO_ASSERT_CHECK='TRUE';
      NO_DIR_CHECK='TRUE';
      ALLOW_CONNECT='TRUE';
    'VSS109':
      PIN_NUMBER='(0,0,0,0,0,0,0,0,0,0,0,0,0,0,0,0,0,0,0,0,0,0,0,0,0,0,0,0,0,0,0~
,0,0,0,0,0,0,0,AE50,0,0,0)';
      PINUSE='POWER';
      NO_LOAD_CHECK='Both';
      NO_IO_CHECK='Both';
      NO_ASSERT_CHECK='TRUE';
      NO_DIR_CHECK='TRUE';
      ALLOW_CONNECT='TRUE';
    'VSS108':
      PIN_NUMBER='(0,0,0,0,0,0,0,0,0,0,0,0,0,0,0,0,0,0,0,0,0,0,0,0,0,0,0,0,0,0,0~
,0,0,0,0,0,0,0,AE48,0,0,0)';
      PINUSE='POWER';
      NO_LOAD_CHECK='Both';
      NO_IO_CHECK='Both';
      NO_ASSERT_CHECK='TRUE';
      NO_DIR_CHECK='TRUE';
      ALLOW_CONNECT='TRUE';
    'VSS107':
      PIN_NUMBER='(0,0,0,0,0,0,0,0,0,0,0,0,0,0,0,0,0,0,0,0,0,0,0,0,0,0,0,0,0,0,0~
,0,0,0,0,0,0,0,AE45,0,0,0)';
      PINUSE='POWER';
      NO_LOAD_CHECK='Both';
      NO_IO_CHECK='Both';
      NO_ASSERT_CHECK='TRUE';
      NO_DIR_CHECK='TRUE';
      ALLOW_CONNECT='TRUE';
    'VSS106':
      PIN_NUMBER='(0,0,0,0,0,0,0,0,0,0,0,0,0,0,0,0,0,0,0,0,0,0,0,0,0,0,0,0,0,0,0~
,0,0,0,0,0,0,0,AE43,0,0,0)';
      PINUSE='POWER';
      NO_LOAD_CHECK='Both';
      NO_IO_CHECK='Both';
      NO_ASSERT_CHECK='TRUE';
      NO_DIR_CHECK='TRUE';
      ALLOW_CONNECT='TRUE';
    'VSS105':
      PIN_NUMBER='(0,0,0,0,0,0,0,0,0,0,0,0,0,0,0,0,0,0,0,0,0,0,0,0,0,0,0,0,0,0,0~
,0,0,0,0,0,0,0,AE41,0,0,0)';
      PINUSE='POWER';
      NO_LOAD_CHECK='Both';
      NO_IO_CHECK='Both';
      NO_ASSERT_CHECK='TRUE';
      NO_DIR_CHECK='TRUE';
      ALLOW_CONNECT='TRUE';
    'VSS104':
      PIN_NUMBER='(0,0,0,0,0,0,0,0,0,0,0,0,0,0,0,0,0,0,0,0,0,0,0,0,0,0,0,0,0,0,0~
,0,0,0,0,0,0,0,AE39,0,0,0)';
      PINUSE='POWER';
      NO_LOAD_CHECK='Both';
      NO_IO_CHECK='Both';
      NO_ASSERT_CHECK='TRUE';
      NO_DIR_CHECK='TRUE';
      ALLOW_CONNECT='TRUE';
    'VSS103':
      PIN_NUMBER='(0,0,0,0,0,0,0,0,0,0,0,0,0,0,0,0,0,0,0,0,0,0,0,0,0,0,0,0,0,0,0~
,0,0,0,0,0,0,0,AE37,0,0,0)';
      PINUSE='POWER';
      NO_LOAD_CHECK='Both';
      NO_IO_CHECK='Both';
      NO_ASSERT_CHECK='TRUE';
      NO_DIR_CHECK='TRUE';
      ALLOW_CONNECT='TRUE';
    'VSS102':
      PIN_NUMBER='(0,0,0,0,0,0,0,0,0,0,0,0,0,0,0,0,0,0,0,0,0,0,0,0,0,0,0,0,0,0,0~
,0,0,0,0,0,0,0,AE35,0,0,0)';
      PINUSE='POWER';
      NO_LOAD_CHECK='Both';
      NO_IO_CHECK='Both';
      NO_ASSERT_CHECK='TRUE';
      NO_DIR_CHECK='TRUE';
      ALLOW_CONNECT='TRUE';
    'VSS101':
      PIN_NUMBER='(0,0,0,0,0,0,0,0,0,0,0,0,0,0,0,0,0,0,0,0,0,0,0,0,0,0,0,0,0,0,0~
,0,0,0,0,0,0,0,AE33,0,0,0)';
      PINUSE='POWER';
      NO_LOAD_CHECK='Both';
      NO_IO_CHECK='Both';
      NO_ASSERT_CHECK='TRUE';
      NO_DIR_CHECK='TRUE';
      ALLOW_CONNECT='TRUE';
    'VSS100':
      PIN_NUMBER='(0,0,0,0,0,0,0,0,0,0,0,0,0,0,0,0,0,0,0,0,0,0,0,0,0,0,0,0,0,0,0~
,0,0,0,0,0,0,0,AE31,0,0,0)';
      PINUSE='POWER';
      NO_LOAD_CHECK='Both';
      NO_IO_CHECK='Both';
      NO_ASSERT_CHECK='TRUE';
      NO_DIR_CHECK='TRUE';
      ALLOW_CONNECT='TRUE';
    'VSS99':
      PIN_NUMBER='(0,0,0,0,0,0,0,0,0,0,0,0,0,0,0,0,0,0,0,0,0,0,0,0,0,0,0,0,0,0,0~
,0,0,0,0,0,0,0,AE29,0,0,0)';
      PINUSE='POWER';
      NO_LOAD_CHECK='Both';
      NO_IO_CHECK='Both';
      NO_ASSERT_CHECK='TRUE';
      NO_DIR_CHECK='TRUE';
      ALLOW_CONNECT='TRUE';
    'VSS98':
      PIN_NUMBER='(0,0,0,0,0,0,0,0,0,0,0,0,0,0,0,0,0,0,0,0,0,0,0,0,0,0,0,0,0,0,0~
,0,0,0,0,0,0,0,AE27,0,0,0)';
      PINUSE='POWER';
      NO_LOAD_CHECK='Both';
      NO_IO_CHECK='Both';
      NO_ASSERT_CHECK='TRUE';
      NO_DIR_CHECK='TRUE';
      ALLOW_CONNECT='TRUE';
    'VSS97':
      PIN_NUMBER='(0,0,0,0,0,0,0,0,0,0,0,0,0,0,0,0,0,0,0,0,0,0,0,0,0,0,0,0,0,0,0~
,0,0,0,0,0,0,0,AE25,0,0,0)';
      PINUSE='POWER';
      NO_LOAD_CHECK='Both';
      NO_IO_CHECK='Both';
      NO_ASSERT_CHECK='TRUE';
      NO_DIR_CHECK='TRUE';
      ALLOW_CONNECT='TRUE';
    'VSS96':
      PIN_NUMBER='(0,0,0,0,0,0,0,0,0,0,0,0,0,0,0,0,0,0,0,0,0,0,0,0,0,0,0,0,0,0,0~
,0,0,0,0,0,0,0,AE23,0,0,0)';
      PINUSE='POWER';
      NO_LOAD_CHECK='Both';
      NO_IO_CHECK='Both';
      NO_ASSERT_CHECK='TRUE';
      NO_DIR_CHECK='TRUE';
      ALLOW_CONNECT='TRUE';
    'VSS95':
      PIN_NUMBER='(0,0,0,0,0,0,0,0,0,0,0,0,0,0,0,0,0,0,0,0,0,0,0,0,0,0,0,0,0,0,0~
,0,0,0,0,0,0,0,AE21,0,0,0)';
      PINUSE='POWER';
      NO_LOAD_CHECK='Both';
      NO_IO_CHECK='Both';
      NO_ASSERT_CHECK='TRUE';
      NO_DIR_CHECK='TRUE';
      ALLOW_CONNECT='TRUE';
    'VSS94':
      PIN_NUMBER='(0,0,0,0,0,0,0,0,0,0,0,0,0,0,0,0,0,0,0,0,0,0,0,0,0,0,0,0,0,0,0~
,0,0,0,0,0,0,0,AE19,0,0,0)';
      PINUSE='POWER';
      NO_LOAD_CHECK='Both';
      NO_IO_CHECK='Both';
      NO_ASSERT_CHECK='TRUE';
      NO_DIR_CHECK='TRUE';
      ALLOW_CONNECT='TRUE';
    'VSS93':
      PIN_NUMBER='(0,0,0,0,0,0,0,0,0,0,0,0,0,0,0,0,0,0,0,0,0,0,0,0,0,0,0,0,0,0,0~
,0,0,0,0,0,0,0,AE17,0,0,0)';
      PINUSE='POWER';
      NO_LOAD_CHECK='Both';
      NO_IO_CHECK='Both';
      NO_ASSERT_CHECK='TRUE';
      NO_DIR_CHECK='TRUE';
      ALLOW_CONNECT='TRUE';
    'VSS92':
      PIN_NUMBER='(0,0,0,0,0,0,0,0,0,0,0,0,0,0,0,0,0,0,0,0,0,0,0,0,0,0,0,0,0,0,0~
,0,0,0,0,0,0,0,AD83,0,0,0)';
      PINUSE='POWER';
      NO_LOAD_CHECK='Both';
      NO_IO_CHECK='Both';
      NO_ASSERT_CHECK='TRUE';
      NO_DIR_CHECK='TRUE';
      ALLOW_CONNECT='TRUE';
    'VSS91':
      PIN_NUMBER='(0,0,0,0,0,0,0,0,0,0,0,0,0,0,0,0,0,0,0,0,0,0,0,0,0,0,0,0,0,0,0~
,0,0,0,0,0,0,0,AD8,0,0,0)';
      PINUSE='POWER';
      NO_LOAD_CHECK='Both';
      NO_IO_CHECK='Both';
      NO_ASSERT_CHECK='TRUE';
      NO_DIR_CHECK='TRUE';
      ALLOW_CONNECT='TRUE';
    'VSS90':
      PIN_NUMBER='(0,0,0,0,0,0,0,0,0,0,0,0,0,0,0,0,0,0,0,0,0,0,0,0,0,0,0,0,0,0,0~
,0,0,0,0,0,0,0,AD79,0,0,0)';
      PINUSE='POWER';
      NO_LOAD_CHECK='Both';
      NO_IO_CHECK='Both';
      NO_ASSERT_CHECK='TRUE';
      NO_DIR_CHECK='TRUE';
      ALLOW_CONNECT='TRUE';
    'VSS89':
      PIN_NUMBER='(0,0,0,0,0,0,0,0,0,0,0,0,0,0,0,0,0,0,0,0,0,0,0,0,0,0,0,0,0,0,0~
,0,0,0,0,0,0,0,AD42,0,0,0)';
      PINUSE='POWER';
      NO_LOAD_CHECK='Both';
      NO_IO_CHECK='Both';
      NO_ASSERT_CHECK='TRUE';
      NO_DIR_CHECK='TRUE';
      ALLOW_CONNECT='TRUE';
    'VSS88':
      PIN_NUMBER='(0,0,0,0,0,0,0,0,0,0,0,0,0,0,0,0,0,0,0,0,0,0,0,0,0,0,0,0,0,0,0~
,0,0,0,0,0,0,0,AD4,0,0,0)';
      PINUSE='POWER';
      NO_LOAD_CHECK='Both';
      NO_IO_CHECK='Both';
      NO_ASSERT_CHECK='TRUE';
      NO_DIR_CHECK='TRUE';
      ALLOW_CONNECT='TRUE';
    'VSS87':
      PIN_NUMBER='(0,0,0,0,0,0,0,0,0,0,0,0,0,0,0,0,0,0,0,0,0,0,0,0,0,0,0,0,0,0,0~
,0,0,0,0,0,0,0,AD16,0,0,0)';
      PINUSE='POWER';
      NO_LOAD_CHECK='Both';
      NO_IO_CHECK='Both';
      NO_ASSERT_CHECK='TRUE';
      NO_DIR_CHECK='TRUE';
      ALLOW_CONNECT='TRUE';
    'VSS86':
      PIN_NUMBER='(0,0,0,0,0,0,0,0,0,0,0,0,0,0,0,0,0,0,0,0,0,0,0,0,0,0,0,0,0,0,0~
,0,0,0,0,0,0,0,AD12,0,0,0)';
      PINUSE='POWER';
      NO_LOAD_CHECK='Both';
      NO_IO_CHECK='Both';
      NO_ASSERT_CHECK='TRUE';
      NO_DIR_CHECK='TRUE';
      ALLOW_CONNECT='TRUE';
    'VSS85':
      PIN_NUMBER='(0,0,0,0,0,0,0,0,0,0,0,0,0,0,0,0,0,0,0,0,0,0,0,0,0,0,0,0,0,0,0~
,0,0,0,0,0,0,0,AC9,0,0,0)';
      PINUSE='POWER';
      NO_LOAD_CHECK='Both';
      NO_IO_CHECK='Both';
      NO_ASSERT_CHECK='TRUE';
      NO_DIR_CHECK='TRUE';
      ALLOW_CONNECT='TRUE';
    'VSS84':
      PIN_NUMBER='(0,0,0,0,0,0,0,0,0,0,0,0,0,0,0,0,0,0,0,0,0,0,0,0,0,0,0,0,0,0,0~
,0,0,0,0,0,0,0,AC88,0,0,0)';
      PINUSE='POWER';
      NO_LOAD_CHECK='Both';
      NO_IO_CHECK='Both';
      NO_ASSERT_CHECK='TRUE';
      NO_DIR_CHECK='TRUE';
      ALLOW_CONNECT='TRUE';
    'VSS83':
      PIN_NUMBER='(0,0,0,0,0,0,0,0,0,0,0,0,0,0,0,0,0,0,0,0,0,0,0,0,0,0,0,0,0,0,0~
,0,0,0,0,0,0,0,AC84,0,0,0)';
      PINUSE='POWER';
      NO_LOAD_CHECK='Both';
      NO_IO_CHECK='Both';
      NO_ASSERT_CHECK='TRUE';
      NO_DIR_CHECK='TRUE';
      ALLOW_CONNECT='TRUE';
    'VSS82':
      PIN_NUMBER='(0,0,0,0,0,0,0,0,0,0,0,0,0,0,0,0,0,0,0,0,0,0,0,0,0,0,0,0,0,0,0~
,0,0,0,0,0,0,0,AC76,0,0,0)';
      PINUSE='POWER';
      NO_LOAD_CHECK='Both';
      NO_IO_CHECK='Both';
      NO_ASSERT_CHECK='TRUE';
      NO_DIR_CHECK='TRUE';
      ALLOW_CONNECT='TRUE';
    'VSS81':
      PIN_NUMBER='(0,0,0,0,0,0,0,0,0,0,0,0,0,0,0,0,0,0,0,0,0,0,0,0,0,0,0,0,0,0,0~
,0,0,0,0,0,0,0,AC70,0,0,0)';
      PINUSE='POWER';
      NO_LOAD_CHECK='Both';
      NO_IO_CHECK='Both';
      NO_ASSERT_CHECK='TRUE';
      NO_DIR_CHECK='TRUE';
      ALLOW_CONNECT='TRUE';
    'VSS80':
      PIN_NUMBER='(0,0,0,0,0,0,0,0,0,0,0,0,0,0,0,0,0,0,0,0,0,0,0,0,0,0,0,0,0,0,0~
,0,0,0,0,0,0,0,AC64,0,0,0)';
      PINUSE='POWER';
      NO_LOAD_CHECK='Both';
      NO_IO_CHECK='Both';
      NO_ASSERT_CHECK='TRUE';
      NO_DIR_CHECK='TRUE';
      ALLOW_CONNECT='TRUE';
    'VSS79':
      PIN_NUMBER='(0,0,0,0,0,0,0,0,0,0,0,0,0,0,0,0,0,0,0,0,0,0,0,0,0,0,0,0,0,0,0~
,0,0,0,0,0,0,0,AC58,0,0,0)';
      PINUSE='POWER';
      NO_LOAD_CHECK='Both';
      NO_IO_CHECK='Both';
      NO_ASSERT_CHECK='TRUE';
      NO_DIR_CHECK='TRUE';
      ALLOW_CONNECT='TRUE';
    'VSS78':
      PIN_NUMBER='(0,0,0,0,0,0,0,0,0,0,0,0,0,0,0,0,0,0,0,0,0,0,0,0,0,0,0,0,0,0,0~
,0,0,0,0,0,0,0,AC52,0,0,0)';
      PINUSE='POWER';
      NO_LOAD_CHECK='Both';
      NO_IO_CHECK='Both';
      NO_ASSERT_CHECK='TRUE';
      NO_DIR_CHECK='TRUE';
      ALLOW_CONNECT='TRUE';
    'VSS77':
      PIN_NUMBER='(0,0,0,0,0,0,0,0,0,0,0,0,0,0,0,0,0,0,0,0,0,0,0,0,0,0,0,0,0,0,0~
,0,0,0,0,0,0,0,AC5,0,0,0)';
      PINUSE='POWER';
      NO_LOAD_CHECK='Both';
      NO_IO_CHECK='Both';
      NO_ASSERT_CHECK='TRUE';
      NO_DIR_CHECK='TRUE';
      ALLOW_CONNECT='TRUE';
    'VSS76':
      PIN_NUMBER='(0,0,0,0,0,0,0,0,0,0,0,0,0,0,0,0,0,0,0,0,0,0,0,0,0,0,0,0,0,0,0~
,0,0,0,0,0,0,0,AC45,0,0,0)';
      PINUSE='POWER';
      NO_LOAD_CHECK='Both';
      NO_IO_CHECK='Both';
      NO_ASSERT_CHECK='TRUE';
      NO_DIR_CHECK='TRUE';
      ALLOW_CONNECT='TRUE';
    'VSS75':
      PIN_NUMBER='(0,0,0,0,0,0,0,0,0,0,0,0,0,0,0,0,0,0,0,0,0,0,0,0,0,0,0,0,0,0,0~
,0,0,0,0,0,0,0,AC39,0,0,0)';
      PINUSE='POWER';
      NO_LOAD_CHECK='Both';
      NO_IO_CHECK='Both';
      NO_ASSERT_CHECK='TRUE';
      NO_DIR_CHECK='TRUE';
      ALLOW_CONNECT='TRUE';
    'VSS74':
      PIN_NUMBER='(0,0,0,0,0,0,0,0,0,0,0,0,0,0,0,0,0,0,0,0,0,0,0,0,0,0,0,0,0,0,0~
,0,0,0,0,0,0,0,AC33,0,0,0)';
      PINUSE='POWER';
      NO_LOAD_CHECK='Both';
      NO_IO_CHECK='Both';
      NO_ASSERT_CHECK='TRUE';
      NO_DIR_CHECK='TRUE';
      ALLOW_CONNECT='TRUE';
    'VSS73':
      PIN_NUMBER='(0,0,0,0,0,0,0,0,0,0,0,0,0,0,0,0,0,0,0,0,0,0,0,0,0,0,0,0,0,0,0~
,0,0,0,0,0,0,0,AC27,0,0,0)';
      PINUSE='POWER';
      NO_LOAD_CHECK='Both';
      NO_IO_CHECK='Both';
      NO_ASSERT_CHECK='TRUE';
      NO_DIR_CHECK='TRUE';
      ALLOW_CONNECT='TRUE';
    'VSS72':
      PIN_NUMBER='(0,0,0,0,0,0,0,0,0,0,0,0,0,0,0,0,0,0,0,0,0,0,0,0,0,0,0,0,0,0,0~
,0,0,0,0,0,0,0,AC21,0,0,0)';
      PINUSE='POWER';
      NO_LOAD_CHECK='Both';
      NO_IO_CHECK='Both';
      NO_ASSERT_CHECK='TRUE';
      NO_DIR_CHECK='TRUE';
      ALLOW_CONNECT='TRUE';
    'VSS71':
      PIN_NUMBER='(0,0,0,0,0,0,0,0,0,0,0,0,0,0,0,0,0,0,0,0,0,0,0,0,0,0,0,0,0,0,0~
,0,0,0,0,0,0,0,AC13,0,0,0)';
      PINUSE='POWER';
      NO_LOAD_CHECK='Both';
      NO_IO_CHECK='Both';
      NO_ASSERT_CHECK='TRUE';
      NO_DIR_CHECK='TRUE';
      ALLOW_CONNECT='TRUE';
    'VSS70':
      PIN_NUMBER='(0,0,0,0,0,0,0,0,0,0,0,0,0,0,0,0,0,0,0,0,0,0,0,0,0,0,0,0,0,0,0~
,0,0,0,0,0,0,0,AC1,0,0,0)';
      PINUSE='POWER';
      NO_LOAD_CHECK='Both';
      NO_IO_CHECK='Both';
      NO_ASSERT_CHECK='TRUE';
      NO_DIR_CHECK='TRUE';
      ALLOW_CONNECT='TRUE';
    'VSS69':
      PIN_NUMBER='(0,0,0,0,0,0,0,0,0,0,0,0,0,0,0,0,0,0,0,0,0,0,0,0,0,0,0,0,0,0,0~
,0,0,0,0,0,0,0,AB91,0,0,0)';
      PINUSE='POWER';
      NO_LOAD_CHECK='Both';
      NO_IO_CHECK='Both';
      NO_ASSERT_CHECK='TRUE';
      NO_DIR_CHECK='TRUE';
      ALLOW_CONNECT='TRUE';
    'VSS68':
      PIN_NUMBER='(0,0,0,0,0,0,0,0,0,0,0,0,0,0,0,0,0,0,0,0,0,0,0,0,0,0,0,0,0,0,0~
,0,0,0,0,0,0,0,AB87,0,0,0)';
      PINUSE='POWER';
      NO_LOAD_CHECK='Both';
      NO_IO_CHECK='Both';
      NO_ASSERT_CHECK='TRUE';
      NO_DIR_CHECK='TRUE';
      ALLOW_CONNECT='TRUE';
    'VSS67':
      PIN_NUMBER='(0,0,0,0,0,0,0,0,0,0,0,0,0,0,0,0,0,0,0,0,0,0,0,0,0,0,0,0,0,0,0~
,0,0,0,0,0,0,0,AB83,0,0,0)';
      PINUSE='POWER';
      NO_LOAD_CHECK='Both';
      NO_IO_CHECK='Both';
      NO_ASSERT_CHECK='TRUE';
      NO_DIR_CHECK='TRUE';
      ALLOW_CONNECT='TRUE';
    'VSS66':
      PIN_NUMBER='(0,0,0,0,0,0,0,0,0,0,0,0,0,0,0,0,0,0,0,0,0,0,0,0,0,0,0,0,0,0,0~
,0,0,0,0,0,0,0,AB81,0,0,0)';
      PINUSE='POWER';
      NO_LOAD_CHECK='Both';
      NO_IO_CHECK='Both';
      NO_ASSERT_CHECK='TRUE';
      NO_DIR_CHECK='TRUE';
      ALLOW_CONNECT='TRUE';
    'VSS65':
      PIN_NUMBER='(0,0,0,0,0,0,0,0,0,0,0,0,0,0,0,0,0,0,0,0,0,0,0,0,0,0,0,0,0,0,0~
,0,0,0,0,0,0,0,AB8,0,0,0)';
      PINUSE='POWER';
      NO_LOAD_CHECK='Both';
      NO_IO_CHECK='Both';
      NO_ASSERT_CHECK='TRUE';
      NO_DIR_CHECK='TRUE';
      ALLOW_CONNECT='TRUE';
    'VSS64':
      PIN_NUMBER='(0,0,0,0,0,0,0,0,0,0,0,0,0,0,0,0,0,0,0,0,0,0,0,0,0,0,0,0,0,0,0~
,0,0,0,0,0,0,0,AB79,0,0,0)';
      PINUSE='POWER';
      NO_LOAD_CHECK='Both';
      NO_IO_CHECK='Both';
      NO_ASSERT_CHECK='TRUE';
      NO_DIR_CHECK='TRUE';
      ALLOW_CONNECT='TRUE';
    'VSS63':
      PIN_NUMBER='(0,0,0,0,0,0,0,0,0,0,0,0,0,0,0,0,0,0,0,0,0,0,0,0,0,0,0,0,0,0,0~
,0,0,0,0,0,0,0,AB77,0,0,0)';
      PINUSE='POWER';
      NO_LOAD_CHECK='Both';
      NO_IO_CHECK='Both';
      NO_ASSERT_CHECK='TRUE';
      NO_DIR_CHECK='TRUE';
      ALLOW_CONNECT='TRUE';
    'VSS62':
      PIN_NUMBER='(0,0,0,0,0,0,0,0,0,0,0,0,0,0,0,0,0,0,0,0,0,0,0,0,0,0,0,0,0,0,0~
,0,0,0,0,0,0,0,AB75,0,0,0)';
      PINUSE='POWER';
      NO_LOAD_CHECK='Both';
      NO_IO_CHECK='Both';
      NO_ASSERT_CHECK='TRUE';
      NO_DIR_CHECK='TRUE';
      ALLOW_CONNECT='TRUE';
    'VSS61':
      PIN_NUMBER='(0,0,0,0,0,0,0,0,0,0,0,0,0,0,0,0,0,0,0,0,0,0,0,0,0,0,0,0,0,0,0~
,0,0,0,0,0,0,0,AB71,0,0,0)';
      PINUSE='POWER';
      NO_LOAD_CHECK='Both';
      NO_IO_CHECK='Both';
      NO_ASSERT_CHECK='TRUE';
      NO_DIR_CHECK='TRUE';
      ALLOW_CONNECT='TRUE';
    'VSS60':
      PIN_NUMBER='(0,0,0,0,0,0,0,0,0,0,0,0,0,0,0,0,0,0,0,0,0,0,0,0,0,0,0,0,0,0,0~
,0,0,0,0,0,0,0,AB69,0,0,0)';
      PINUSE='POWER';
      NO_LOAD_CHECK='Both';
      NO_IO_CHECK='Both';
      NO_ASSERT_CHECK='TRUE';
      NO_DIR_CHECK='TRUE';
      ALLOW_CONNECT='TRUE';
    'VSS59':
      PIN_NUMBER='(0,0,0,0,0,0,0,0,0,0,0,0,0,0,0,0,0,0,0,0,0,0,0,0,0,0,0,0,0,0,0~
,0,0,0,0,0,0,0,AB65,0,0,0)';
      PINUSE='POWER';
      NO_LOAD_CHECK='Both';
      NO_IO_CHECK='Both';
      NO_ASSERT_CHECK='TRUE';
      NO_DIR_CHECK='TRUE';
      ALLOW_CONNECT='TRUE';
    'VSS58':
      PIN_NUMBER='(0,0,0,0,0,0,0,0,0,0,0,0,0,0,0,0,0,0,0,0,0,0,0,0,0,0,0,0,0,0,0~
,0,0,0,0,0,0,0,AB63,0,0,0)';
      PINUSE='POWER';
      NO_LOAD_CHECK='Both';
      NO_IO_CHECK='Both';
      NO_ASSERT_CHECK='TRUE';
      NO_DIR_CHECK='TRUE';
      ALLOW_CONNECT='TRUE';
    'VSS57':
      PIN_NUMBER='(0,0,0,0,0,0,0,0,0,0,0,0,0,0,0,0,0,0,0,0,0,0,0,0,0,0,0,0,0,0,0~
,0,0,0,0,0,0,0,AB59,0,0,0)';
      PINUSE='POWER';
      NO_LOAD_CHECK='Both';
      NO_IO_CHECK='Both';
      NO_ASSERT_CHECK='TRUE';
      NO_DIR_CHECK='TRUE';
      ALLOW_CONNECT='TRUE';
    'VSS56':
      PIN_NUMBER='(0,0,0,0,0,0,0,0,0,0,0,0,0,0,0,0,0,0,0,0,0,0,0,0,0,0,0,0,0,0,0~
,0,0,0,0,0,0,0,AB57,0,0,0)';
      PINUSE='POWER';
      NO_LOAD_CHECK='Both';
      NO_IO_CHECK='Both';
      NO_ASSERT_CHECK='TRUE';
      NO_DIR_CHECK='TRUE';
      ALLOW_CONNECT='TRUE';
    'VSS55':
      PIN_NUMBER='(0,0,0,0,0,0,0,0,0,0,0,0,0,0,0,0,0,0,0,0,0,0,0,0,0,0,0,0,0,0,0~
,0,0,0,0,0,0,0,AB53,0,0,0)';
      PINUSE='POWER';
      NO_LOAD_CHECK='Both';
      NO_IO_CHECK='Both';
      NO_ASSERT_CHECK='TRUE';
      NO_DIR_CHECK='TRUE';
      ALLOW_CONNECT='TRUE';
    'VSS54':
      PIN_NUMBER='(0,0,0,0,0,0,0,0,0,0,0,0,0,0,0,0,0,0,0,0,0,0,0,0,0,0,0,0,0,0,0~
,0,0,0,0,0,0,0,AB51,0,0,0)';
      PINUSE='POWER';
      NO_LOAD_CHECK='Both';
      NO_IO_CHECK='Both';
      NO_ASSERT_CHECK='TRUE';
      NO_DIR_CHECK='TRUE';
      ALLOW_CONNECT='TRUE';
    'VSS53':
      PIN_NUMBER='(0,0,0,0,0,0,0,0,0,0,0,0,0,0,0,0,0,0,0,0,0,0,0,0,0,0,0,0,0,0,0~
,0,0,0,0,0,0,0,AB47,0,0,0)';
      PINUSE='POWER';
      NO_LOAD_CHECK='Both';
      NO_IO_CHECK='Both';
      NO_ASSERT_CHECK='TRUE';
      NO_DIR_CHECK='TRUE';
      ALLOW_CONNECT='TRUE';
    'VSS52':
      PIN_NUMBER='(0,0,0,0,0,0,0,0,0,0,0,0,0,0,0,0,0,0,0,0,0,0,0,0,0,0,0,0,0,0,0~
,0,0,0,0,0,0,0,AB44,0,0,0)';
      PINUSE='POWER';
      NO_LOAD_CHECK='Both';
      NO_IO_CHECK='Both';
      NO_ASSERT_CHECK='TRUE';
      NO_DIR_CHECK='TRUE';
      ALLOW_CONNECT='TRUE';
    'VSS51':
      PIN_NUMBER='(0,0,0,0,0,0,0,0,0,0,0,0,0,0,0,0,0,0,0,0,0,0,0,0,0,0,0,0,0,0,0~
,0,0,0,0,0,0,0,AB40,0,0,0)';
      PINUSE='POWER';
      NO_LOAD_CHECK='Both';
      NO_IO_CHECK='Both';
      NO_ASSERT_CHECK='TRUE';
      NO_DIR_CHECK='TRUE';
      ALLOW_CONNECT='TRUE';
    'VSS50':
      PIN_NUMBER='(0,0,0,0,0,0,0,0,0,0,0,0,0,0,0,0,0,0,0,0,0,0,0,0,0,0,0,0,0,0,0~
,0,0,0,0,0,0,0,AB4,0,0,0)';
      PINUSE='POWER';
      NO_LOAD_CHECK='Both';
      NO_IO_CHECK='Both';
      NO_ASSERT_CHECK='TRUE';
      NO_DIR_CHECK='TRUE';
      ALLOW_CONNECT='TRUE';
    'VSS49':
      PIN_NUMBER='(0,0,0,0,0,0,0,0,0,0,0,0,0,0,0,0,0,0,0,0,0,0,0,0,0,0,0,0,0,0,0~
,0,0,0,0,0,0,0,AB38,0,0,0)';
      PINUSE='POWER';
      NO_LOAD_CHECK='Both';
      NO_IO_CHECK='Both';
      NO_ASSERT_CHECK='TRUE';
      NO_DIR_CHECK='TRUE';
      ALLOW_CONNECT='TRUE';
    'VSS48':
      PIN_NUMBER='(0,0,0,0,0,0,0,0,0,0,0,0,0,0,0,0,0,0,0,0,0,0,0,0,0,0,0,0,0,0,0~
,0,0,0,0,0,0,0,AB34,0,0,0)';
      PINUSE='POWER';
      NO_LOAD_CHECK='Both';
      NO_IO_CHECK='Both';
      NO_ASSERT_CHECK='TRUE';
      NO_DIR_CHECK='TRUE';
      ALLOW_CONNECT='TRUE';
    'VSS47':
      PIN_NUMBER='(0,0,0,0,0,0,0,0,0,0,0,0,0,0,0,0,0,0,0,0,0,0,0,0,0,0,0,0,0,0,0~
,0,0,0,0,0,0,0,AB32,0,0,0)';
      PINUSE='POWER';
      NO_LOAD_CHECK='Both';
      NO_IO_CHECK='Both';
      NO_ASSERT_CHECK='TRUE';
      NO_DIR_CHECK='TRUE';
      ALLOW_CONNECT='TRUE';
    'VSS46':
      PIN_NUMBER='(0,0,0,0,0,0,0,0,0,0,0,0,0,0,0,0,0,0,0,0,0,0,0,0,0,0,0,0,0,0,0~
,0,0,0,0,0,0,0,AB28,0,0,0)';
      PINUSE='POWER';
      NO_LOAD_CHECK='Both';
      NO_IO_CHECK='Both';
      NO_ASSERT_CHECK='TRUE';
      NO_DIR_CHECK='TRUE';
      ALLOW_CONNECT='TRUE';
    'VSS45':
      PIN_NUMBER='(0,0,0,0,0,0,0,0,0,0,0,0,0,0,0,0,0,0,0,0,0,0,0,0,0,0,0,0,0,0,0~
,0,0,0,0,0,0,0,AB26,0,0,0)';
      PINUSE='POWER';
      NO_LOAD_CHECK='Both';
      NO_IO_CHECK='Both';
      NO_ASSERT_CHECK='TRUE';
      NO_DIR_CHECK='TRUE';
      ALLOW_CONNECT='TRUE';
    'VSS44':
      PIN_NUMBER='(0,0,0,0,0,0,0,0,0,0,0,0,0,0,0,0,0,0,0,0,0,0,0,0,0,0,0,0,0,0,0~
,0,0,0,0,0,0,0,AB22,0,0,0)';
      PINUSE='POWER';
      NO_LOAD_CHECK='Both';
      NO_IO_CHECK='Both';
      NO_ASSERT_CHECK='TRUE';
      NO_DIR_CHECK='TRUE';
      ALLOW_CONNECT='TRUE';
    'VSS43':
      PIN_NUMBER='(0,0,0,0,0,0,0,0,0,0,0,0,0,0,0,0,0,0,0,0,0,0,0,0,0,0,0,0,0,0,0~
,0,0,0,0,0,0,0,AB20,0,0,0)';
      PINUSE='POWER';
      NO_LOAD_CHECK='Both';
      NO_IO_CHECK='Both';
      NO_ASSERT_CHECK='TRUE';
      NO_DIR_CHECK='TRUE';
      ALLOW_CONNECT='TRUE';
    'VSS42':
      PIN_NUMBER='(0,0,0,0,0,0,0,0,0,0,0,0,0,0,0,0,0,0,0,0,0,0,0,0,0,0,0,0,0,0,0~
,0,0,0,0,0,0,0,AB16,0,0,0)';
      PINUSE='POWER';
      NO_LOAD_CHECK='Both';
      NO_IO_CHECK='Both';
      NO_ASSERT_CHECK='TRUE';
      NO_DIR_CHECK='TRUE';
      ALLOW_CONNECT='TRUE';
    'VSS41':
      PIN_NUMBER='(0,0,0,0,0,0,0,0,0,0,0,0,0,0,0,0,0,0,0,0,0,0,0,0,0,0,0,0,0,0,0~
,0,0,0,0,0,0,0,AB12,0,0,0)';
      PINUSE='POWER';
      NO_LOAD_CHECK='Both';
      NO_IO_CHECK='Both';
      NO_ASSERT_CHECK='TRUE';
      NO_DIR_CHECK='TRUE';
      ALLOW_CONNECT='TRUE';
    'VSS40':
      PIN_NUMBER='(0,0,0,0,0,0,0,0,0,0,0,0,0,0,0,0,0,0,0,0,0,0,0,0,0,0,0,0,0,0,0~
,0,0,0,0,0,0,0,AA88,0,0,0)';
      PINUSE='POWER';
      NO_LOAD_CHECK='Both';
      NO_IO_CHECK='Both';
      NO_ASSERT_CHECK='TRUE';
      NO_DIR_CHECK='TRUE';
      ALLOW_CONNECT='TRUE';
    'VSS39':
      PIN_NUMBER='(0,0,0,0,0,0,0,0,0,0,0,0,0,0,0,0,0,0,0,0,0,0,0,0,0,0,0,0,0,0,0~
,0,0,0,0,0,0,0,AA84,0,0,0)';
      PINUSE='POWER';
      NO_LOAD_CHECK='Both';
      NO_IO_CHECK='Both';
      NO_ASSERT_CHECK='TRUE';
      NO_DIR_CHECK='TRUE';
      ALLOW_CONNECT='TRUE';
    'VSS38':
      PIN_NUMBER='(0,0,0,0,0,0,0,0,0,0,0,0,0,0,0,0,0,0,0,0,0,0,0,0,0,0,0,0,0,0,0~
,0,0,0,0,0,0,0,AA82,0,0,0)';
      PINUSE='POWER';
      NO_LOAD_CHECK='Both';
      NO_IO_CHECK='Both';
      NO_ASSERT_CHECK='TRUE';
      NO_DIR_CHECK='TRUE';
      ALLOW_CONNECT='TRUE';
    'VSS1833':
      PIN_NUMBER='(0,0,0,0,0,0,0,0,0,0,0,0,0,0,0,0,0,0,0,0,0,0,0,0,0,0,0,0,0,0,0~
,0,0,0,0,0,0,0,0,Y73,0,0)';
      PINUSE='POWER';
      NO_LOAD_CHECK='Both';
      NO_IO_CHECK='Both';
      NO_ASSERT_CHECK='TRUE';
      NO_DIR_CHECK='TRUE';
      ALLOW_CONNECT='TRUE';
    'VSS1832':
      PIN_NUMBER='(0,0,0,0,0,0,0,0,0,0,0,0,0,0,0,0,0,0,0,0,0,0,0,0,0,0,0,0,0,0,0~
,0,0,0,0,0,0,0,0,Y8,0,0)';
      PINUSE='POWER';
      NO_LOAD_CHECK='Both';
      NO_IO_CHECK='Both';
      NO_ASSERT_CHECK='TRUE';
      NO_DIR_CHECK='TRUE';
      ALLOW_CONNECT='TRUE';
    'VSS1831':
      PIN_NUMBER='(0,0,0,0,0,0,0,0,0,0,0,0,0,0,0,0,0,0,0,0,0,0,0,0,0,0,0,0,0,0,0~
,0,0,0,0,0,0,0,0,Y55,0,0)';
      PINUSE='POWER';
      NO_LOAD_CHECK='Both';
      NO_IO_CHECK='Both';
      NO_ASSERT_CHECK='TRUE';
      NO_DIR_CHECK='TRUE';
      ALLOW_CONNECT='TRUE';
    'VSS1830':
      PIN_NUMBER='(0,0,0,0,0,0,0,0,0,0,0,0,0,0,0,0,0,0,0,0,0,0,0,0,0,0,0,0,0,0,0~
,0,0,0,0,0,0,0,0,Y49,0,0)';
      PINUSE='POWER';
      NO_LOAD_CHECK='Both';
      NO_IO_CHECK='Both';
      NO_ASSERT_CHECK='TRUE';
      NO_DIR_CHECK='TRUE';
      ALLOW_CONNECT='TRUE';
    'VSS1829':
      PIN_NUMBER='(0,0,0,0,0,0,0,0,0,0,0,0,0,0,0,0,0,0,0,0,0,0,0,0,0,0,0,0,0,0,0~
,0,0,0,0,0,0,0,0,Y67,0,0)';
      PINUSE='POWER';
      NO_LOAD_CHECK='Both';
      NO_IO_CHECK='Both';
      NO_ASSERT_CHECK='TRUE';
      NO_DIR_CHECK='TRUE';
      ALLOW_CONNECT='TRUE';
    'VSS1828':
      PIN_NUMBER='(0,0,0,0,0,0,0,0,0,0,0,0,0,0,0,0,0,0,0,0,0,0,0,0,0,0,0,0,0,0,0~
,0,0,0,0,0,0,0,0,Y61,0,0)';
      PINUSE='POWER';
      NO_LOAD_CHECK='Both';
      NO_IO_CHECK='Both';
      NO_ASSERT_CHECK='TRUE';
      NO_DIR_CHECK='TRUE';
      ALLOW_CONNECT='TRUE';
    'VSS1827':
      PIN_NUMBER='(0,0,0,0,0,0,0,0,0,0,0,0,0,0,0,0,0,0,0,0,0,0,0,0,0,0,0,0,0,0,0~
,0,0,0,0,0,0,0,0,Y42,0,0)';
      PINUSE='POWER';
      NO_LOAD_CHECK='Both';
      NO_IO_CHECK='Both';
      NO_ASSERT_CHECK='TRUE';
      NO_DIR_CHECK='TRUE';
      ALLOW_CONNECT='TRUE';
    'VSS1826':
      PIN_NUMBER='(0,0,0,0,0,0,0,0,0,0,0,0,0,0,0,0,0,0,0,0,0,0,0,0,0,0,0,0,0,0,0~
,0,0,0,0,0,0,0,0,Y4,0,0)';
      PINUSE='POWER';
      NO_LOAD_CHECK='Both';
      NO_IO_CHECK='Both';
      NO_ASSERT_CHECK='TRUE';
      NO_DIR_CHECK='TRUE';
      ALLOW_CONNECT='TRUE';
    'VSS1825':
      PIN_NUMBER='(0,0,0,0,0,0,0,0,0,0,0,0,0,0,0,0,0,0,0,0,0,0,0,0,0,0,0,0,0,0,0~
,0,0,0,0,0,0,0,0,Y36,0,0)';
      PINUSE='POWER';
      NO_LOAD_CHECK='Both';
      NO_IO_CHECK='Both';
      NO_ASSERT_CHECK='TRUE';
      NO_DIR_CHECK='TRUE';
      ALLOW_CONNECT='TRUE';
    'VSS1824':
      PIN_NUMBER='(0,0,0,0,0,0,0,0,0,0,0,0,0,0,0,0,0,0,0,0,0,0,0,0,0,0,0,0,0,0,0~
,0,0,0,0,0,0,0,0,Y30,0,0)';
      PINUSE='POWER';
      NO_LOAD_CHECK='Both';
      NO_IO_CHECK='Both';
      NO_ASSERT_CHECK='TRUE';
      NO_DIR_CHECK='TRUE';
      ALLOW_CONNECT='TRUE';
    'VSS1823':
      PIN_NUMBER='(0,0,0,0,0,0,0,0,0,0,0,0,0,0,0,0,0,0,0,0,0,0,0,0,0,0,0,0,0,0,0~
,0,0,0,0,0,0,0,0,Y24,0,0)';
      PINUSE='POWER';
      NO_LOAD_CHECK='Both';
      NO_IO_CHECK='Both';
      NO_ASSERT_CHECK='TRUE';
      NO_DIR_CHECK='TRUE';
      ALLOW_CONNECT='TRUE';
    'VSS1822':
      PIN_NUMBER='(0,0,0,0,0,0,0,0,0,0,0,0,0,0,0,0,0,0,0,0,0,0,0,0,0,0,0,0,0,0,0~
,0,0,0,0,0,0,0,0,Y18,0,0)';
      PINUSE='POWER';
      NO_LOAD_CHECK='Both';
      NO_IO_CHECK='Both';
      NO_ASSERT_CHECK='TRUE';
      NO_DIR_CHECK='TRUE';
      ALLOW_CONNECT='TRUE';
    'VSS1821':
      PIN_NUMBER='(0,0,0,0,0,0,0,0,0,0,0,0,0,0,0,0,0,0,0,0,0,0,0,0,0,0,0,0,0,0,0~
,0,0,0,0,0,0,0,0,Y16,0,0)';
      PINUSE='POWER';
      NO_LOAD_CHECK='Both';
      NO_IO_CHECK='Both';
      NO_ASSERT_CHECK='TRUE';
      NO_DIR_CHECK='TRUE';
      ALLOW_CONNECT='TRUE';
    'VSS1820':
      PIN_NUMBER='(0,0,0,0,0,0,0,0,0,0,0,0,0,0,0,0,0,0,0,0,0,0,0,0,0,0,0,0,0,0,0~
,0,0,0,0,0,0,0,0,Y12,0,0)';
      PINUSE='POWER';
      NO_LOAD_CHECK='Both';
      NO_IO_CHECK='Both';
      NO_ASSERT_CHECK='TRUE';
      NO_DIR_CHECK='TRUE';
      ALLOW_CONNECT='TRUE';
    'VSS1819':
      PIN_NUMBER='(0,0,0,0,0,0,0,0,0,0,0,0,0,0,0,0,0,0,0,0,0,0,0,0,0,0,0,0,0,0,0~
,0,0,0,0,0,0,0,0,W9,0,0)';
      PINUSE='POWER';
      NO_LOAD_CHECK='Both';
      NO_IO_CHECK='Both';
      NO_ASSERT_CHECK='TRUE';
      NO_DIR_CHECK='TRUE';
      ALLOW_CONNECT='TRUE';
    'VSS1818':
      PIN_NUMBER='(0,0,0,0,0,0,0,0,0,0,0,0,0,0,0,0,0,0,0,0,0,0,0,0,0,0,0,0,0,0,0~
,0,0,0,0,0,0,0,0,W88,0,0)';
      PINUSE='POWER';
      NO_LOAD_CHECK='Both';
      NO_IO_CHECK='Both';
      NO_ASSERT_CHECK='TRUE';
      NO_DIR_CHECK='TRUE';
      ALLOW_CONNECT='TRUE';
    'VSS1817':
      PIN_NUMBER='(0,0,0,0,0,0,0,0,0,0,0,0,0,0,0,0,0,0,0,0,0,0,0,0,0,0,0,0,0,0,0~
,0,0,0,0,0,0,0,0,W84,0,0)';
      PINUSE='POWER';
      NO_LOAD_CHECK='Both';
      NO_IO_CHECK='Both';
      NO_ASSERT_CHECK='TRUE';
      NO_DIR_CHECK='TRUE';
      ALLOW_CONNECT='TRUE';
    'VSS1816':
      PIN_NUMBER='(0,0,0,0,0,0,0,0,0,0,0,0,0,0,0,0,0,0,0,0,0,0,0,0,0,0,0,0,0,0,0~
,0,0,0,0,0,0,0,0,W39,0,0)';
      PINUSE='POWER';
      NO_LOAD_CHECK='Both';
      NO_IO_CHECK='Both';
      NO_ASSERT_CHECK='TRUE';
      NO_DIR_CHECK='TRUE';
      ALLOW_CONNECT='TRUE';
    'VSS1815':
      PIN_NUMBER='(0,0,0,0,0,0,0,0,0,0,0,0,0,0,0,0,0,0,0,0,0,0,0,0,0,0,0,0,0,0,0~
,0,0,0,0,0,0,0,0,W52,0,0)';
      PINUSE='POWER';
      NO_LOAD_CHECK='Both';
      NO_IO_CHECK='Both';
      NO_ASSERT_CHECK='TRUE';
      NO_DIR_CHECK='TRUE';
      ALLOW_CONNECT='TRUE';
    'VSS1814':
      PIN_NUMBER='(0,0,0,0,0,0,0,0,0,0,0,0,0,0,0,0,0,0,0,0,0,0,0,0,0,0,0,0,0,0,0~
,0,0,0,0,0,0,0,0,W5,0,0)';
      PINUSE='POWER';
      NO_LOAD_CHECK='Both';
      NO_IO_CHECK='Both';
      NO_ASSERT_CHECK='TRUE';
      NO_DIR_CHECK='TRUE';
      ALLOW_CONNECT='TRUE';
    'VSS1813':
      PIN_NUMBER='(0,0,0,0,0,0,0,0,0,0,0,0,0,0,0,0,0,0,0,0,0,0,0,0,0,0,0,0,0,0,0~
,0,0,0,0,0,0,0,0,V87,0,0)';
      PINUSE='POWER';
      NO_LOAD_CHECK='Both';
      NO_IO_CHECK='Both';
      NO_ASSERT_CHECK='TRUE';
      NO_DIR_CHECK='TRUE';
      ALLOW_CONNECT='TRUE';
    'VSS1812':
      PIN_NUMBER='(0,0,0,0,0,0,0,0,0,0,0,0,0,0,0,0,0,0,0,0,0,0,0,0,0,0,0,0,0,0,0~
,0,0,0,0,0,0,0,0,V8,0,0)';
      PINUSE='POWER';
      NO_LOAD_CHECK='Both';
      NO_IO_CHECK='Both';
      NO_ASSERT_CHECK='TRUE';
      NO_DIR_CHECK='TRUE';
      ALLOW_CONNECT='TRUE';
    'VSS1811':
      PIN_NUMBER='(0,0,0,0,0,0,0,0,0,0,0,0,0,0,0,0,0,0,0,0,0,0,0,0,0,0,0,0,0,0,0~
,0,0,0,0,0,0,0,0,V79,0,0)';
      PINUSE='POWER';
      NO_LOAD_CHECK='Both';
      NO_IO_CHECK='Both';
      NO_ASSERT_CHECK='TRUE';
      NO_DIR_CHECK='TRUE';
      ALLOW_CONNECT='TRUE';
    'VSS1810':
      PIN_NUMBER='(0,0,0,0,0,0,0,0,0,0,0,0,0,0,0,0,0,0,0,0,0,0,0,0,0,0,0,0,0,0,0~
,0,0,0,0,0,0,0,0,V77,0,0)';
      PINUSE='POWER';
      NO_LOAD_CHECK='Both';
      NO_IO_CHECK='Both';
      NO_ASSERT_CHECK='TRUE';
      NO_DIR_CHECK='TRUE';
      ALLOW_CONNECT='TRUE';
    'VSS1809':
      PIN_NUMBER='(0,0,0,0,0,0,0,0,0,0,0,0,0,0,0,0,0,0,0,0,0,0,0,0,0,0,0,0,0,0,0~
,0,0,0,0,0,0,0,0,W13,0,0)';
      PINUSE='POWER';
      NO_LOAD_CHECK='Both';
      NO_IO_CHECK='Both';
      NO_ASSERT_CHECK='TRUE';
      NO_DIR_CHECK='TRUE';
      ALLOW_CONNECT='TRUE';
    'VSS1808':
      PIN_NUMBER='(0,0,0,0,0,0,0,0,0,0,0,0,0,0,0,0,0,0,0,0,0,0,0,0,0,0,0,0,0,0,0~
,0,0,0,0,0,0,0,0,W1,0,0)';
      PINUSE='POWER';
      NO_LOAD_CHECK='Both';
      NO_IO_CHECK='Both';
      NO_ASSERT_CHECK='TRUE';
      NO_DIR_CHECK='TRUE';
      ALLOW_CONNECT='TRUE';
    'VSS1807':
      PIN_NUMBER='(0,0,0,0,0,0,0,0,0,0,0,0,0,0,0,0,0,0,0,0,0,0,0,0,0,0,0,0,0,0,0~
,0,0,0,0,0,0,0,0,V91,0,0)';
      PINUSE='POWER';
      NO_LOAD_CHECK='Both';
      NO_IO_CHECK='Both';
      NO_ASSERT_CHECK='TRUE';
      NO_DIR_CHECK='TRUE';
      ALLOW_CONNECT='TRUE';
    'VSS1806':
      PIN_NUMBER='(0,0,0,0,0,0,0,0,0,0,0,0,0,0,0,0,0,0,0,0,0,0,0,0,0,0,0,0,0,0,0~
,0,0,0,0,0,0,0,0,V75,0,0)';
      PINUSE='POWER';
      NO_LOAD_CHECK='Both';
      NO_IO_CHECK='Both';
      NO_ASSERT_CHECK='TRUE';
      NO_DIR_CHECK='TRUE';
      ALLOW_CONNECT='TRUE';
    'VSS1805':
      PIN_NUMBER='(0,0,0,0,0,0,0,0,0,0,0,0,0,0,0,0,0,0,0,0,0,0,0,0,0,0,0,0,0,0,0~
,0,0,0,0,0,0,0,0,V69,0,0)';
      PINUSE='POWER';
      NO_LOAD_CHECK='Both';
      NO_IO_CHECK='Both';
      NO_ASSERT_CHECK='TRUE';
      NO_DIR_CHECK='TRUE';
      ALLOW_CONNECT='TRUE';
    'VSS1804':
      PIN_NUMBER='(0,0,0,0,0,0,0,0,0,0,0,0,0,0,0,0,0,0,0,0,0,0,0,0,0,0,0,0,0,0,0~
,0,0,0,0,0,0,0,0,V67,0,0)';
      PINUSE='POWER';
      NO_LOAD_CHECK='Both';
      NO_IO_CHECK='Both';
      NO_ASSERT_CHECK='TRUE';
      NO_DIR_CHECK='TRUE';
      ALLOW_CONNECT='TRUE';
    'VSS1803':
      PIN_NUMBER='(0,0,0,0,0,0,0,0,0,0,0,0,0,0,0,0,0,0,0,0,0,0,0,0,0,0,0,0,0,0,0~
,0,0,0,0,0,0,0,0,V65,0,0)';
      PINUSE='POWER';
      NO_LOAD_CHECK='Both';
      NO_IO_CHECK='Both';
      NO_ASSERT_CHECK='TRUE';
      NO_DIR_CHECK='TRUE';
      ALLOW_CONNECT='TRUE';
    'VSS1802':
      PIN_NUMBER='(0,0,0,0,0,0,0,0,0,0,0,0,0,0,0,0,0,0,0,0,0,0,0,0,0,0,0,0,0,0,0~
,0,0,0,0,0,0,0,0,V63,0,0)';
      PINUSE='POWER';
      NO_LOAD_CHECK='Both';
      NO_IO_CHECK='Both';
      NO_ASSERT_CHECK='TRUE';
      NO_DIR_CHECK='TRUE';
      ALLOW_CONNECT='TRUE';
    'VSS1801':
      PIN_NUMBER='(0,0,0,0,0,0,0,0,0,0,0,0,0,0,0,0,0,0,0,0,0,0,0,0,0,0,0,0,0,0,0~
,0,0,0,0,0,0,0,0,V73,0,0)';
      PINUSE='POWER';
      NO_LOAD_CHECK='Both';
      NO_IO_CHECK='Both';
      NO_ASSERT_CHECK='TRUE';
      NO_DIR_CHECK='TRUE';
      ALLOW_CONNECT='TRUE';
    'VSS1800':
      PIN_NUMBER='(0,0,0,0,0,0,0,0,0,0,0,0,0,0,0,0,0,0,0,0,0,0,0,0,0,0,0,0,0,0,0~
,0,0,0,0,0,0,0,0,V71,0,0)';
      PINUSE='POWER';
      NO_LOAD_CHECK='Both';
      NO_IO_CHECK='Both';
      NO_ASSERT_CHECK='TRUE';
      NO_DIR_CHECK='TRUE';
      ALLOW_CONNECT='TRUE';
    'VSS1799':
      PIN_NUMBER='(0,0,0,0,0,0,0,0,0,0,0,0,0,0,0,0,0,0,0,0,0,0,0,0,0,0,0,0,0,0,0~
,0,0,0,0,0,0,0,0,V61,0,0)';
      PINUSE='POWER';
      NO_LOAD_CHECK='Both';
      NO_IO_CHECK='Both';
      NO_ASSERT_CHECK='TRUE';
      NO_DIR_CHECK='TRUE';
      ALLOW_CONNECT='TRUE';
    'VSS1798':
      PIN_NUMBER='(0,0,0,0,0,0,0,0,0,0,0,0,0,0,0,0,0,0,0,0,0,0,0,0,0,0,0,0,0,0,0~
,0,0,0,0,0,0,0,0,V59,0,0)';
      PINUSE='POWER';
      NO_LOAD_CHECK='Both';
      NO_IO_CHECK='Both';
      NO_ASSERT_CHECK='TRUE';
      NO_DIR_CHECK='TRUE';
      ALLOW_CONNECT='TRUE';
    'VSS1797':
      PIN_NUMBER='(0,0,0,0,0,0,0,0,0,0,0,0,0,0,0,0,0,0,0,0,0,0,0,0,0,0,0,0,0,0,0~
,0,0,0,0,0,0,0,0,V57,0,0)';
      PINUSE='POWER';
      NO_LOAD_CHECK='Both';
      NO_IO_CHECK='Both';
      NO_ASSERT_CHECK='TRUE';
      NO_DIR_CHECK='TRUE';
      ALLOW_CONNECT='TRUE';
    'VSS1796':
      PIN_NUMBER='(0,0,0,0,0,0,0,0,0,0,0,0,0,0,0,0,0,0,0,0,0,0,0,0,0,0,0,0,0,0,0~
,0,0,0,0,0,0,0,0,V55,0,0)';
      PINUSE='POWER';
      NO_LOAD_CHECK='Both';
      NO_IO_CHECK='Both';
      NO_ASSERT_CHECK='TRUE';
      NO_DIR_CHECK='TRUE';
      ALLOW_CONNECT='TRUE';
    'VSS1795':
      PIN_NUMBER='(0,0,0,0,0,0,0,0,0,0,0,0,0,0,0,0,0,0,0,0,0,0,0,0,0,0,0,0,0,0,0~
,0,0,0,0,0,0,0,0,V53,0,0)';
      PINUSE='POWER';
      NO_LOAD_CHECK='Both';
      NO_IO_CHECK='Both';
      NO_ASSERT_CHECK='TRUE';
      NO_DIR_CHECK='TRUE';
      ALLOW_CONNECT='TRUE';
    'VSS1794':
      PIN_NUMBER='(0,0,0,0,0,0,0,0,0,0,0,0,0,0,0,0,0,0,0,0,0,0,0,0,0,0,0,0,0,0,0~
,0,0,0,0,0,0,0,0,V51,0,0)';
      PINUSE='POWER';
      NO_LOAD_CHECK='Both';
      NO_IO_CHECK='Both';
      NO_ASSERT_CHECK='TRUE';
      NO_DIR_CHECK='TRUE';
      ALLOW_CONNECT='TRUE';
    'VSS1793':
      PIN_NUMBER='(0,0,0,0,0,0,0,0,0,0,0,0,0,0,0,0,0,0,0,0,0,0,0,0,0,0,0,0,0,0,0~
,0,0,0,0,0,0,0,0,V47,0,0)';
      PINUSE='POWER';
      NO_LOAD_CHECK='Both';
      NO_IO_CHECK='Both';
      NO_ASSERT_CHECK='TRUE';
      NO_DIR_CHECK='TRUE';
      ALLOW_CONNECT='TRUE';
    'VSS1792':
      PIN_NUMBER='(0,0,0,0,0,0,0,0,0,0,0,0,0,0,0,0,0,0,0,0,0,0,0,0,0,0,0,0,0,0,0~
,0,0,0,0,0,0,0,0,V44,0,0)';
      PINUSE='POWER';
      NO_LOAD_CHECK='Both';
      NO_IO_CHECK='Both';
      NO_ASSERT_CHECK='TRUE';
      NO_DIR_CHECK='TRUE';
      ALLOW_CONNECT='TRUE';
    'VSS1791':
      PIN_NUMBER='(0,0,0,0,0,0,0,0,0,0,0,0,0,0,0,0,0,0,0,0,0,0,0,0,0,0,0,0,0,0,0~
,0,0,0,0,0,0,0,0,V42,0,0)';
      PINUSE='POWER';
      NO_LOAD_CHECK='Both';
      NO_IO_CHECK='Both';
      NO_ASSERT_CHECK='TRUE';
      NO_DIR_CHECK='TRUE';
      ALLOW_CONNECT='TRUE';
    'VSS1790':
      PIN_NUMBER='(0,0,0,0,0,0,0,0,0,0,0,0,0,0,0,0,0,0,0,0,0,0,0,0,0,0,0,0,0,0,0~
,0,0,0,0,0,0,0,0,V40,0,0)';
      PINUSE='POWER';
      NO_LOAD_CHECK='Both';
      NO_IO_CHECK='Both';
      NO_ASSERT_CHECK='TRUE';
      NO_DIR_CHECK='TRUE';
      ALLOW_CONNECT='TRUE';
    'VSS1789':
      PIN_NUMBER='(0,0,0,0,0,0,0,0,0,0,0,0,0,0,0,0,0,0,0,0,0,0,0,0,0,0,0,0,0,0,0~
,0,0,0,0,0,0,0,0,V49,0,0)';
      PINUSE='POWER';
      NO_LOAD_CHECK='Both';
      NO_IO_CHECK='Both';
      NO_ASSERT_CHECK='TRUE';
      NO_DIR_CHECK='TRUE';
      ALLOW_CONNECT='TRUE';
    'VSS1788':
      PIN_NUMBER='(0,0,0,0,0,0,0,0,0,0,0,0,0,0,0,0,0,0,0,0,0,0,0,0,0,0,0,0,0,0,0~
,0,0,0,0,0,0,0,0,V4,0,0)';
      PINUSE='POWER';
      NO_LOAD_CHECK='Both';
      NO_IO_CHECK='Both';
      NO_ASSERT_CHECK='TRUE';
      NO_DIR_CHECK='TRUE';
      ALLOW_CONNECT='TRUE';
    'VSS1787':
      PIN_NUMBER='(0,0,0,0,0,0,0,0,0,0,0,0,0,0,0,0,0,0,0,0,0,0,0,0,0,0,0,0,0,0,0~
,0,0,0,0,0,0,0,0,V38,0,0)';
      PINUSE='POWER';
      NO_LOAD_CHECK='Both';
      NO_IO_CHECK='Both';
      NO_ASSERT_CHECK='TRUE';
      NO_DIR_CHECK='TRUE';
      ALLOW_CONNECT='TRUE';
    'VSS1786':
      PIN_NUMBER='(0,0,0,0,0,0,0,0,0,0,0,0,0,0,0,0,0,0,0,0,0,0,0,0,0,0,0,0,0,0,0~
,0,0,0,0,0,0,0,0,V36,0,0)';
      PINUSE='POWER';
      NO_LOAD_CHECK='Both';
      NO_IO_CHECK='Both';
      NO_ASSERT_CHECK='TRUE';
      NO_DIR_CHECK='TRUE';
      ALLOW_CONNECT='TRUE';
    'VSS1785':
      PIN_NUMBER='(0,0,0,0,0,0,0,0,0,0,0,0,0,0,0,0,0,0,0,0,0,0,0,0,0,0,0,0,0,0,0~
,0,0,0,0,0,0,0,0,V34,0,0)';
      PINUSE='POWER';
      NO_LOAD_CHECK='Both';
      NO_IO_CHECK='Both';
      NO_ASSERT_CHECK='TRUE';
      NO_DIR_CHECK='TRUE';
      ALLOW_CONNECT='TRUE';
    'VSS1784':
      PIN_NUMBER='(0,0,0,0,0,0,0,0,0,0,0,0,0,0,0,0,0,0,0,0,0,0,0,0,0,0,0,0,0,0,0~
,0,0,0,0,0,0,0,0,V32,0,0)';
      PINUSE='POWER';
      NO_LOAD_CHECK='Both';
      NO_IO_CHECK='Both';
      NO_ASSERT_CHECK='TRUE';
      NO_DIR_CHECK='TRUE';
      ALLOW_CONNECT='TRUE';
    'VSS1783':
      PIN_NUMBER='(0,0,0,0,0,0,0,0,0,0,0,0,0,0,0,0,0,0,0,0,0,0,0,0,0,0,0,0,0,0,0~
,0,0,0,0,0,0,0,0,V30,0,0)';
      PINUSE='POWER';
      NO_LOAD_CHECK='Both';
      NO_IO_CHECK='Both';
      NO_ASSERT_CHECK='TRUE';
      NO_DIR_CHECK='TRUE';
      ALLOW_CONNECT='TRUE';
    'VSS1782':
      PIN_NUMBER='(0,0,0,0,0,0,0,0,0,0,0,0,0,0,0,0,0,0,0,0,0,0,0,0,0,0,0,0,0,0,0~
,0,0,0,0,0,0,0,0,V28,0,0)';
      PINUSE='POWER';
      NO_LOAD_CHECK='Both';
      NO_IO_CHECK='Both';
      NO_ASSERT_CHECK='TRUE';
      NO_DIR_CHECK='TRUE';
      ALLOW_CONNECT='TRUE';
    'VSS1781':
      PIN_NUMBER='(0,0,0,0,0,0,0,0,0,0,0,0,0,0,0,0,0,0,0,0,0,0,0,0,0,0,0,0,0,0,0~
,0,0,0,0,0,0,0,0,V26,0,0)';
      PINUSE='POWER';
      NO_LOAD_CHECK='Both';
      NO_IO_CHECK='Both';
      NO_ASSERT_CHECK='TRUE';
      NO_DIR_CHECK='TRUE';
      ALLOW_CONNECT='TRUE';
    'VSS1780':
      PIN_NUMBER='(0,0,0,0,0,0,0,0,0,0,0,0,0,0,0,0,0,0,0,0,0,0,0,0,0,0,0,0,0,0,0~
,0,0,0,0,0,0,0,0,V24,0,0)';
      PINUSE='POWER';
      NO_LOAD_CHECK='Both';
      NO_IO_CHECK='Both';
      NO_ASSERT_CHECK='TRUE';
      NO_DIR_CHECK='TRUE';
      ALLOW_CONNECT='TRUE';
    'VSS1779':
      PIN_NUMBER='(0,0,0,0,0,0,0,0,0,0,0,0,0,0,0,0,0,0,0,0,0,0,0,0,0,0,0,0,0,0,0~
,0,0,0,0,0,0,0,0,V22,0,0)';
      PINUSE='POWER';
      NO_LOAD_CHECK='Both';
      NO_IO_CHECK='Both';
      NO_ASSERT_CHECK='TRUE';
      NO_DIR_CHECK='TRUE';
      ALLOW_CONNECT='TRUE';
    'VSS1778':
      PIN_NUMBER='(0,0,0,0,0,0,0,0,0,0,0,0,0,0,0,0,0,0,0,0,0,0,0,0,0,0,0,0,0,0,0~
,0,0,0,0,0,0,0,0,V20,0,0)';
      PINUSE='POWER';
      NO_LOAD_CHECK='Both';
      NO_IO_CHECK='Both';
      NO_ASSERT_CHECK='TRUE';
      NO_DIR_CHECK='TRUE';
      ALLOW_CONNECT='TRUE';
    'VSS1777':
      PIN_NUMBER='(0,0,0,0,0,0,0,0,0,0,0,0,0,0,0,0,0,0,0,0,0,0,0,0,0,0,0,0,0,0,0~
,0,0,0,0,0,0,0,0,V18,0,0)';
      PINUSE='POWER';
      NO_LOAD_CHECK='Both';
      NO_IO_CHECK='Both';
      NO_ASSERT_CHECK='TRUE';
      NO_DIR_CHECK='TRUE';
      ALLOW_CONNECT='TRUE';
    'VSS1776':
      PIN_NUMBER='(0,0,0,0,0,0,0,0,0,0,0,0,0,0,0,0,0,0,0,0,0,0,0,0,0,0,0,0,0,0,0~
,0,0,0,0,0,0,0,0,V16,0,0)';
      PINUSE='POWER';
      NO_LOAD_CHECK='Both';
      NO_IO_CHECK='Both';
      NO_ASSERT_CHECK='TRUE';
      NO_DIR_CHECK='TRUE';
      ALLOW_CONNECT='TRUE';
    'VSS1775':
      PIN_NUMBER='(0,0,0,0,0,0,0,0,0,0,0,0,0,0,0,0,0,0,0,0,0,0,0,0,0,0,0,0,0,0,0~
,0,0,0,0,0,0,0,0,V12,0,0)';
      PINUSE='POWER';
      NO_LOAD_CHECK='Both';
      NO_IO_CHECK='Both';
      NO_ASSERT_CHECK='TRUE';
      NO_DIR_CHECK='TRUE';
      ALLOW_CONNECT='TRUE';
    'VSS1774':
      PIN_NUMBER='(0,0,0,0,0,0,0,0,0,0,0,0,0,0,0,0,0,0,0,0,0,0,0,0,0,0,0,0,0,0,0~
,0,0,0,0,0,0,0,0,U88,0,0)';
      PINUSE='POWER';
      NO_LOAD_CHECK='Both';
      NO_IO_CHECK='Both';
      NO_ASSERT_CHECK='TRUE';
      NO_DIR_CHECK='TRUE';
      ALLOW_CONNECT='TRUE';
    'VSS1773':
      PIN_NUMBER='(0,0,0,0,0,0,0,0,0,0,0,0,0,0,0,0,0,0,0,0,0,0,0,0,0,0,0,0,0,0,0~
,0,0,0,0,0,0,0,0,U84,0,0)';
      PINUSE='POWER';
      NO_LOAD_CHECK='Both';
      NO_IO_CHECK='Both';
      NO_ASSERT_CHECK='TRUE';
      NO_DIR_CHECK='TRUE';
      ALLOW_CONNECT='TRUE';
    'VSS1772':
      PIN_NUMBER='(0,0,0,0,0,0,0,0,0,0,0,0,0,0,0,0,0,0,0,0,0,0,0,0,0,0,0,0,0,0,0~
,0,0,0,0,0,0,0,0,U82,0,0)';
      PINUSE='POWER';
      NO_LOAD_CHECK='Both';
      NO_IO_CHECK='Both';
      NO_ASSERT_CHECK='TRUE';
      NO_DIR_CHECK='TRUE';
      ALLOW_CONNECT='TRUE';
    'VSS1771':
      PIN_NUMBER='(0,0,0,0,0,0,0,0,0,0,0,0,0,0,0,0,0,0,0,0,0,0,0,0,0,0,0,0,0,0,0~
,0,0,0,0,0,0,0,0,U39,0,0)';
      PINUSE='POWER';
      NO_LOAD_CHECK='Both';
      NO_IO_CHECK='Both';
      NO_ASSERT_CHECK='TRUE';
      NO_DIR_CHECK='TRUE';
      ALLOW_CONNECT='TRUE';
    'VSS1770':
      PIN_NUMBER='(0,0,0,0,0,0,0,0,0,0,0,0,0,0,0,0,0,0,0,0,0,0,0,0,0,0,0,0,0,0,0~
,0,0,0,0,0,0,0,0,T83,0,0)';
      PINUSE='POWER';
      NO_LOAD_CHECK='Both';
      NO_IO_CHECK='Both';
      NO_ASSERT_CHECK='TRUE';
      NO_DIR_CHECK='TRUE';
      ALLOW_CONNECT='TRUE';
    'VSS1769':
      PIN_NUMBER='(0,0,0,0,0,0,0,0,0,0,0,0,0,0,0,0,0,0,0,0,0,0,0,0,0,0,0,0,0,0,0~
,0,0,0,0,0,0,0,0,T8,0,0)';
      PINUSE='POWER';
      NO_LOAD_CHECK='Both';
      NO_IO_CHECK='Both';
      NO_ASSERT_CHECK='TRUE';
      NO_DIR_CHECK='TRUE';
      ALLOW_CONNECT='TRUE';
    'VSS1768':
      PIN_NUMBER='(0,0,0,0,0,0,0,0,0,0,0,0,0,0,0,0,0,0,0,0,0,0,0,0,0,0,0,0,0,0,0~
,0,0,0,0,0,0,0,0,T79,0,0)';
      PINUSE='POWER';
      NO_LOAD_CHECK='Both';
      NO_IO_CHECK='Both';
      NO_ASSERT_CHECK='TRUE';
      NO_DIR_CHECK='TRUE';
      ALLOW_CONNECT='TRUE';
    'VSS1767':
      PIN_NUMBER='(0,0,0,0,0,0,0,0,0,0,0,0,0,0,0,0,0,0,0,0,0,0,0,0,0,0,0,0,0,0,0~
,0,0,0,0,0,0,0,0,T73,0,0)';
      PINUSE='POWER';
      NO_LOAD_CHECK='Both';
      NO_IO_CHECK='Both';
      NO_ASSERT_CHECK='TRUE';
      NO_DIR_CHECK='TRUE';
      ALLOW_CONNECT='TRUE';
    'VSS1766':
      PIN_NUMBER='(0,0,0,0,0,0,0,0,0,0,0,0,0,0,0,0,0,0,0,0,0,0,0,0,0,0,0,0,0,0,0~
,0,0,0,0,0,0,0,0,U52,0,0)';
      PINUSE='POWER';
      NO_LOAD_CHECK='Both';
      NO_IO_CHECK='Both';
      NO_ASSERT_CHECK='TRUE';
      NO_DIR_CHECK='TRUE';
      ALLOW_CONNECT='TRUE';
    'VSS1765':
      PIN_NUMBER='(0,0,0,0,0,0,0,0,0,0,0,0,0,0,0,0,0,0,0,0,0,0,0,0,0,0,0,0,0,0,0~
,0,0,0,0,0,0,0,0,T67,0,0)';
      PINUSE='POWER';
      NO_LOAD_CHECK='Both';
      NO_IO_CHECK='Both';
      NO_ASSERT_CHECK='TRUE';
      NO_DIR_CHECK='TRUE';
      ALLOW_CONNECT='TRUE';
    'VSS1764':
      PIN_NUMBER='(0,0,0,0,0,0,0,0,0,0,0,0,0,0,0,0,0,0,0,0,0,0,0,0,0,0,0,0,0,0,0~
,0,0,0,0,0,0,0,0,T61,0,0)';
      PINUSE='POWER';
      NO_LOAD_CHECK='Both';
      NO_IO_CHECK='Both';
      NO_ASSERT_CHECK='TRUE';
      NO_DIR_CHECK='TRUE';
      ALLOW_CONNECT='TRUE';
    'VSS1763':
      PIN_NUMBER='(0,0,0,0,0,0,0,0,0,0,0,0,0,0,0,0,0,0,0,0,0,0,0,0,0,0,0,0,0,0,0~
,0,0,0,0,0,0,0,0,T42,0,0)';
      PINUSE='POWER';
      NO_LOAD_CHECK='Both';
      NO_IO_CHECK='Both';
      NO_ASSERT_CHECK='TRUE';
      NO_DIR_CHECK='TRUE';
      ALLOW_CONNECT='TRUE';
    'VSS1762':
      PIN_NUMBER='(0,0,0,0,0,0,0,0,0,0,0,0,0,0,0,0,0,0,0,0,0,0,0,0,0,0,0,0,0,0,0~
,0,0,0,0,0,0,0,0,T4,0,0)';
      PINUSE='POWER';
      NO_LOAD_CHECK='Both';
      NO_IO_CHECK='Both';
      NO_ASSERT_CHECK='TRUE';
      NO_DIR_CHECK='TRUE';
      ALLOW_CONNECT='TRUE';
    'VSS1761':
      PIN_NUMBER='(0,0,0,0,0,0,0,0,0,0,0,0,0,0,0,0,0,0,0,0,0,0,0,0,0,0,0,0,0,0,0~
,0,0,0,0,0,0,0,0,T30,0,0)';
      PINUSE='POWER';
      NO_LOAD_CHECK='Both';
      NO_IO_CHECK='Both';
      NO_ASSERT_CHECK='TRUE';
      NO_DIR_CHECK='TRUE';
      ALLOW_CONNECT='TRUE';
    'VSS1760':
      PIN_NUMBER='(0,0,0,0,0,0,0,0,0,0,0,0,0,0,0,0,0,0,0,0,0,0,0,0,0,0,0,0,0,0,0~
,0,0,0,0,0,0,0,0,T24,0,0)';
      PINUSE='POWER';
      NO_LOAD_CHECK='Both';
      NO_IO_CHECK='Both';
      NO_ASSERT_CHECK='TRUE';
      NO_DIR_CHECK='TRUE';
      ALLOW_CONNECT='TRUE';
    'VSS1759':
      PIN_NUMBER='(0,0,0,0,0,0,0,0,0,0,0,0,0,0,0,0,0,0,0,0,0,0,0,0,0,0,0,0,0,0,0~
,0,0,0,0,0,0,0,0,R9,0,0)';
      PINUSE='POWER';
      NO_LOAD_CHECK='Both';
      NO_IO_CHECK='Both';
      NO_ASSERT_CHECK='TRUE';
      NO_DIR_CHECK='TRUE';
      ALLOW_CONNECT='TRUE';
    'VSS1758':
      PIN_NUMBER='(0,0,0,0,0,0,0,0,0,0,0,0,0,0,0,0,0,0,0,0,0,0,0,0,0,0,0,0,0,0,0~
,0,0,0,0,0,0,0,0,R88,0,0)';
      PINUSE='POWER';
      NO_LOAD_CHECK='Both';
      NO_IO_CHECK='Both';
      NO_ASSERT_CHECK='TRUE';
      NO_DIR_CHECK='TRUE';
      ALLOW_CONNECT='TRUE';
    'VSS1757':
      PIN_NUMBER='(0,0,0,0,0,0,0,0,0,0,0,0,0,0,0,0,0,0,0,0,0,0,0,0,0,0,0,0,0,0,0~
,0,0,0,0,0,0,0,0,R84,0,0)';
      PINUSE='POWER';
      NO_LOAD_CHECK='Both';
      NO_IO_CHECK='Both';
      NO_ASSERT_CHECK='TRUE';
      NO_DIR_CHECK='TRUE';
      ALLOW_CONNECT='TRUE';
    'VSS1756':
      PIN_NUMBER='(0,0,0,0,0,0,0,0,0,0,0,0,0,0,0,0,0,0,0,0,0,0,0,0,0,0,0,0,0,0,0~
,0,0,0,0,0,0,0,0,R78,0,0)';
      PINUSE='POWER';
      NO_LOAD_CHECK='Both';
      NO_IO_CHECK='Both';
      NO_ASSERT_CHECK='TRUE';
      NO_DIR_CHECK='TRUE';
      ALLOW_CONNECT='TRUE';
    'VSS1755':
      PIN_NUMBER='(0,0,0,0,0,0,0,0,0,0,0,0,0,0,0,0,0,0,0,0,0,0,0,0,0,0,0,0,0,0,0~
,0,0,0,0,0,0,0,0,R74,0,0)';
      PINUSE='POWER';
      NO_LOAD_CHECK='Both';
      NO_IO_CHECK='Both';
      NO_ASSERT_CHECK='TRUE';
      NO_DIR_CHECK='TRUE';
      ALLOW_CONNECT='TRUE';
    'VSS1754':
      PIN_NUMBER='(0,0,0,0,0,0,0,0,0,0,0,0,0,0,0,0,0,0,0,0,0,0,0,0,0,0,0,0,0,0,0~
,0,0,0,0,0,0,0,0,R72,0,0)';
      PINUSE='POWER';
      NO_LOAD_CHECK='Both';
      NO_IO_CHECK='Both';
      NO_ASSERT_CHECK='TRUE';
      NO_DIR_CHECK='TRUE';
      ALLOW_CONNECT='TRUE';
    'VSS1753':
      PIN_NUMBER='(0,0,0,0,0,0,0,0,0,0,0,0,0,0,0,0,0,0,0,0,0,0,0,0,0,0,0,0,0,0,0~
,0,0,0,0,0,0,0,0,R68,0,0)';
      PINUSE='POWER';
      NO_LOAD_CHECK='Both';
      NO_IO_CHECK='Both';
      NO_ASSERT_CHECK='TRUE';
      NO_DIR_CHECK='TRUE';
      ALLOW_CONNECT='TRUE';
    'VSS1752':
      PIN_NUMBER='(0,0,0,0,0,0,0,0,0,0,0,0,0,0,0,0,0,0,0,0,0,0,0,0,0,0,0,0,0,0,0~
,0,0,0,0,0,0,0,0,R62,0,0)';
      PINUSE='POWER';
      NO_LOAD_CHECK='Both';
      NO_IO_CHECK='Both';
      NO_ASSERT_CHECK='TRUE';
      NO_DIR_CHECK='TRUE';
      ALLOW_CONNECT='TRUE';
    'VSS1751':
      PIN_NUMBER='(0,0,0,0,0,0,0,0,0,0,0,0,0,0,0,0,0,0,0,0,0,0,0,0,0,0,0,0,0,0,0~
,0,0,0,0,0,0,0,0,R56,0,0)';
      PINUSE='POWER';
      NO_LOAD_CHECK='Both';
      NO_IO_CHECK='Both';
      NO_ASSERT_CHECK='TRUE';
      NO_DIR_CHECK='TRUE';
      ALLOW_CONNECT='TRUE';
    'VSS1750':
      PIN_NUMBER='(0,0,0,0,0,0,0,0,0,0,0,0,0,0,0,0,0,0,0,0,0,0,0,0,0,0,0,0,0,0,0~
,0,0,0,0,0,0,0,0,T55,0,0)';
      PINUSE='POWER';
      NO_LOAD_CHECK='Both';
      NO_IO_CHECK='Both';
      NO_ASSERT_CHECK='TRUE';
      NO_DIR_CHECK='TRUE';
      ALLOW_CONNECT='TRUE';
    'VSS1749':
      PIN_NUMBER='(0,0,0,0,0,0,0,0,0,0,0,0,0,0,0,0,0,0,0,0,0,0,0,0,0,0,0,0,0,0,0~
,0,0,0,0,0,0,0,0,T49,0,0)';
      PINUSE='POWER';
      NO_LOAD_CHECK='Both';
      NO_IO_CHECK='Both';
      NO_ASSERT_CHECK='TRUE';
      NO_DIR_CHECK='TRUE';
      ALLOW_CONNECT='TRUE';
    'VSS1748':
      PIN_NUMBER='(0,0,0,0,0,0,0,0,0,0,0,0,0,0,0,0,0,0,0,0,0,0,0,0,0,0,0,0,0,0,0~
,0,0,0,0,0,0,0,0,R54,0,0)';
      PINUSE='POWER';
      NO_LOAD_CHECK='Both';
      NO_IO_CHECK='Both';
      NO_ASSERT_CHECK='TRUE';
      NO_DIR_CHECK='TRUE';
      ALLOW_CONNECT='TRUE';
    'VSS1747':
      PIN_NUMBER='(0,0,0,0,0,0,0,0,0,0,0,0,0,0,0,0,0,0,0,0,0,0,0,0,0,0,0,0,0,0,0~
,0,0,0,0,0,0,0,0,R50,0,0)';
      PINUSE='POWER';
      NO_LOAD_CHECK='Both';
      NO_IO_CHECK='Both';
      NO_ASSERT_CHECK='TRUE';
      NO_DIR_CHECK='TRUE';
      ALLOW_CONNECT='TRUE';
    'VSS1746':
      PIN_NUMBER='(0,0,0,0,0,0,0,0,0,0,0,0,0,0,0,0,0,0,0,0,0,0,0,0,0,0,0,0,0,0,0~
,0,0,0,0,0,0,0,0,T36,0,0)';
      PINUSE='POWER';
      NO_LOAD_CHECK='Both';
      NO_IO_CHECK='Both';
      NO_ASSERT_CHECK='TRUE';
      NO_DIR_CHECK='TRUE';
      ALLOW_CONNECT='TRUE';
    'VSS1745':
      PIN_NUMBER='(0,0,0,0,0,0,0,0,0,0,0,0,0,0,0,0,0,0,0,0,0,0,0,0,0,0,0,0,0,0,0~
,0,0,0,0,0,0,0,0,R5,0,0)';
      PINUSE='POWER';
      NO_LOAD_CHECK='Both';
      NO_IO_CHECK='Both';
      NO_ASSERT_CHECK='TRUE';
      NO_DIR_CHECK='TRUE';
      ALLOW_CONNECT='TRUE';
    'VSS1744':
      PIN_NUMBER='(0,0,0,0,0,0,0,0,0,0,0,0,0,0,0,0,0,0,0,0,0,0,0,0,0,0,0,0,0,0,0~
,0,0,0,0,0,0,0,0,R43,0,0)';
      PINUSE='POWER';
      NO_LOAD_CHECK='Both';
      NO_IO_CHECK='Both';
      NO_ASSERT_CHECK='TRUE';
      NO_DIR_CHECK='TRUE';
      ALLOW_CONNECT='TRUE';
    'VSS1743':
      PIN_NUMBER='(0,0,0,0,0,0,0,0,0,0,0,0,0,0,0,0,0,0,0,0,0,0,0,0,0,0,0,0,0,0,0~
,0,0,0,0,0,0,0,0,R41,0,0)';
      PINUSE='POWER';
      NO_LOAD_CHECK='Both';
      NO_IO_CHECK='Both';
      NO_ASSERT_CHECK='TRUE';
      NO_DIR_CHECK='TRUE';
      ALLOW_CONNECT='TRUE';
    'VSS1742':
      PIN_NUMBER='(0,0,0,0,0,0,0,0,0,0,0,0,0,0,0,0,0,0,0,0,0,0,0,0,0,0,0,0,0,0,0~
,0,0,0,0,0,0,0,0,R37,0,0)';
      PINUSE='POWER';
      NO_LOAD_CHECK='Both';
      NO_IO_CHECK='Both';
      NO_ASSERT_CHECK='TRUE';
      NO_DIR_CHECK='TRUE';
      ALLOW_CONNECT='TRUE';
    'VSS1741':
      PIN_NUMBER='(0,0,0,0,0,0,0,0,0,0,0,0,0,0,0,0,0,0,0,0,0,0,0,0,0,0,0,0,0,0,0~
,0,0,0,0,0,0,0,0,T18,0,0)';
      PINUSE='POWER';
      NO_LOAD_CHECK='Both';
      NO_IO_CHECK='Both';
      NO_ASSERT_CHECK='TRUE';
      NO_DIR_CHECK='TRUE';
      ALLOW_CONNECT='TRUE';
    'VSS1740':
      PIN_NUMBER='(0,0,0,0,0,0,0,0,0,0,0,0,0,0,0,0,0,0,0,0,0,0,0,0,0,0,0,0,0,0,0~
,0,0,0,0,0,0,0,0,T16,0,0)';
      PINUSE='POWER';
      NO_LOAD_CHECK='Both';
      NO_IO_CHECK='Both';
      NO_ASSERT_CHECK='TRUE';
      NO_DIR_CHECK='TRUE';
      ALLOW_CONNECT='TRUE';
    'VSS1739':
      PIN_NUMBER='(0,0,0,0,0,0,0,0,0,0,0,0,0,0,0,0,0,0,0,0,0,0,0,0,0,0,0,0,0,0,0~
,0,0,0,0,0,0,0,0,T12,0,0)';
      PINUSE='POWER';
      NO_LOAD_CHECK='Both';
      NO_IO_CHECK='Both';
      NO_ASSERT_CHECK='TRUE';
      NO_DIR_CHECK='TRUE';
      ALLOW_CONNECT='TRUE';
    'VSS1738':
      PIN_NUMBER='(0,0,0,0,0,0,0,0,0,0,0,0,0,0,0,0,0,0,0,0,0,0,0,0,0,0,0,0,0,0,0~
,0,0,0,0,0,0,0,0,R35,0,0)';
      PINUSE='POWER';
      NO_LOAD_CHECK='Both';
      NO_IO_CHECK='Both';
      NO_ASSERT_CHECK='TRUE';
      NO_DIR_CHECK='TRUE';
      ALLOW_CONNECT='TRUE';
    'VSS1737':
      PIN_NUMBER='(0,0,0,0,0,0,0,0,0,0,0,0,0,0,0,0,0,0,0,0,0,0,0,0,0,0,0,0,0,0,0~
,0,0,0,0,0,0,0,0,R31,0,0)';
      PINUSE='POWER';
      NO_LOAD_CHECK='Both';
      NO_IO_CHECK='Both';
      NO_ASSERT_CHECK='TRUE';
      NO_DIR_CHECK='TRUE';
      ALLOW_CONNECT='TRUE';
    'VSS1736':
      PIN_NUMBER='(0,0,0,0,0,0,0,0,0,0,0,0,0,0,0,0,0,0,0,0,0,0,0,0,0,0,0,0,0,0,0~
,0,0,0,0,0,0,0,0,R29,0,0)';
      PINUSE='POWER';
      NO_LOAD_CHECK='Both';
      NO_IO_CHECK='Both';
      NO_ASSERT_CHECK='TRUE';
      NO_DIR_CHECK='TRUE';
      ALLOW_CONNECT='TRUE';
    'VSS1735':
      PIN_NUMBER='(0,0,0,0,0,0,0,0,0,0,0,0,0,0,0,0,0,0,0,0,0,0,0,0,0,0,0,0,0,0,0~
,0,0,0,0,0,0,0,0,R25,0,0)';
      PINUSE='POWER';
      NO_LOAD_CHECK='Both';
      NO_IO_CHECK='Both';
      NO_ASSERT_CHECK='TRUE';
      NO_DIR_CHECK='TRUE';
      ALLOW_CONNECT='TRUE';
    'VSS1734':
      PIN_NUMBER='(0,0,0,0,0,0,0,0,0,0,0,0,0,0,0,0,0,0,0,0,0,0,0,0,0,0,0,0,0,0,0~
,0,0,0,0,0,0,0,0,R17,0,0)';
      PINUSE='POWER';
      NO_LOAD_CHECK='Both';
      NO_IO_CHECK='Both';
      NO_ASSERT_CHECK='TRUE';
      NO_DIR_CHECK='TRUE';
      ALLOW_CONNECT='TRUE';
    'VSS1733':
      PIN_NUMBER='(0,0,0,0,0,0,0,0,0,0,0,0,0,0,0,0,0,0,0,0,0,0,0,0,0,0,0,0,0,0,0~
,0,0,0,0,0,0,0,0,R13,0,0)';
      PINUSE='POWER';
      NO_LOAD_CHECK='Both';
      NO_IO_CHECK='Both';
      NO_ASSERT_CHECK='TRUE';
      NO_DIR_CHECK='TRUE';
      ALLOW_CONNECT='TRUE';
    'VSS1732':
      PIN_NUMBER='(0,0,0,0,0,0,0,0,0,0,0,0,0,0,0,0,0,0,0,0,0,0,0,0,0,0,0,0,0,0,0~
,0,0,0,0,0,0,0,0,P91,0,0)';
      PINUSE='POWER';
      NO_LOAD_CHECK='Both';
      NO_IO_CHECK='Both';
      NO_ASSERT_CHECK='TRUE';
      NO_DIR_CHECK='TRUE';
      ALLOW_CONNECT='TRUE';
    'VSS1731':
      PIN_NUMBER='(0,0,0,0,0,0,0,0,0,0,0,0,0,0,0,0,0,0,0,0,0,0,0,0,0,0,0,0,0,0,0~
,0,0,0,0,0,0,0,0,P87,0,0)';
      PINUSE='POWER';
      NO_LOAD_CHECK='Both';
      NO_IO_CHECK='Both';
      NO_ASSERT_CHECK='TRUE';
      NO_DIR_CHECK='TRUE';
      ALLOW_CONNECT='TRUE';
    'VSS1730':
      PIN_NUMBER='(0,0,0,0,0,0,0,0,0,0,0,0,0,0,0,0,0,0,0,0,0,0,0,0,0,0,0,0,0,0,0~
,0,0,0,0,0,0,0,0,R66,0,0)';
      PINUSE='POWER';
      NO_LOAD_CHECK='Both';
      NO_IO_CHECK='Both';
      NO_ASSERT_CHECK='TRUE';
      NO_DIR_CHECK='TRUE';
      ALLOW_CONNECT='TRUE';
    'VSS1729':
      PIN_NUMBER='(0,0,0,0,0,0,0,0,0,0,0,0,0,0,0,0,0,0,0,0,0,0,0,0,0,0,0,0,0,0,0~
,0,0,0,0,0,0,0,0,P8,0,0)';
      PINUSE='POWER';
      NO_LOAD_CHECK='Both';
      NO_IO_CHECK='Both';
      NO_ASSERT_CHECK='TRUE';
      NO_DIR_CHECK='TRUE';
      ALLOW_CONNECT='TRUE';
    'VSS1728':
      PIN_NUMBER='(0,0,0,0,0,0,0,0,0,0,0,0,0,0,0,0,0,0,0,0,0,0,0,0,0,0,0,0,0,0,0~
,0,0,0,0,0,0,0,0,R60,0,0)';
      PINUSE='POWER';
      NO_LOAD_CHECK='Both';
      NO_IO_CHECK='Both';
      NO_ASSERT_CHECK='TRUE';
      NO_DIR_CHECK='TRUE';
      ALLOW_CONNECT='TRUE';
    'VSS1727':
      PIN_NUMBER='(0,0,0,0,0,0,0,0,0,0,0,0,0,0,0,0,0,0,0,0,0,0,0,0,0,0,0,0,0,0,0~
,0,0,0,0,0,0,0,0,P77,0,0)';
      PINUSE='POWER';
      NO_LOAD_CHECK='Both';
      NO_IO_CHECK='Both';
      NO_ASSERT_CHECK='TRUE';
      NO_DIR_CHECK='TRUE';
      ALLOW_CONNECT='TRUE';
    'VSS1726':
      PIN_NUMBER='(0,0,0,0,0,0,0,0,0,0,0,0,0,0,0,0,0,0,0,0,0,0,0,0,0,0,0,0,0,0,0~
,0,0,0,0,0,0,0,0,P75,0,0)';
      PINUSE='POWER';
      NO_LOAD_CHECK='Both';
      NO_IO_CHECK='Both';
      NO_ASSERT_CHECK='TRUE';
      NO_DIR_CHECK='TRUE';
      ALLOW_CONNECT='TRUE';
    'VSS1725':
      PIN_NUMBER='(0,0,0,0,0,0,0,0,0,0,0,0,0,0,0,0,0,0,0,0,0,0,0,0,0,0,0,0,0,0,0~
,0,0,0,0,0,0,0,0,P69,0,0)';
      PINUSE='POWER';
      NO_LOAD_CHECK='Both';
      NO_IO_CHECK='Both';
      NO_ASSERT_CHECK='TRUE';
      NO_DIR_CHECK='TRUE';
      ALLOW_CONNECT='TRUE';
    'VSS1724':
      PIN_NUMBER='(0,0,0,0,0,0,0,0,0,0,0,0,0,0,0,0,0,0,0,0,0,0,0,0,0,0,0,0,0,0,0~
,0,0,0,0,0,0,0,0,P65,0,0)';
      PINUSE='POWER';
      NO_LOAD_CHECK='Both';
      NO_IO_CHECK='Both';
      NO_ASSERT_CHECK='TRUE';
      NO_DIR_CHECK='TRUE';
      ALLOW_CONNECT='TRUE';
    'VSS1723':
      PIN_NUMBER='(0,0,0,0,0,0,0,0,0,0,0,0,0,0,0,0,0,0,0,0,0,0,0,0,0,0,0,0,0,0,0~
,0,0,0,0,0,0,0,0,R48,0,0)';
      PINUSE='POWER';
      NO_LOAD_CHECK='Both';
      NO_IO_CHECK='Both';
      NO_ASSERT_CHECK='TRUE';
      NO_DIR_CHECK='TRUE';
      ALLOW_CONNECT='TRUE';
    'VSS1722':
      PIN_NUMBER='(0,0,0,0,0,0,0,0,0,0,0,0,0,0,0,0,0,0,0,0,0,0,0,0,0,0,0,0,0,0,0~
,0,0,0,0,0,0,0,0,P63,0,0)';
      PINUSE='POWER';
      NO_LOAD_CHECK='Both';
      NO_IO_CHECK='Both';
      NO_ASSERT_CHECK='TRUE';
      NO_DIR_CHECK='TRUE';
      ALLOW_CONNECT='TRUE';
    'VSS1721':
      PIN_NUMBER='(0,0,0,0,0,0,0,0,0,0,0,0,0,0,0,0,0,0,0,0,0,0,0,0,0,0,0,0,0,0,0~
,0,0,0,0,0,0,0,0,P59,0,0)';
      PINUSE='POWER';
      NO_LOAD_CHECK='Both';
      NO_IO_CHECK='Both';
      NO_ASSERT_CHECK='TRUE';
      NO_DIR_CHECK='TRUE';
      ALLOW_CONNECT='TRUE';
    'VSS1720':
      PIN_NUMBER='(0,0,0,0,0,0,0,0,0,0,0,0,0,0,0,0,0,0,0,0,0,0,0,0,0,0,0,0,0,0,0~
,0,0,0,0,0,0,0,0,P53,0,0)';
      PINUSE='POWER';
      NO_LOAD_CHECK='Both';
      NO_IO_CHECK='Both';
      NO_ASSERT_CHECK='TRUE';
      NO_DIR_CHECK='TRUE';
      ALLOW_CONNECT='TRUE';
    'VSS1719':
      PIN_NUMBER='(0,0,0,0,0,0,0,0,0,0,0,0,0,0,0,0,0,0,0,0,0,0,0,0,0,0,0,0,0,0,0~
,0,0,0,0,0,0,0,0,P47,0,0)';
      PINUSE='POWER';
      NO_LOAD_CHECK='Both';
      NO_IO_CHECK='Both';
      NO_ASSERT_CHECK='TRUE';
      NO_DIR_CHECK='TRUE';
      ALLOW_CONNECT='TRUE';
    'VSS1718':
      PIN_NUMBER='(0,0,0,0,0,0,0,0,0,0,0,0,0,0,0,0,0,0,0,0,0,0,0,0,0,0,0,0,0,0,0~
,0,0,0,0,0,0,0,0,P44,0,0)';
      PINUSE='POWER';
      NO_LOAD_CHECK='Both';
      NO_IO_CHECK='Both';
      NO_ASSERT_CHECK='TRUE';
      NO_DIR_CHECK='TRUE';
      ALLOW_CONNECT='TRUE';
    'VSS1717':
      PIN_NUMBER='(0,0,0,0,0,0,0,0,0,0,0,0,0,0,0,0,0,0,0,0,0,0,0,0,0,0,0,0,0,0,0~
,0,0,0,0,0,0,0,0,P40,0,0)';
      PINUSE='POWER';
      NO_LOAD_CHECK='Both';
      NO_IO_CHECK='Both';
      NO_ASSERT_CHECK='TRUE';
      NO_DIR_CHECK='TRUE';
      ALLOW_CONNECT='TRUE';
    'VSS1716':
      PIN_NUMBER='(0,0,0,0,0,0,0,0,0,0,0,0,0,0,0,0,0,0,0,0,0,0,0,0,0,0,0,0,0,0,0~
,0,0,0,0,0,0,0,0,P4,0,0)';
      PINUSE='POWER';
      NO_LOAD_CHECK='Both';
      NO_IO_CHECK='Both';
      NO_ASSERT_CHECK='TRUE';
      NO_DIR_CHECK='TRUE';
      ALLOW_CONNECT='TRUE';
    'VSS1715':
      PIN_NUMBER='(0,0,0,0,0,0,0,0,0,0,0,0,0,0,0,0,0,0,0,0,0,0,0,0,0,0,0,0,0,0,0~
,0,0,0,0,0,0,0,0,R23,0,0)';
      PINUSE='POWER';
      NO_LOAD_CHECK='Both';
      NO_IO_CHECK='Both';
      NO_ASSERT_CHECK='TRUE';
      NO_DIR_CHECK='TRUE';
      ALLOW_CONNECT='TRUE';
    'VSS1714':
      PIN_NUMBER='(0,0,0,0,0,0,0,0,0,0,0,0,0,0,0,0,0,0,0,0,0,0,0,0,0,0,0,0,0,0,0~
,0,0,0,0,0,0,0,0,R19,0,0)';
      PINUSE='POWER';
      NO_LOAD_CHECK='Both';
      NO_IO_CHECK='Both';
      NO_ASSERT_CHECK='TRUE';
      NO_DIR_CHECK='TRUE';
      ALLOW_CONNECT='TRUE';
    'VSS1713':
      PIN_NUMBER='(0,0,0,0,0,0,0,0,0,0,0,0,0,0,0,0,0,0,0,0,0,0,0,0,0,0,0,0,0,0,0~
,0,0,0,0,0,0,0,0,P38,0,0)';
      PINUSE='POWER';
      NO_LOAD_CHECK='Both';
      NO_IO_CHECK='Both';
      NO_ASSERT_CHECK='TRUE';
      NO_DIR_CHECK='TRUE';
      ALLOW_CONNECT='TRUE';
    'VSS1712':
      PIN_NUMBER='(0,0,0,0,0,0,0,0,0,0,0,0,0,0,0,0,0,0,0,0,0,0,0,0,0,0,0,0,0,0,0~
,0,0,0,0,0,0,0,0,P34,0,0)';
      PINUSE='POWER';
      NO_LOAD_CHECK='Both';
      NO_IO_CHECK='Both';
      NO_ASSERT_CHECK='TRUE';
      NO_DIR_CHECK='TRUE';
      ALLOW_CONNECT='TRUE';
    'VSS1711':
      PIN_NUMBER='(0,0,0,0,0,0,0,0,0,0,0,0,0,0,0,0,0,0,0,0,0,0,0,0,0,0,0,0,0,0,0~
,0,0,0,0,0,0,0,0,R1,0,0)';
      PINUSE='POWER';
      NO_LOAD_CHECK='Both';
      NO_IO_CHECK='Both';
      NO_ASSERT_CHECK='TRUE';
      NO_DIR_CHECK='TRUE';
      ALLOW_CONNECT='TRUE';
    'VSS1710':
      PIN_NUMBER='(0,0,0,0,0,0,0,0,0,0,0,0,0,0,0,0,0,0,0,0,0,0,0,0,0,0,0,0,0,0,0~
,0,0,0,0,0,0,0,0,P28,0,0)';
      PINUSE='POWER';
      NO_LOAD_CHECK='Both';
      NO_IO_CHECK='Both';
      NO_ASSERT_CHECK='TRUE';
      NO_DIR_CHECK='TRUE';
      ALLOW_CONNECT='TRUE';
    'VSS1709':
      PIN_NUMBER='(0,0,0,0,0,0,0,0,0,0,0,0,0,0,0,0,0,0,0,0,0,0,0,0,0,0,0,0,0,0,0~
,0,0,0,0,0,0,0,0,P26,0,0)';
      PINUSE='POWER';
      NO_LOAD_CHECK='Both';
      NO_IO_CHECK='Both';
      NO_ASSERT_CHECK='TRUE';
      NO_DIR_CHECK='TRUE';
      ALLOW_CONNECT='TRUE';
    'VSS1708':
      PIN_NUMBER='(0,0,0,0,0,0,0,0,0,0,0,0,0,0,0,0,0,0,0,0,0,0,0,0,0,0,0,0,0,0,0~
,0,0,0,0,0,0,0,0,P22,0,0)';
      PINUSE='POWER';
      NO_LOAD_CHECK='Both';
      NO_IO_CHECK='Both';
      NO_ASSERT_CHECK='TRUE';
      NO_DIR_CHECK='TRUE';
      ALLOW_CONNECT='TRUE';
    'VSS1707':
      PIN_NUMBER='(0,0,0,0,0,0,0,0,0,0,0,0,0,0,0,0,0,0,0,0,0,0,0,0,0,0,0,0,0,0,0~
,0,0,0,0,0,0,0,0,P20,0,0)';
      PINUSE='POWER';
      NO_LOAD_CHECK='Both';
      NO_IO_CHECK='Both';
      NO_ASSERT_CHECK='TRUE';
      NO_DIR_CHECK='TRUE';
      ALLOW_CONNECT='TRUE';
    'VSS1706':
      PIN_NUMBER='(0,0,0,0,0,0,0,0,0,0,0,0,0,0,0,0,0,0,0,0,0,0,0,0,0,0,0,0,0,0,0~
,0,0,0,0,0,0,0,0,P16,0,0)';
      PINUSE='POWER';
      NO_LOAD_CHECK='Both';
      NO_IO_CHECK='Both';
      NO_ASSERT_CHECK='TRUE';
      NO_DIR_CHECK='TRUE';
      ALLOW_CONNECT='TRUE';
    'VSS1705':
      PIN_NUMBER='(0,0,0,0,0,0,0,0,0,0,0,0,0,0,0,0,0,0,0,0,0,0,0,0,0,0,0,0,0,0,0~
,0,0,0,0,0,0,0,0,P12,0,0)';
      PINUSE='POWER';
      NO_LOAD_CHECK='Both';
      NO_IO_CHECK='Both';
      NO_ASSERT_CHECK='TRUE';
      NO_DIR_CHECK='TRUE';
      ALLOW_CONNECT='TRUE';
    'VSS1704':
      PIN_NUMBER='(0,0,0,0,0,0,0,0,0,0,0,0,0,0,0,0,0,0,0,0,0,0,0,0,0,0,0,0,0,0,0~
,0,0,0,0,0,0,0,0,P71,0,0)';
      PINUSE='POWER';
      NO_LOAD_CHECK='Both';
      NO_IO_CHECK='Both';
      NO_ASSERT_CHECK='TRUE';
      NO_DIR_CHECK='TRUE';
      ALLOW_CONNECT='TRUE';
    'VSS1703':
      PIN_NUMBER='(0,0,0,0,0,0,0,0,0,0,0,0,0,0,0,0,0,0,0,0,0,0,0,0,0,0,0,0,0,0,0~
,0,0,0,0,0,0,0,0,N88,0,0)';
      PINUSE='POWER';
      NO_LOAD_CHECK='Both';
      NO_IO_CHECK='Both';
      NO_ASSERT_CHECK='TRUE';
      NO_DIR_CHECK='TRUE';
      ALLOW_CONNECT='TRUE';
    'VSS1702':
      PIN_NUMBER='(0,0,0,0,0,0,0,0,0,0,0,0,0,0,0,0,0,0,0,0,0,0,0,0,0,0,0,0,0,0,0~
,0,0,0,0,0,0,0,0,N84,0,0)';
      PINUSE='POWER';
      NO_LOAD_CHECK='Both';
      NO_IO_CHECK='Both';
      NO_ASSERT_CHECK='TRUE';
      NO_DIR_CHECK='TRUE';
      ALLOW_CONNECT='TRUE';
    'VSS1701':
      PIN_NUMBER='(0,0,0,0,0,0,0,0,0,0,0,0,0,0,0,0,0,0,0,0,0,0,0,0,0,0,0,0,0,0,0~
,0,0,0,0,0,0,0,0,N82,0,0)';
      PINUSE='POWER';
      NO_LOAD_CHECK='Both';
      NO_IO_CHECK='Both';
      NO_ASSERT_CHECK='TRUE';
      NO_DIR_CHECK='TRUE';
      ALLOW_CONNECT='TRUE';
    'VSS1700':
      PIN_NUMBER='(0,0,0,0,0,0,0,0,0,0,0,0,0,0,0,0,0,0,0,0,0,0,0,0,0,0,0,0,0,0,0~
,0,0,0,0,0,0,0,0,N80,0,0)';
      PINUSE='POWER';
      NO_LOAD_CHECK='Both';
      NO_IO_CHECK='Both';
      NO_ASSERT_CHECK='TRUE';
      NO_DIR_CHECK='TRUE';
      ALLOW_CONNECT='TRUE';
    'VSS1699':
      PIN_NUMBER='(0,0,0,0,0,0,0,0,0,0,0,0,0,0,0,0,0,0,0,0,0,0,0,0,0,0,0,0,0,0,0~
,0,0,0,0,0,0,0,0,P57,0,0)';
      PINUSE='POWER';
      NO_LOAD_CHECK='Both';
      NO_IO_CHECK='Both';
      NO_ASSERT_CHECK='TRUE';
      NO_DIR_CHECK='TRUE';
      ALLOW_CONNECT='TRUE';
    'VSS1698':
      PIN_NUMBER='(0,0,0,0,0,0,0,0,0,0,0,0,0,0,0,0,0,0,0,0,0,0,0,0,0,0,0,0,0,0,0~
,0,0,0,0,0,0,0,0,N78,0,0)';
      PINUSE='POWER';
      NO_LOAD_CHECK='Both';
      NO_IO_CHECK='Both';
      NO_ASSERT_CHECK='TRUE';
      NO_DIR_CHECK='TRUE';
      ALLOW_CONNECT='TRUE';
    'VSS1697':
      PIN_NUMBER='(0,0,0,0,0,0,0,0,0,0,0,0,0,0,0,0,0,0,0,0,0,0,0,0,0,0,0,0,0,0,0~
,0,0,0,0,0,0,0,0,P51,0,0)';
      PINUSE='POWER';
      NO_LOAD_CHECK='Both';
      NO_IO_CHECK='Both';
      NO_ASSERT_CHECK='TRUE';
      NO_DIR_CHECK='TRUE';
      ALLOW_CONNECT='TRUE';
    'VSS1696':
      PIN_NUMBER='(0,0,0,0,0,0,0,0,0,0,0,0,0,0,0,0,0,0,0,0,0,0,0,0,0,0,0,0,0,0,0~
,0,0,0,0,0,0,0,0,N76,0,0)';
      PINUSE='POWER';
      NO_LOAD_CHECK='Both';
      NO_IO_CHECK='Both';
      NO_ASSERT_CHECK='TRUE';
      NO_DIR_CHECK='TRUE';
      ALLOW_CONNECT='TRUE';
    'VSS1690':
      PIN_NUMBER='(0,0,0,0,0,0,0,0,0,0,0,0,0,0,0,0,0,0,0,0,0,0,0,0,0,0,0,0,0,0,0~
,0,0,0,0,0,0,0,0,P32,0,0)';
      PINUSE='POWER';
      NO_LOAD_CHECK='Both';
      NO_IO_CHECK='Both';
      NO_ASSERT_CHECK='TRUE';
      NO_DIR_CHECK='TRUE';
      ALLOW_CONNECT='TRUE';
    'VSS37':
      PIN_NUMBER='(0,0,0,0,0,0,0,0,0,0,0,0,0,0,0,0,0,0,0,0,0,0,0,0,0,0,0,0,0,0,0~
,0,0,0,0,0,0,0,0,AA80,0,0)';
      PINUSE='POWER';
      NO_LOAD_CHECK='Both';
      NO_IO_CHECK='Both';
      NO_ASSERT_CHECK='TRUE';
      NO_DIR_CHECK='TRUE';
      ALLOW_CONNECT='TRUE';
    'VSS36':
      PIN_NUMBER='(0,0,0,0,0,0,0,0,0,0,0,0,0,0,0,0,0,0,0,0,0,0,0,0,0,0,0,0,0,0,0~
,0,0,0,0,0,0,0,0,AA78,0,0)';
      PINUSE='POWER';
      NO_LOAD_CHECK='Both';
      NO_IO_CHECK='Both';
      NO_ASSERT_CHECK='TRUE';
      NO_DIR_CHECK='TRUE';
      ALLOW_CONNECT='TRUE';
    'VSS35':
      PIN_NUMBER='(0,0,0,0,0,0,0,0,0,0,0,0,0,0,0,0,0,0,0,0,0,0,0,0,0,0,0,0,0,0,0~
,0,0,0,0,0,0,0,0,AA74,0,0)';
      PINUSE='POWER';
      NO_LOAD_CHECK='Both';
      NO_IO_CHECK='Both';
      NO_ASSERT_CHECK='TRUE';
      NO_DIR_CHECK='TRUE';
      ALLOW_CONNECT='TRUE';
    'VSS34':
      PIN_NUMBER='(0,0,0,0,0,0,0,0,0,0,0,0,0,0,0,0,0,0,0,0,0,0,0,0,0,0,0,0,0,0,0~
,0,0,0,0,0,0,0,0,AA72,0,0)';
      PINUSE='POWER';
      NO_LOAD_CHECK='Both';
      NO_IO_CHECK='Both';
      NO_ASSERT_CHECK='TRUE';
      NO_DIR_CHECK='TRUE';
      ALLOW_CONNECT='TRUE';
    'VSS33':
      PIN_NUMBER='(0,0,0,0,0,0,0,0,0,0,0,0,0,0,0,0,0,0,0,0,0,0,0,0,0,0,0,0,0,0,0~
,0,0,0,0,0,0,0,0,AA68,0,0)';
      PINUSE='POWER';
      NO_LOAD_CHECK='Both';
      NO_IO_CHECK='Both';
      NO_ASSERT_CHECK='TRUE';
      NO_DIR_CHECK='TRUE';
      ALLOW_CONNECT='TRUE';
    'VSS32':
      PIN_NUMBER='(0,0,0,0,0,0,0,0,0,0,0,0,0,0,0,0,0,0,0,0,0,0,0,0,0,0,0,0,0,0,0~
,0,0,0,0,0,0,0,0,AA66,0,0)';
      PINUSE='POWER';
      NO_LOAD_CHECK='Both';
      NO_IO_CHECK='Both';
      NO_ASSERT_CHECK='TRUE';
      NO_DIR_CHECK='TRUE';
      ALLOW_CONNECT='TRUE';
    'VSS31':
      PIN_NUMBER='(0,0,0,0,0,0,0,0,0,0,0,0,0,0,0,0,0,0,0,0,0,0,0,0,0,0,0,0,0,0,0~
,0,0,0,0,0,0,0,0,AA62,0,0)';
      PINUSE='POWER';
      NO_LOAD_CHECK='Both';
      NO_IO_CHECK='Both';
      NO_ASSERT_CHECK='TRUE';
      NO_DIR_CHECK='TRUE';
      ALLOW_CONNECT='TRUE';
    'VSS30':
      PIN_NUMBER='(0,0,0,0,0,0,0,0,0,0,0,0,0,0,0,0,0,0,0,0,0,0,0,0,0,0,0,0,0,0,0~
,0,0,0,0,0,0,0,0,AA60,0,0)';
      PINUSE='POWER';
      NO_LOAD_CHECK='Both';
      NO_IO_CHECK='Both';
      NO_ASSERT_CHECK='TRUE';
      NO_DIR_CHECK='TRUE';
      ALLOW_CONNECT='TRUE';
    'VSS29':
      PIN_NUMBER='(0,0,0,0,0,0,0,0,0,0,0,0,0,0,0,0,0,0,0,0,0,0,0,0,0,0,0,0,0,0,0~
,0,0,0,0,0,0,0,0,AA56,0,0)';
      PINUSE='POWER';
      NO_LOAD_CHECK='Both';
      NO_IO_CHECK='Both';
      NO_ASSERT_CHECK='TRUE';
      NO_DIR_CHECK='TRUE';
      ALLOW_CONNECT='TRUE';
    'VSS28':
      PIN_NUMBER='(0,0,0,0,0,0,0,0,0,0,0,0,0,0,0,0,0,0,0,0,0,0,0,0,0,0,0,0,0,0,0~
,0,0,0,0,0,0,0,0,AA54,0,0)';
      PINUSE='POWER';
      NO_LOAD_CHECK='Both';
      NO_IO_CHECK='Both';
      NO_ASSERT_CHECK='TRUE';
      NO_DIR_CHECK='TRUE';
      ALLOW_CONNECT='TRUE';
    'VSS27':
      PIN_NUMBER='(0,0,0,0,0,0,0,0,0,0,0,0,0,0,0,0,0,0,0,0,0,0,0,0,0,0,0,0,0,0,0~
,0,0,0,0,0,0,0,0,AA50,0,0)';
      PINUSE='POWER';
      NO_LOAD_CHECK='Both';
      NO_IO_CHECK='Both';
      NO_ASSERT_CHECK='TRUE';
      NO_DIR_CHECK='TRUE';
      ALLOW_CONNECT='TRUE';
    'VSS26':
      PIN_NUMBER='(0,0,0,0,0,0,0,0,0,0,0,0,0,0,0,0,0,0,0,0,0,0,0,0,0,0,0,0,0,0,0~
,0,0,0,0,0,0,0,0,AA48,0,0)';
      PINUSE='POWER';
      NO_LOAD_CHECK='Both';
      NO_IO_CHECK='Both';
      NO_ASSERT_CHECK='TRUE';
      NO_DIR_CHECK='TRUE';
      ALLOW_CONNECT='TRUE';
    'VSS25':
      PIN_NUMBER='(0,0,0,0,0,0,0,0,0,0,0,0,0,0,0,0,0,0,0,0,0,0,0,0,0,0,0,0,0,0,0~
,0,0,0,0,0,0,0,0,AA43,0,0)';
      PINUSE='POWER';
      NO_LOAD_CHECK='Both';
      NO_IO_CHECK='Both';
      NO_ASSERT_CHECK='TRUE';
      NO_DIR_CHECK='TRUE';
      ALLOW_CONNECT='TRUE';
    'VSS24':
      PIN_NUMBER='(0,0,0,0,0,0,0,0,0,0,0,0,0,0,0,0,0,0,0,0,0,0,0,0,0,0,0,0,0,0,0~
,0,0,0,0,0,0,0,0,AA41,0,0)';
      PINUSE='POWER';
      NO_LOAD_CHECK='Both';
      NO_IO_CHECK='Both';
      NO_ASSERT_CHECK='TRUE';
      NO_DIR_CHECK='TRUE';
      ALLOW_CONNECT='TRUE';
    'VSS23':
      PIN_NUMBER='(0,0,0,0,0,0,0,0,0,0,0,0,0,0,0,0,0,0,0,0,0,0,0,0,0,0,0,0,0,0,0~
,0,0,0,0,0,0,0,0,AA37,0,0)';
      PINUSE='POWER';
      NO_LOAD_CHECK='Both';
      NO_IO_CHECK='Both';
      NO_ASSERT_CHECK='TRUE';
      NO_DIR_CHECK='TRUE';
      ALLOW_CONNECT='TRUE';
    'VSS22':
      PIN_NUMBER='(0,0,0,0,0,0,0,0,0,0,0,0,0,0,0,0,0,0,0,0,0,0,0,0,0,0,0,0,0,0,0~
,0,0,0,0,0,0,0,0,AA35,0,0)';
      PINUSE='POWER';
      NO_LOAD_CHECK='Both';
      NO_IO_CHECK='Both';
      NO_ASSERT_CHECK='TRUE';
      NO_DIR_CHECK='TRUE';
      ALLOW_CONNECT='TRUE';
    'VSS21':
      PIN_NUMBER='(0,0,0,0,0,0,0,0,0,0,0,0,0,0,0,0,0,0,0,0,0,0,0,0,0,0,0,0,0,0,0~
,0,0,0,0,0,0,0,0,AA31,0,0)';
      PINUSE='POWER';
      NO_LOAD_CHECK='Both';
      NO_IO_CHECK='Both';
      NO_ASSERT_CHECK='TRUE';
      NO_DIR_CHECK='TRUE';
      ALLOW_CONNECT='TRUE';
    'VSS20':
      PIN_NUMBER='(0,0,0,0,0,0,0,0,0,0,0,0,0,0,0,0,0,0,0,0,0,0,0,0,0,0,0,0,0,0,0~
,0,0,0,0,0,0,0,0,AA29,0,0)';
      PINUSE='POWER';
      NO_LOAD_CHECK='Both';
      NO_IO_CHECK='Both';
      NO_ASSERT_CHECK='TRUE';
      NO_DIR_CHECK='TRUE';
      ALLOW_CONNECT='TRUE';
    'VSS19':
      PIN_NUMBER='(0,0,0,0,0,0,0,0,0,0,0,0,0,0,0,0,0,0,0,0,0,0,0,0,0,0,0,0,0,0,0~
,0,0,0,0,0,0,0,0,AA25,0,0)';
      PINUSE='POWER';
      NO_LOAD_CHECK='Both';
      NO_IO_CHECK='Both';
      NO_ASSERT_CHECK='TRUE';
      NO_DIR_CHECK='TRUE';
      ALLOW_CONNECT='TRUE';
    'VSS18':
      PIN_NUMBER='(0,0,0,0,0,0,0,0,0,0,0,0,0,0,0,0,0,0,0,0,0,0,0,0,0,0,0,0,0,0,0~
,0,0,0,0,0,0,0,0,AA23,0,0)';
      PINUSE='POWER';
      NO_LOAD_CHECK='Both';
      NO_IO_CHECK='Both';
      NO_ASSERT_CHECK='TRUE';
      NO_DIR_CHECK='TRUE';
      ALLOW_CONNECT='TRUE';
    'VSS17':
      PIN_NUMBER='(0,0,0,0,0,0,0,0,0,0,0,0,0,0,0,0,0,0,0,0,0,0,0,0,0,0,0,0,0,0,0~
,0,0,0,0,0,0,0,0,AA19,0,0)';
      PINUSE='POWER';
      NO_LOAD_CHECK='Both';
      NO_IO_CHECK='Both';
      NO_ASSERT_CHECK='TRUE';
      NO_DIR_CHECK='TRUE';
      ALLOW_CONNECT='TRUE';
    'VSS1695':
      PIN_NUMBER='(0,0,0,0,0,0,0,0,0,0,0,0,0,0,0,0,0,0,0,0,0,0,0,0,0,0,0,0,0,0,0~
,0,0,0,0,0,0,0,0,0,N70,0)';
      PINUSE='POWER';
      NO_LOAD_CHECK='Both';
      NO_IO_CHECK='Both';
      NO_ASSERT_CHECK='TRUE';
      NO_DIR_CHECK='TRUE';
      ALLOW_CONNECT='TRUE';
    'VSS1694':
      PIN_NUMBER='(0,0,0,0,0,0,0,0,0,0,0,0,0,0,0,0,0,0,0,0,0,0,0,0,0,0,0,0,0,0,0~
,0,0,0,0,0,0,0,0,0,N58,0)';
      PINUSE='POWER';
      NO_LOAD_CHECK='Both';
      NO_IO_CHECK='Both';
      NO_ASSERT_CHECK='TRUE';
      NO_DIR_CHECK='TRUE';
      ALLOW_CONNECT='TRUE';
    'VSS1693':
      PIN_NUMBER='(0,0,0,0,0,0,0,0,0,0,0,0,0,0,0,0,0,0,0,0,0,0,0,0,0,0,0,0,0,0,0~
,0,0,0,0,0,0,0,0,0,N52,0)';
      PINUSE='POWER';
      NO_LOAD_CHECK='Both';
      NO_IO_CHECK='Both';
      NO_ASSERT_CHECK='TRUE';
      NO_DIR_CHECK='TRUE';
      ALLOW_CONNECT='TRUE';
    'VSS1692':
      PIN_NUMBER='(0,0,0,0,0,0,0,0,0,0,0,0,0,0,0,0,0,0,0,0,0,0,0,0,0,0,0,0,0,0,0~
,0,0,0,0,0,0,0,0,0,N45,0)';
      PINUSE='POWER';
      NO_LOAD_CHECK='Both';
      NO_IO_CHECK='Both';
      NO_ASSERT_CHECK='TRUE';
      NO_DIR_CHECK='TRUE';
      ALLOW_CONNECT='TRUE';
    'VSS1691':
      PIN_NUMBER='(0,0,0,0,0,0,0,0,0,0,0,0,0,0,0,0,0,0,0,0,0,0,0,0,0,0,0,0,0,0,0~
,0,0,0,0,0,0,0,0,0,N33,0)';
      PINUSE='POWER';
      NO_LOAD_CHECK='Both';
      NO_IO_CHECK='Both';
      NO_ASSERT_CHECK='TRUE';
      NO_DIR_CHECK='TRUE';
      ALLOW_CONNECT='TRUE';
    'VSS1689':
      PIN_NUMBER='(0,0,0,0,0,0,0,0,0,0,0,0,0,0,0,0,0,0,0,0,0,0,0,0,0,0,0,0,0,0,0~
,0,0,0,0,0,0,0,0,0,N27,0)';
      PINUSE='POWER';
      NO_LOAD_CHECK='Both';
      NO_IO_CHECK='Both';
      NO_ASSERT_CHECK='TRUE';
      NO_DIR_CHECK='TRUE';
      ALLOW_CONNECT='TRUE';
    'VSS1688':
      PIN_NUMBER='(0,0,0,0,0,0,0,0,0,0,0,0,0,0,0,0,0,0,0,0,0,0,0,0,0,0,0,0,0,0,0~
,0,0,0,0,0,0,0,0,0,N15,0)';
      PINUSE='POWER';
      NO_LOAD_CHECK='Both';
      NO_IO_CHECK='Both';
      NO_ASSERT_CHECK='TRUE';
      NO_DIR_CHECK='TRUE';
      ALLOW_CONNECT='TRUE';
    'VSS1687':
      PIN_NUMBER='(0,0,0,0,0,0,0,0,0,0,0,0,0,0,0,0,0,0,0,0,0,0,0,0,0,0,0,0,0,0,0~
,0,0,0,0,0,0,0,0,0,M83,0)';
      PINUSE='POWER';
      NO_LOAD_CHECK='Both';
      NO_IO_CHECK='Both';
      NO_ASSERT_CHECK='TRUE';
      NO_DIR_CHECK='TRUE';
      ALLOW_CONNECT='TRUE';
    'VSS1686':
      PIN_NUMBER='(0,0,0,0,0,0,0,0,0,0,0,0,0,0,0,0,0,0,0,0,0,0,0,0,0,0,0,0,0,0,0~
,0,0,0,0,0,0,0,0,0,M81,0)';
      PINUSE='POWER';
      NO_LOAD_CHECK='Both';
      NO_IO_CHECK='Both';
      NO_ASSERT_CHECK='TRUE';
      NO_DIR_CHECK='TRUE';
      ALLOW_CONNECT='TRUE';
    'VSS1685':
      PIN_NUMBER='(0,0,0,0,0,0,0,0,0,0,0,0,0,0,0,0,0,0,0,0,0,0,0,0,0,0,0,0,0,0,0~
,0,0,0,0,0,0,0,0,0,L78,0)';
      PINUSE='POWER';
      NO_LOAD_CHECK='Both';
      NO_IO_CHECK='Both';
      NO_ASSERT_CHECK='TRUE';
      NO_DIR_CHECK='TRUE';
      ALLOW_CONNECT='TRUE';
    'VSS1684':
      PIN_NUMBER='(0,0,0,0,0,0,0,0,0,0,0,0,0,0,0,0,0,0,0,0,0,0,0,0,0,0,0,0,0,0,0~
,0,0,0,0,0,0,0,0,0,L76,0)';
      PINUSE='POWER';
      NO_LOAD_CHECK='Both';
      NO_IO_CHECK='Both';
      NO_ASSERT_CHECK='TRUE';
      NO_DIR_CHECK='TRUE';
      ALLOW_CONNECT='TRUE';
    'VSS1683':
      PIN_NUMBER='(0,0,0,0,0,0,0,0,0,0,0,0,0,0,0,0,0,0,0,0,0,0,0,0,0,0,0,0,0,0,0~
,0,0,0,0,0,0,0,0,0,L74,0)';
      PINUSE='POWER';
      NO_LOAD_CHECK='Both';
      NO_IO_CHECK='Both';
      NO_ASSERT_CHECK='TRUE';
      NO_DIR_CHECK='TRUE';
      ALLOW_CONNECT='TRUE';
    'VSS1682':
      PIN_NUMBER='(0,0,0,0,0,0,0,0,0,0,0,0,0,0,0,0,0,0,0,0,0,0,0,0,0,0,0,0,0,0,0~
,0,0,0,0,0,0,0,0,0,L72,0)';
      PINUSE='POWER';
      NO_LOAD_CHECK='Both';
      NO_IO_CHECK='Both';
      NO_ASSERT_CHECK='TRUE';
      NO_DIR_CHECK='TRUE';
      ALLOW_CONNECT='TRUE';
    'VSS1681':
      PIN_NUMBER='(0,0,0,0,0,0,0,0,0,0,0,0,0,0,0,0,0,0,0,0,0,0,0,0,0,0,0,0,0,0,0~
,0,0,0,0,0,0,0,0,0,L68,0)';
      PINUSE='POWER';
      NO_LOAD_CHECK='Both';
      NO_IO_CHECK='Both';
      NO_ASSERT_CHECK='TRUE';
      NO_DIR_CHECK='TRUE';
      ALLOW_CONNECT='TRUE';
    'VSS1680':
      PIN_NUMBER='(0,0,0,0,0,0,0,0,0,0,0,0,0,0,0,0,0,0,0,0,0,0,0,0,0,0,0,0,0,0,0~
,0,0,0,0,0,0,0,0,0,L66,0)';
      PINUSE='POWER';
      NO_LOAD_CHECK='Both';
      NO_IO_CHECK='Both';
      NO_ASSERT_CHECK='TRUE';
      NO_DIR_CHECK='TRUE';
      ALLOW_CONNECT='TRUE';
    'VSS1679':
      PIN_NUMBER='(0,0,0,0,0,0,0,0,0,0,0,0,0,0,0,0,0,0,0,0,0,0,0,0,0,0,0,0,0,0,0~
,0,0,0,0,0,0,0,0,0,L64,0)';
      PINUSE='POWER';
      NO_LOAD_CHECK='Both';
      NO_IO_CHECK='Both';
      NO_ASSERT_CHECK='TRUE';
      NO_DIR_CHECK='TRUE';
      ALLOW_CONNECT='TRUE';
    'VSS1678':
      PIN_NUMBER='(0,0,0,0,0,0,0,0,0,0,0,0,0,0,0,0,0,0,0,0,0,0,0,0,0,0,0,0,0,0,0~
,0,0,0,0,0,0,0,0,0,L62,0)';
      PINUSE='POWER';
      NO_LOAD_CHECK='Both';
      NO_IO_CHECK='Both';
      NO_ASSERT_CHECK='TRUE';
      NO_DIR_CHECK='TRUE';
      ALLOW_CONNECT='TRUE';
    'VSS1677':
      PIN_NUMBER='(0,0,0,0,0,0,0,0,0,0,0,0,0,0,0,0,0,0,0,0,0,0,0,0,0,0,0,0,0,0,0~
,0,0,0,0,0,0,0,0,0,L60,0)';
      PINUSE='POWER';
      NO_LOAD_CHECK='Both';
      NO_IO_CHECK='Both';
      NO_ASSERT_CHECK='TRUE';
      NO_DIR_CHECK='TRUE';
      ALLOW_CONNECT='TRUE';
    'VSS1676':
      PIN_NUMBER='(0,0,0,0,0,0,0,0,0,0,0,0,0,0,0,0,0,0,0,0,0,0,0,0,0,0,0,0,0,0,0~
,0,0,0,0,0,0,0,0,0,L56,0)';
      PINUSE='POWER';
      NO_LOAD_CHECK='Both';
      NO_IO_CHECK='Both';
      NO_ASSERT_CHECK='TRUE';
      NO_DIR_CHECK='TRUE';
      ALLOW_CONNECT='TRUE';
    'VSS1675':
      PIN_NUMBER='(0,0,0,0,0,0,0,0,0,0,0,0,0,0,0,0,0,0,0,0,0,0,0,0,0,0,0,0,0,0,0~
,0,0,0,0,0,0,0,0,0,N64,0)';
      PINUSE='POWER';
      NO_LOAD_CHECK='Both';
      NO_IO_CHECK='Both';
      NO_ASSERT_CHECK='TRUE';
      NO_DIR_CHECK='TRUE';
      ALLOW_CONNECT='TRUE';
    'VSS1674':
      PIN_NUMBER='(0,0,0,0,0,0,0,0,0,0,0,0,0,0,0,0,0,0,0,0,0,0,0,0,0,0,0,0,0,0,0~
,0,0,0,0,0,0,0,0,0,L54,0)';
      PINUSE='POWER';
      NO_LOAD_CHECK='Both';
      NO_IO_CHECK='Both';
      NO_ASSERT_CHECK='TRUE';
      NO_DIR_CHECK='TRUE';
      ALLOW_CONNECT='TRUE';
    'VSS1673':
      PIN_NUMBER='(0,0,0,0,0,0,0,0,0,0,0,0,0,0,0,0,0,0,0,0,0,0,0,0,0,0,0,0,0,0,0~
,0,0,0,0,0,0,0,0,0,L52,0)';
      PINUSE='POWER';
      NO_LOAD_CHECK='Both';
      NO_IO_CHECK='Both';
      NO_ASSERT_CHECK='TRUE';
      NO_DIR_CHECK='TRUE';
      ALLOW_CONNECT='TRUE';
    'VSS1672':
      PIN_NUMBER='(0,0,0,0,0,0,0,0,0,0,0,0,0,0,0,0,0,0,0,0,0,0,0,0,0,0,0,0,0,0,0~
,0,0,0,0,0,0,0,0,0,L50,0)';
      PINUSE='POWER';
      NO_LOAD_CHECK='Both';
      NO_IO_CHECK='Both';
      NO_ASSERT_CHECK='TRUE';
      NO_DIR_CHECK='TRUE';
      ALLOW_CONNECT='TRUE';
    'VSS1671':
      PIN_NUMBER='(0,0,0,0,0,0,0,0,0,0,0,0,0,0,0,0,0,0,0,0,0,0,0,0,0,0,0,0,0,0,0~
,0,0,0,0,0,0,0,0,0,L5,0)';
      PINUSE='POWER';
      NO_LOAD_CHECK='Both';
      NO_IO_CHECK='Both';
      NO_ASSERT_CHECK='TRUE';
      NO_DIR_CHECK='TRUE';
      ALLOW_CONNECT='TRUE';
    'VSS1670':
      PIN_NUMBER='(0,0,0,0,0,0,0,0,0,0,0,0,0,0,0,0,0,0,0,0,0,0,0,0,0,0,0,0,0,0,0~
,0,0,0,0,0,0,0,0,0,L48,0)';
      PINUSE='POWER';
      NO_LOAD_CHECK='Both';
      NO_IO_CHECK='Both';
      NO_ASSERT_CHECK='TRUE';
      NO_DIR_CHECK='TRUE';
      ALLOW_CONNECT='TRUE';
    'VSS1669':
      PIN_NUMBER='(0,0,0,0,0,0,0,0,0,0,0,0,0,0,0,0,0,0,0,0,0,0,0,0,0,0,0,0,0,0,0~
,0,0,0,0,0,0,0,0,0,N39,0)';
      PINUSE='POWER';
      NO_LOAD_CHECK='Both';
      NO_IO_CHECK='Both';
      NO_ASSERT_CHECK='TRUE';
      NO_DIR_CHECK='TRUE';
      ALLOW_CONNECT='TRUE';
    'VSS1668':
      PIN_NUMBER='(0,0,0,0,0,0,0,0,0,0,0,0,0,0,0,0,0,0,0,0,0,0,0,0,0,0,0,0,0,0,0~
,0,0,0,0,0,0,0,0,0,L45,0)';
      PINUSE='POWER';
      NO_LOAD_CHECK='Both';
      NO_IO_CHECK='Both';
      NO_ASSERT_CHECK='TRUE';
      NO_DIR_CHECK='TRUE';
      ALLOW_CONNECT='TRUE';
    'VSS1667':
      PIN_NUMBER='(0,0,0,0,0,0,0,0,0,0,0,0,0,0,0,0,0,0,0,0,0,0,0,0,0,0,0,0,0,0,0~
,0,0,0,0,0,0,0,0,0,L43,0)';
      PINUSE='POWER';
      NO_LOAD_CHECK='Both';
      NO_IO_CHECK='Both';
      NO_ASSERT_CHECK='TRUE';
      NO_DIR_CHECK='TRUE';
      ALLOW_CONNECT='TRUE';
    'VSS1666':
      PIN_NUMBER='(0,0,0,0,0,0,0,0,0,0,0,0,0,0,0,0,0,0,0,0,0,0,0,0,0,0,0,0,0,0,0~
,0,0,0,0,0,0,0,0,0,L41,0)';
      PINUSE='POWER';
      NO_LOAD_CHECK='Both';
      NO_IO_CHECK='Both';
      NO_ASSERT_CHECK='TRUE';
      NO_DIR_CHECK='TRUE';
      ALLOW_CONNECT='TRUE';
    'VSS1665':
      PIN_NUMBER='(0,0,0,0,0,0,0,0,0,0,0,0,0,0,0,0,0,0,0,0,0,0,0,0,0,0,0,0,0,0,0~
,0,0,0,0,0,0,0,0,0,L39,0)';
      PINUSE='POWER';
      NO_LOAD_CHECK='Both';
      NO_IO_CHECK='Both';
      NO_ASSERT_CHECK='TRUE';
      NO_DIR_CHECK='TRUE';
      ALLOW_CONNECT='TRUE';
    'VSS1664':
      PIN_NUMBER='(0,0,0,0,0,0,0,0,0,0,0,0,0,0,0,0,0,0,0,0,0,0,0,0,0,0,0,0,0,0,0~
,0,0,0,0,0,0,0,0,0,N21,0)';
      PINUSE='POWER';
      NO_LOAD_CHECK='Both';
      NO_IO_CHECK='Both';
      NO_ASSERT_CHECK='TRUE';
      NO_DIR_CHECK='TRUE';
      ALLOW_CONNECT='TRUE';
    'VSS1663':
      PIN_NUMBER='(0,0,0,0,0,0,0,0,0,0,0,0,0,0,0,0,0,0,0,0,0,0,0,0,0,0,0,0,0,0,0~
,0,0,0,0,0,0,0,0,0,L37,0)';
      PINUSE='POWER';
      NO_LOAD_CHECK='Both';
      NO_IO_CHECK='Both';
      NO_ASSERT_CHECK='TRUE';
      NO_DIR_CHECK='TRUE';
      ALLOW_CONNECT='TRUE';
    'VSS1662':
      PIN_NUMBER='(0,0,0,0,0,0,0,0,0,0,0,0,0,0,0,0,0,0,0,0,0,0,0,0,0,0,0,0,0,0,0~
,0,0,0,0,0,0,0,0,0,L35,0)';
      PINUSE='POWER';
      NO_LOAD_CHECK='Both';
      NO_IO_CHECK='Both';
      NO_ASSERT_CHECK='TRUE';
      NO_DIR_CHECK='TRUE';
      ALLOW_CONNECT='TRUE';
    'VSS1661':
      PIN_NUMBER='(0,0,0,0,0,0,0,0,0,0,0,0,0,0,0,0,0,0,0,0,0,0,0,0,0,0,0,0,0,0,0~
,0,0,0,0,0,0,0,0,0,L33,0)';
      PINUSE='POWER';
      NO_LOAD_CHECK='Both';
      NO_IO_CHECK='Both';
      NO_ASSERT_CHECK='TRUE';
      NO_DIR_CHECK='TRUE';
      ALLOW_CONNECT='TRUE';
    'VSS1660':
      PIN_NUMBER='(0,0,0,0,0,0,0,0,0,0,0,0,0,0,0,0,0,0,0,0,0,0,0,0,0,0,0,0,0,0,0~
,0,0,0,0,0,0,0,0,0,L31,0)';
      PINUSE='POWER';
      NO_LOAD_CHECK='Both';
      NO_IO_CHECK='Both';
      NO_ASSERT_CHECK='TRUE';
      NO_DIR_CHECK='TRUE';
      ALLOW_CONNECT='TRUE';
    'VSS1659':
      PIN_NUMBER='(0,0,0,0,0,0,0,0,0,0,0,0,0,0,0,0,0,0,0,0,0,0,0,0,0,0,0,0,0,0,0~
,0,0,0,0,0,0,0,0,0,L29,0)';
      PINUSE='POWER';
      NO_LOAD_CHECK='Both';
      NO_IO_CHECK='Both';
      NO_ASSERT_CHECK='TRUE';
      NO_DIR_CHECK='TRUE';
      ALLOW_CONNECT='TRUE';
    'VSS1658':
      PIN_NUMBER='(0,0,0,0,0,0,0,0,0,0,0,0,0,0,0,0,0,0,0,0,0,0,0,0,0,0,0,0,0,0,0~
,0,0,0,0,0,0,0,0,0,L27,0)';
      PINUSE='POWER';
      NO_LOAD_CHECK='Both';
      NO_IO_CHECK='Both';
      NO_ASSERT_CHECK='TRUE';
      NO_DIR_CHECK='TRUE';
      ALLOW_CONNECT='TRUE';
    'VSS1657':
      PIN_NUMBER='(0,0,0,0,0,0,0,0,0,0,0,0,0,0,0,0,0,0,0,0,0,0,0,0,0,0,0,0,0,0,0~
,0,0,0,0,0,0,0,0,0,M8,0)';
      PINUSE='POWER';
      NO_LOAD_CHECK='Both';
      NO_IO_CHECK='Both';
      NO_ASSERT_CHECK='TRUE';
      NO_DIR_CHECK='TRUE';
      ALLOW_CONNECT='TRUE';
    'VSS1656':
      PIN_NUMBER='(0,0,0,0,0,0,0,0,0,0,0,0,0,0,0,0,0,0,0,0,0,0,0,0,0,0,0,0,0,0,0~
,0,0,0,0,0,0,0,0,0,L25,0)';
      PINUSE='POWER';
      NO_LOAD_CHECK='Both';
      NO_IO_CHECK='Both';
      NO_ASSERT_CHECK='TRUE';
      NO_DIR_CHECK='TRUE';
      ALLOW_CONNECT='TRUE';
    'VSS1655':
      PIN_NUMBER='(0,0,0,0,0,0,0,0,0,0,0,0,0,0,0,0,0,0,0,0,0,0,0,0,0,0,0,0,0,0,0~
,0,0,0,0,0,0,0,0,0,L23,0)';
      PINUSE='POWER';
      NO_LOAD_CHECK='Both';
      NO_IO_CHECK='Both';
      NO_ASSERT_CHECK='TRUE';
      NO_DIR_CHECK='TRUE';
      ALLOW_CONNECT='TRUE';
    'VSS1654':
      PIN_NUMBER='(0,0,0,0,0,0,0,0,0,0,0,0,0,0,0,0,0,0,0,0,0,0,0,0,0,0,0,0,0,0,0~
,0,0,0,0,0,0,0,0,0,M49,0)';
      PINUSE='POWER';
      NO_LOAD_CHECK='Both';
      NO_IO_CHECK='Both';
      NO_ASSERT_CHECK='TRUE';
      NO_DIR_CHECK='TRUE';
      ALLOW_CONNECT='TRUE';
    'VSS1653':
      PIN_NUMBER='(0,0,0,0,0,0,0,0,0,0,0,0,0,0,0,0,0,0,0,0,0,0,0,0,0,0,0,0,0,0,0~
,0,0,0,0,0,0,0,0,0,M42,0)';
      PINUSE='POWER';
      NO_LOAD_CHECK='Both';
      NO_IO_CHECK='Both';
      NO_ASSERT_CHECK='TRUE';
      NO_DIR_CHECK='TRUE';
      ALLOW_CONNECT='TRUE';
    'VSS1652':
      PIN_NUMBER='(0,0,0,0,0,0,0,0,0,0,0,0,0,0,0,0,0,0,0,0,0,0,0,0,0,0,0,0,0,0,0~
,0,0,0,0,0,0,0,0,0,M4,0)';
      PINUSE='POWER';
      NO_LOAD_CHECK='Both';
      NO_IO_CHECK='Both';
      NO_ASSERT_CHECK='TRUE';
      NO_DIR_CHECK='TRUE';
      ALLOW_CONNECT='TRUE';
    'VSS1651':
      PIN_NUMBER='(0,0,0,0,0,0,0,0,0,0,0,0,0,0,0,0,0,0,0,0,0,0,0,0,0,0,0,0,0,0,0~
,0,0,0,0,0,0,0,0,0,L21,0)';
      PINUSE='POWER';
      NO_LOAD_CHECK='Both';
      NO_IO_CHECK='Both';
      NO_ASSERT_CHECK='TRUE';
      NO_DIR_CHECK='TRUE';
      ALLOW_CONNECT='TRUE';
    'VSS1650':
      PIN_NUMBER='(0,0,0,0,0,0,0,0,0,0,0,0,0,0,0,0,0,0,0,0,0,0,0,0,0,0,0,0,0,0,0~
,0,0,0,0,0,0,0,0,0,L17,0)';
      PINUSE='POWER';
      NO_LOAD_CHECK='Both';
      NO_IO_CHECK='Both';
      NO_ASSERT_CHECK='TRUE';
      NO_DIR_CHECK='TRUE';
      ALLOW_CONNECT='TRUE';
    'VSS1649':
      PIN_NUMBER='(0,0,0,0,0,0,0,0,0,0,0,0,0,0,0,0,0,0,0,0,0,0,0,0,0,0,0,0,0,0,0~
,0,0,0,0,0,0,0,0,0,M12,0)';
      PINUSE='POWER';
      NO_LOAD_CHECK='Both';
      NO_IO_CHECK='Both';
      NO_ASSERT_CHECK='TRUE';
      NO_DIR_CHECK='TRUE';
      ALLOW_CONNECT='TRUE';
    'VSS1648':
      PIN_NUMBER='(0,0,0,0,0,0,0,0,0,0,0,0,0,0,0,0,0,0,0,0,0,0,0,0,0,0,0,0,0,0,0~
,0,0,0,0,0,0,0,0,0,L90,0)';
      PINUSE='POWER';
      NO_LOAD_CHECK='Both';
      NO_IO_CHECK='Both';
      NO_ASSERT_CHECK='TRUE';
      NO_DIR_CHECK='TRUE';
      ALLOW_CONNECT='TRUE';
    'VSS1647':
      PIN_NUMBER='(0,0,0,0,0,0,0,0,0,0,0,0,0,0,0,0,0,0,0,0,0,0,0,0,0,0,0,0,0,0,0~
,0,0,0,0,0,0,0,0,0,L9,0)';
      PINUSE='POWER';
      NO_LOAD_CHECK='Both';
      NO_IO_CHECK='Both';
      NO_ASSERT_CHECK='TRUE';
      NO_DIR_CHECK='TRUE';
      ALLOW_CONNECT='TRUE';
    'VSS1646':
      PIN_NUMBER='(0,0,0,0,0,0,0,0,0,0,0,0,0,0,0,0,0,0,0,0,0,0,0,0,0,0,0,0,0,0,0~
,0,0,0,0,0,0,0,0,0,L88,0)';
      PINUSE='POWER';
      NO_LOAD_CHECK='Both';
      NO_IO_CHECK='Both';
      NO_ASSERT_CHECK='TRUE';
      NO_DIR_CHECK='TRUE';
      ALLOW_CONNECT='TRUE';
    'VSS1645':
      PIN_NUMBER='(0,0,0,0,0,0,0,0,0,0,0,0,0,0,0,0,0,0,0,0,0,0,0,0,0,0,0,0,0,0,0~
,0,0,0,0,0,0,0,0,0,L15,0)';
      PINUSE='POWER';
      NO_LOAD_CHECK='Both';
      NO_IO_CHECK='Both';
      NO_ASSERT_CHECK='TRUE';
      NO_DIR_CHECK='TRUE';
      ALLOW_CONNECT='TRUE';
    'VSS1644':
      PIN_NUMBER='(0,0,0,0,0,0,0,0,0,0,0,0,0,0,0,0,0,0,0,0,0,0,0,0,0,0,0,0,0,0,0~
,0,0,0,0,0,0,0,0,0,L13,0)';
      PINUSE='POWER';
      NO_LOAD_CHECK='Both';
      NO_IO_CHECK='Both';
      NO_ASSERT_CHECK='TRUE';
      NO_DIR_CHECK='TRUE';
      ALLOW_CONNECT='TRUE';
    'VSS1643':
      PIN_NUMBER='(0,0,0,0,0,0,0,0,0,0,0,0,0,0,0,0,0,0,0,0,0,0,0,0,0,0,0,0,0,0,0~
,0,0,0,0,0,0,0,0,0,K85,0)';
      PINUSE='POWER';
      NO_LOAD_CHECK='Both';
      NO_IO_CHECK='Both';
      NO_ASSERT_CHECK='TRUE';
      NO_DIR_CHECK='TRUE';
      ALLOW_CONNECT='TRUE';
    'VSS1642':
      PIN_NUMBER='(0,0,0,0,0,0,0,0,0,0,0,0,0,0,0,0,0,0,0,0,0,0,0,0,0,0,0,0,0,0,0~
,0,0,0,0,0,0,0,0,0,K83,0)';
      PINUSE='POWER';
      NO_LOAD_CHECK='Both';
      NO_IO_CHECK='Both';
      NO_ASSERT_CHECK='TRUE';
      NO_DIR_CHECK='TRUE';
      ALLOW_CONNECT='TRUE';
    'VSS1641':
      PIN_NUMBER='(0,0,0,0,0,0,0,0,0,0,0,0,0,0,0,0,0,0,0,0,0,0,0,0,0,0,0,0,0,0,0~
,0,0,0,0,0,0,0,0,0,K8,0)';
      PINUSE='POWER';
      NO_LOAD_CHECK='Both';
      NO_IO_CHECK='Both';
      NO_ASSERT_CHECK='TRUE';
      NO_DIR_CHECK='TRUE';
      ALLOW_CONNECT='TRUE';
    'VSS1640':
      PIN_NUMBER='(0,0,0,0,0,0,0,0,0,0,0,0,0,0,0,0,0,0,0,0,0,0,0,0,0,0,0,0,0,0,0~
,0,0,0,0,0,0,0,0,0,L70,0)';
      PINUSE='POWER';
      NO_LOAD_CHECK='Both';
      NO_IO_CHECK='Both';
      NO_ASSERT_CHECK='TRUE';
      NO_DIR_CHECK='TRUE';
      ALLOW_CONNECT='TRUE';
    'VSS1639':
      PIN_NUMBER='(0,0,0,0,0,0,0,0,0,0,0,0,0,0,0,0,0,0,0,0,0,0,0,0,0,0,0,0,0,0,0~
,0,0,0,0,0,0,0,0,0,K77,0)';
      PINUSE='POWER';
      NO_LOAD_CHECK='Both';
      NO_IO_CHECK='Both';
      NO_ASSERT_CHECK='TRUE';
      NO_DIR_CHECK='TRUE';
      ALLOW_CONNECT='TRUE';
    'VSS1638':
      PIN_NUMBER='(0,0,0,0,0,0,0,0,0,0,0,0,0,0,0,0,0,0,0,0,0,0,0,0,0,0,0,0,0,0,0~
,0,0,0,0,0,0,0,0,0,J86,0)';
      PINUSE='POWER';
      NO_LOAD_CHECK='Both';
      NO_IO_CHECK='Both';
      NO_ASSERT_CHECK='TRUE';
      NO_DIR_CHECK='TRUE';
      ALLOW_CONNECT='TRUE';
    'VSS1637':
      PIN_NUMBER='(0,0,0,0,0,0,0,0,0,0,0,0,0,0,0,0,0,0,0,0,0,0,0,0,0,0,0,0,0,0,0~
,0,0,0,0,0,0,0,0,0,J84,0)';
      PINUSE='POWER';
      NO_LOAD_CHECK='Both';
      NO_IO_CHECK='Both';
      NO_ASSERT_CHECK='TRUE';
      NO_DIR_CHECK='TRUE';
      ALLOW_CONNECT='TRUE';
    'VSS1636':
      PIN_NUMBER='(0,0,0,0,0,0,0,0,0,0,0,0,0,0,0,0,0,0,0,0,0,0,0,0,0,0,0,0,0,0,0~
,0,0,0,0,0,0,0,0,0,J78,0)';
      PINUSE='POWER';
      NO_LOAD_CHECK='Both';
      NO_IO_CHECK='Both';
      NO_ASSERT_CHECK='TRUE';
      NO_DIR_CHECK='TRUE';
      ALLOW_CONNECT='TRUE';
    'VSS1635':
      PIN_NUMBER='(0,0,0,0,0,0,0,0,0,0,0,0,0,0,0,0,0,0,0,0,0,0,0,0,0,0,0,0,0,0,0~
,0,0,0,0,0,0,0,0,0,J76,0)';
      PINUSE='POWER';
      NO_LOAD_CHECK='Both';
      NO_IO_CHECK='Both';
      NO_ASSERT_CHECK='TRUE';
      NO_DIR_CHECK='TRUE';
      ALLOW_CONNECT='TRUE';
    'VSS1634':
      PIN_NUMBER='(0,0,0,0,0,0,0,0,0,0,0,0,0,0,0,0,0,0,0,0,0,0,0,0,0,0,0,0,0,0,0~
,0,0,0,0,0,0,0,0,0,L58,0)';
      PINUSE='POWER';
      NO_LOAD_CHECK='Both';
      NO_IO_CHECK='Both';
      NO_ASSERT_CHECK='TRUE';
      NO_DIR_CHECK='TRUE';
      ALLOW_CONNECT='TRUE';
    'VSS1633':
      PIN_NUMBER='(0,0,0,0,0,0,0,0,0,0,0,0,0,0,0,0,0,0,0,0,0,0,0,0,0,0,0,0,0,0,0~
,0,0,0,0,0,0,0,0,0,J58,0)';
      PINUSE='POWER';
      NO_LOAD_CHECK='Both';
      NO_IO_CHECK='Both';
      NO_ASSERT_CHECK='TRUE';
      NO_DIR_CHECK='TRUE';
      ALLOW_CONNECT='TRUE';
    'VSS1632':
      PIN_NUMBER='(0,0,0,0,0,0,0,0,0,0,0,0,0,0,0,0,0,0,0,0,0,0,0,0,0,0,0,0,0,0,0~
,0,0,0,0,0,0,0,0,0,J52,0)';
      PINUSE='POWER';
      NO_LOAD_CHECK='Both';
      NO_IO_CHECK='Both';
      NO_ASSERT_CHECK='TRUE';
      NO_DIR_CHECK='TRUE';
      ALLOW_CONNECT='TRUE';
    'VSS1631':
      PIN_NUMBER='(0,0,0,0,0,0,0,0,0,0,0,0,0,0,0,0,0,0,0,0,0,0,0,0,0,0,0,0,0,0,0~
,0,0,0,0,0,0,0,0,0,J45,0)';
      PINUSE='POWER';
      NO_LOAD_CHECK='Both';
      NO_IO_CHECK='Both';
      NO_ASSERT_CHECK='TRUE';
      NO_DIR_CHECK='TRUE';
      ALLOW_CONNECT='TRUE';
    'VSS1630':
      PIN_NUMBER='(0,0,0,0,0,0,0,0,0,0,0,0,0,0,0,0,0,0,0,0,0,0,0,0,0,0,0,0,0,0,0~
,0,0,0,0,0,0,0,0,0,J33,0)';
      PINUSE='POWER';
      NO_LOAD_CHECK='Both';
      NO_IO_CHECK='Both';
      NO_ASSERT_CHECK='TRUE';
      NO_DIR_CHECK='TRUE';
      ALLOW_CONNECT='TRUE';
    'VSS1629':
      PIN_NUMBER='(0,0,0,0,0,0,0,0,0,0,0,0,0,0,0,0,0,0,0,0,0,0,0,0,0,0,0,0,0,0,0~
,0,0,0,0,0,0,0,0,0,J27,0)';
      PINUSE='POWER';
      NO_LOAD_CHECK='Both';
      NO_IO_CHECK='Both';
      NO_ASSERT_CHECK='TRUE';
      NO_DIR_CHECK='TRUE';
      ALLOW_CONNECT='TRUE';
    'VSS1628':
      PIN_NUMBER='(0,0,0,0,0,0,0,0,0,0,0,0,0,0,0,0,0,0,0,0,0,0,0,0,0,0,0,0,0,0,0~
,0,0,0,0,0,0,0,0,0,J15,0)';
      PINUSE='POWER';
      NO_LOAD_CHECK='Both';
      NO_IO_CHECK='Both';
      NO_ASSERT_CHECK='TRUE';
      NO_DIR_CHECK='TRUE';
      ALLOW_CONNECT='TRUE';
    'VSS1627':
      PIN_NUMBER='(0,0,0,0,0,0,0,0,0,0,0,0,0,0,0,0,0,0,0,0,0,0,0,0,0,0,0,0,0,0,0~
,0,0,0,0,0,0,0,0,0,H81,0)';
      PINUSE='POWER';
      NO_LOAD_CHECK='Both';
      NO_IO_CHECK='Both';
      NO_ASSERT_CHECK='TRUE';
      NO_DIR_CHECK='TRUE';
      ALLOW_CONNECT='TRUE';
    'VSS1626':
      PIN_NUMBER='(0,0,0,0,0,0,0,0,0,0,0,0,0,0,0,0,0,0,0,0,0,0,0,0,0,0,0,0,0,0,0~
,0,0,0,0,0,0,0,0,0,H8,0)';
      PINUSE='POWER';
      NO_LOAD_CHECK='Both';
      NO_IO_CHECK='Both';
      NO_ASSERT_CHECK='TRUE';
      NO_DIR_CHECK='TRUE';
      ALLOW_CONNECT='TRUE';
    'VSS1625':
      PIN_NUMBER='(0,0,0,0,0,0,0,0,0,0,0,0,0,0,0,0,0,0,0,0,0,0,0,0,0,0,0,0,0,0,0~
,0,0,0,0,0,0,0,0,0,H79,0)';
      PINUSE='POWER';
      NO_LOAD_CHECK='Both';
      NO_IO_CHECK='Both';
      NO_ASSERT_CHECK='TRUE';
      NO_DIR_CHECK='TRUE';
      ALLOW_CONNECT='TRUE';
    'VSS1624':
      PIN_NUMBER='(0,0,0,0,0,0,0,0,0,0,0,0,0,0,0,0,0,0,0,0,0,0,0,0,0,0,0,0,0,0,0~
,0,0,0,0,0,0,0,0,0,H71,0)';
      PINUSE='POWER';
      NO_LOAD_CHECK='Both';
      NO_IO_CHECK='Both';
      NO_ASSERT_CHECK='TRUE';
      NO_DIR_CHECK='TRUE';
      ALLOW_CONNECT='TRUE';
    'VSS1623':
      PIN_NUMBER='(0,0,0,0,0,0,0,0,0,0,0,0,0,0,0,0,0,0,0,0,0,0,0,0,0,0,0,0,0,0,0~
,0,0,0,0,0,0,0,0,0,H69,0)';
      PINUSE='POWER';
      NO_LOAD_CHECK='Both';
      NO_IO_CHECK='Both';
      NO_ASSERT_CHECK='TRUE';
      NO_DIR_CHECK='TRUE';
      ALLOW_CONNECT='TRUE';
    'VSS1622':
      PIN_NUMBER='(0,0,0,0,0,0,0,0,0,0,0,0,0,0,0,0,0,0,0,0,0,0,0,0,0,0,0,0,0,0,0~
,0,0,0,0,0,0,0,0,0,H63,0)';
      PINUSE='POWER';
      NO_LOAD_CHECK='Both';
      NO_IO_CHECK='Both';
      NO_ASSERT_CHECK='TRUE';
      NO_DIR_CHECK='TRUE';
      ALLOW_CONNECT='TRUE';
    'VSS1621':
      PIN_NUMBER='(0,0,0,0,0,0,0,0,0,0,0,0,0,0,0,0,0,0,0,0,0,0,0,0,0,0,0,0,0,0,0~
,0,0,0,0,0,0,0,0,0,H6,0)';
      PINUSE='POWER';
      NO_LOAD_CHECK='Both';
      NO_IO_CHECK='Both';
      NO_ASSERT_CHECK='TRUE';
      NO_DIR_CHECK='TRUE';
      ALLOW_CONNECT='TRUE';
    'VSS1620':
      PIN_NUMBER='(0,0,0,0,0,0,0,0,0,0,0,0,0,0,0,0,0,0,0,0,0,0,0,0,0,0,0,0,0,0,0~
,0,0,0,0,0,0,0,0,0,H59,0)';
      PINUSE='POWER';
      NO_LOAD_CHECK='Both';
      NO_IO_CHECK='Both';
      NO_ASSERT_CHECK='TRUE';
      NO_DIR_CHECK='TRUE';
      ALLOW_CONNECT='TRUE';
    'VSS1619':
      PIN_NUMBER='(0,0,0,0,0,0,0,0,0,0,0,0,0,0,0,0,0,0,0,0,0,0,0,0,0,0,0,0,0,0,0~
,0,0,0,0,0,0,0,0,0,H53,0)';
      PINUSE='POWER';
      NO_LOAD_CHECK='Both';
      NO_IO_CHECK='Both';
      NO_ASSERT_CHECK='TRUE';
      NO_DIR_CHECK='TRUE';
      ALLOW_CONNECT='TRUE';
    'VSS1618':
      PIN_NUMBER='(0,0,0,0,0,0,0,0,0,0,0,0,0,0,0,0,0,0,0,0,0,0,0,0,0,0,0,0,0,0,0~
,0,0,0,0,0,0,0,0,0,H47,0)';
      PINUSE='POWER';
      NO_LOAD_CHECK='Both';
      NO_IO_CHECK='Both';
      NO_ASSERT_CHECK='TRUE';
      NO_DIR_CHECK='TRUE';
      ALLOW_CONNECT='TRUE';
    'VSS1617':
      PIN_NUMBER='(0,0,0,0,0,0,0,0,0,0,0,0,0,0,0,0,0,0,0,0,0,0,0,0,0,0,0,0,0,0,0~
,0,0,0,0,0,0,0,0,0,H44,0)';
      PINUSE='POWER';
      NO_LOAD_CHECK='Both';
      NO_IO_CHECK='Both';
      NO_ASSERT_CHECK='TRUE';
      NO_DIR_CHECK='TRUE';
      ALLOW_CONNECT='TRUE';
    'VSS1616':
      PIN_NUMBER='(0,0,0,0,0,0,0,0,0,0,0,0,0,0,0,0,0,0,0,0,0,0,0,0,0,0,0,0,0,0,0~
,0,0,0,0,0,0,0,0,0,H40,0)';
      PINUSE='POWER';
      NO_LOAD_CHECK='Both';
      NO_IO_CHECK='Both';
      NO_ASSERT_CHECK='TRUE';
      NO_DIR_CHECK='TRUE';
      ALLOW_CONNECT='TRUE';
    'VSS1615':
      PIN_NUMBER='(0,0,0,0,0,0,0,0,0,0,0,0,0,0,0,0,0,0,0,0,0,0,0,0,0,0,0,0,0,0,0~
,0,0,0,0,0,0,0,0,0,H4,0)';
      PINUSE='POWER';
      NO_LOAD_CHECK='Both';
      NO_IO_CHECK='Both';
      NO_ASSERT_CHECK='TRUE';
      NO_DIR_CHECK='TRUE';
      ALLOW_CONNECT='TRUE';
    'VSS1614':
      PIN_NUMBER='(0,0,0,0,0,0,0,0,0,0,0,0,0,0,0,0,0,0,0,0,0,0,0,0,0,0,0,0,0,0,0~
,0,0,0,0,0,0,0,0,0,L19,0)';
      PINUSE='POWER';
      NO_LOAD_CHECK='Both';
      NO_IO_CHECK='Both';
      NO_ASSERT_CHECK='TRUE';
      NO_DIR_CHECK='TRUE';
      ALLOW_CONNECT='TRUE';
    'VSS1613':
      PIN_NUMBER='(0,0,0,0,0,0,0,0,0,0,0,0,0,0,0,0,0,0,0,0,0,0,0,0,0,0,0,0,0,0,0~
,0,0,0,0,0,0,0,0,0,H38,0)';
      PINUSE='POWER';
      NO_LOAD_CHECK='Both';
      NO_IO_CHECK='Both';
      NO_ASSERT_CHECK='TRUE';
      NO_DIR_CHECK='TRUE';
      ALLOW_CONNECT='TRUE';
    'VSS1612':
      PIN_NUMBER='(0,0,0,0,0,0,0,0,0,0,0,0,0,0,0,0,0,0,0,0,0,0,0,0,0,0,0,0,0,0,0~
,0,0,0,0,0,0,0,0,0,H34,0)';
      PINUSE='POWER';
      NO_LOAD_CHECK='Both';
      NO_IO_CHECK='Both';
      NO_ASSERT_CHECK='TRUE';
      NO_DIR_CHECK='TRUE';
      ALLOW_CONNECT='TRUE';
    'VSS1611':
      PIN_NUMBER='(0,0,0,0,0,0,0,0,0,0,0,0,0,0,0,0,0,0,0,0,0,0,0,0,0,0,0,0,0,0,0~
,0,0,0,0,0,0,0,0,0,H32,0)';
      PINUSE='POWER';
      NO_LOAD_CHECK='Both';
      NO_IO_CHECK='Both';
      NO_ASSERT_CHECK='TRUE';
      NO_DIR_CHECK='TRUE';
      ALLOW_CONNECT='TRUE';
    'VSS1610':
      PIN_NUMBER='(0,0,0,0,0,0,0,0,0,0,0,0,0,0,0,0,0,0,0,0,0,0,0,0,0,0,0,0,0,0,0~
,0,0,0,0,0,0,0,0,0,H28,0)';
      PINUSE='POWER';
      NO_LOAD_CHECK='Both';
      NO_IO_CHECK='Both';
      NO_ASSERT_CHECK='TRUE';
      NO_DIR_CHECK='TRUE';
      ALLOW_CONNECT='TRUE';
    'VSS1609':
      PIN_NUMBER='(0,0,0,0,0,0,0,0,0,0,0,0,0,0,0,0,0,0,0,0,0,0,0,0,0,0,0,0,0,0,0~
,0,0,0,0,0,0,0,0,0,H26,0)';
      PINUSE='POWER';
      NO_LOAD_CHECK='Both';
      NO_IO_CHECK='Both';
      NO_ASSERT_CHECK='TRUE';
      NO_DIR_CHECK='TRUE';
      ALLOW_CONNECT='TRUE';
    'VSS1608':
      PIN_NUMBER='(0,0,0,0,0,0,0,0,0,0,0,0,0,0,0,0,0,0,0,0,0,0,0,0,0,0,0,0,0,0,0~
,0,0,0,0,0,0,0,0,0,H22,0)';
      PINUSE='POWER';
      NO_LOAD_CHECK='Both';
      NO_IO_CHECK='Both';
      NO_ASSERT_CHECK='TRUE';
      NO_DIR_CHECK='TRUE';
      ALLOW_CONNECT='TRUE';
    'VSS1607':
      PIN_NUMBER='(0,0,0,0,0,0,0,0,0,0,0,0,0,0,0,0,0,0,0,0,0,0,0,0,0,0,0,0,0,0,0~
,0,0,0,0,0,0,0,0,0,H20,0)';
      PINUSE='POWER';
      NO_LOAD_CHECK='Both';
      NO_IO_CHECK='Both';
      NO_ASSERT_CHECK='TRUE';
      NO_DIR_CHECK='TRUE';
      ALLOW_CONNECT='TRUE';
    'VSS1606':
      PIN_NUMBER='(0,0,0,0,0,0,0,0,0,0,0,0,0,0,0,0,0,0,0,0,0,0,0,0,0,0,0,0,0,0,0~
,0,0,0,0,0,0,0,0,0,H16,0)';
      PINUSE='POWER';
      NO_LOAD_CHECK='Both';
      NO_IO_CHECK='Both';
      NO_ASSERT_CHECK='TRUE';
      NO_DIR_CHECK='TRUE';
      ALLOW_CONNECT='TRUE';
    'VSS1605':
      PIN_NUMBER='(0,0,0,0,0,0,0,0,0,0,0,0,0,0,0,0,0,0,0,0,0,0,0,0,0,0,0,0,0,0,0~
,0,0,0,0,0,0,0,0,0,H10,0)';
      PINUSE='POWER';
      NO_LOAD_CHECK='Both';
      NO_IO_CHECK='Both';
      NO_ASSERT_CHECK='TRUE';
      NO_DIR_CHECK='TRUE';
      ALLOW_CONNECT='TRUE';
    'VSS1604':
      PIN_NUMBER='(0,0,0,0,0,0,0,0,0,0,0,0,0,0,0,0,0,0,0,0,0,0,0,0,0,0,0,0,0,0,0~
,0,0,0,0,0,0,0,0,0,G90,0)';
      PINUSE='POWER';
      NO_LOAD_CHECK='Both';
      NO_IO_CHECK='Both';
      NO_ASSERT_CHECK='TRUE';
      NO_DIR_CHECK='TRUE';
      ALLOW_CONNECT='TRUE';
    'VSS1603':
      PIN_NUMBER='(0,0,0,0,0,0,0,0,0,0,0,0,0,0,0,0,0,0,0,0,0,0,0,0,0,0,0,0,0,0,0~
,0,0,0,0,0,0,0,0,0,K49,0)';
      PINUSE='POWER';
      NO_LOAD_CHECK='Both';
      NO_IO_CHECK='Both';
      NO_ASSERT_CHECK='TRUE';
      NO_DIR_CHECK='TRUE';
      ALLOW_CONNECT='TRUE';
    'VSS1602':
      PIN_NUMBER='(0,0,0,0,0,0,0,0,0,0,0,0,0,0,0,0,0,0,0,0,0,0,0,0,0,0,0,0,0,0,0~
,0,0,0,0,0,0,0,0,0,K42,0)';
      PINUSE='POWER';
      NO_LOAD_CHECK='Both';
      NO_IO_CHECK='Both';
      NO_ASSERT_CHECK='TRUE';
      NO_DIR_CHECK='TRUE';
      ALLOW_CONNECT='TRUE';
    'VSS1601':
      PIN_NUMBER='(0,0,0,0,0,0,0,0,0,0,0,0,0,0,0,0,0,0,0,0,0,0,0,0,0,0,0,0,0,0,0~
,0,0,0,0,0,0,0,0,0,G88,0)';
      PINUSE='POWER';
      NO_LOAD_CHECK='Both';
      NO_IO_CHECK='Both';
      NO_ASSERT_CHECK='TRUE';
      NO_DIR_CHECK='TRUE';
      ALLOW_CONNECT='TRUE';
    'VSS1600':
      PIN_NUMBER='(0,0,0,0,0,0,0,0,0,0,0,0,0,0,0,0,0,0,0,0,0,0,0,0,0,0,0,0,0,0,0~
,0,0,0,0,0,0,0,0,0,G84,0)';
      PINUSE='POWER';
      NO_LOAD_CHECK='Both';
      NO_IO_CHECK='Both';
      NO_ASSERT_CHECK='TRUE';
      NO_DIR_CHECK='TRUE';
      ALLOW_CONNECT='TRUE';
    'VSS1599':
      PIN_NUMBER='(0,0,0,0,0,0,0,0,0,0,0,0,0,0,0,0,0,0,0,0,0,0,0,0,0,0,0,0,0,0,0~
,0,0,0,0,0,0,0,0,0,K2,0)';
      PINUSE='POWER';
      NO_LOAD_CHECK='Both';
      NO_IO_CHECK='Both';
      NO_ASSERT_CHECK='TRUE';
      NO_DIR_CHECK='TRUE';
      ALLOW_CONNECT='TRUE';
    'VSS1598':
      PIN_NUMBER='(0,0,0,0,0,0,0,0,0,0,0,0,0,0,0,0,0,0,0,0,0,0,0,0,0,0,0,0,0,0,0~
,0,0,0,0,0,0,0,0,0,K14,0)';
      PINUSE='POWER';
      NO_LOAD_CHECK='Both';
      NO_IO_CHECK='Both';
      NO_ASSERT_CHECK='TRUE';
      NO_DIR_CHECK='TRUE';
      ALLOW_CONNECT='TRUE';
    'VSS1597':
      PIN_NUMBER='(0,0,0,0,0,0,0,0,0,0,0,0,0,0,0,0,0,0,0,0,0,0,0,0,0,0,0,0,0,0,0~
,0,0,0,0,0,0,0,0,0,K12,0)';
      PINUSE='POWER';
      NO_LOAD_CHECK='Both';
      NO_IO_CHECK='Both';
      NO_ASSERT_CHECK='TRUE';
      NO_DIR_CHECK='TRUE';
      ALLOW_CONNECT='TRUE';
    'VSS1596':
      PIN_NUMBER='(0,0,0,0,0,0,0,0,0,0,0,0,0,0,0,0,0,0,0,0,0,0,0,0,0,0,0,0,0,0,0~
,0,0,0,0,0,0,0,0,0,J9,0)';
      PINUSE='POWER';
      NO_LOAD_CHECK='Both';
      NO_IO_CHECK='Both';
      NO_ASSERT_CHECK='TRUE';
      NO_DIR_CHECK='TRUE';
      ALLOW_CONNECT='TRUE';
    'VSS1595':
      PIN_NUMBER='(0,0,0,0,0,0,0,0,0,0,0,0,0,0,0,0,0,0,0,0,0,0,0,0,0,0,0,0,0,0,0~
,0,0,0,0,0,0,0,0,0,J88,0)';
      PINUSE='POWER';
      NO_LOAD_CHECK='Both';
      NO_IO_CHECK='Both';
      NO_ASSERT_CHECK='TRUE';
      NO_DIR_CHECK='TRUE';
      ALLOW_CONNECT='TRUE';
    'VSS1594':
      PIN_NUMBER='(0,0,0,0,0,0,0,0,0,0,0,0,0,0,0,0,0,0,0,0,0,0,0,0,0,0,0,0,0,0,0~
,0,0,0,0,0,0,0,0,0,G72,0)';
      PINUSE='POWER';
      NO_LOAD_CHECK='Both';
      NO_IO_CHECK='Both';
      NO_ASSERT_CHECK='TRUE';
      NO_DIR_CHECK='TRUE';
      ALLOW_CONNECT='TRUE';
    'VSS1593':
      PIN_NUMBER='(0,0,0,0,0,0,0,0,0,0,0,0,0,0,0,0,0,0,0,0,0,0,0,0,0,0,0,0,0,0,0~
,0,0,0,0,0,0,0,0,0,G62,0)';
      PINUSE='POWER';
      NO_LOAD_CHECK='Both';
      NO_IO_CHECK='Both';
      NO_ASSERT_CHECK='TRUE';
      NO_DIR_CHECK='TRUE';
      ALLOW_CONNECT='TRUE';
    'VSS1592':
      PIN_NUMBER='(0,0,0,0,0,0,0,0,0,0,0,0,0,0,0,0,0,0,0,0,0,0,0,0,0,0,0,0,0,0,0~
,0,0,0,0,0,0,0,0,0,G56,0)';
      PINUSE='POWER';
      NO_LOAD_CHECK='Both';
      NO_IO_CHECK='Both';
      NO_ASSERT_CHECK='TRUE';
      NO_DIR_CHECK='TRUE';
      ALLOW_CONNECT='TRUE';
    'VSS1591':
      PIN_NUMBER='(0,0,0,0,0,0,0,0,0,0,0,0,0,0,0,0,0,0,0,0,0,0,0,0,0,0,0,0,0,0,0~
,0,0,0,0,0,0,0,0,0,G54,0)';
      PINUSE='POWER';
      NO_LOAD_CHECK='Both';
      NO_IO_CHECK='Both';
      NO_ASSERT_CHECK='TRUE';
      NO_DIR_CHECK='TRUE';
      ALLOW_CONNECT='TRUE';
    'VSS1590':
      PIN_NUMBER='(0,0,0,0,0,0,0,0,0,0,0,0,0,0,0,0,0,0,0,0,0,0,0,0,0,0,0,0,0,0,0~
,0,0,0,0,0,0,0,0,0,G50,0)';
      PINUSE='POWER';
      NO_LOAD_CHECK='Both';
      NO_IO_CHECK='Both';
      NO_ASSERT_CHECK='TRUE';
      NO_DIR_CHECK='TRUE';
      ALLOW_CONNECT='TRUE';
    'VSS1589':
      PIN_NUMBER='(0,0,0,0,0,0,0,0,0,0,0,0,0,0,0,0,0,0,0,0,0,0,0,0,0,0,0,0,0,0,0~
,0,0,0,0,0,0,0,0,0,J70,0)';
      PINUSE='POWER';
      NO_LOAD_CHECK='Both';
      NO_IO_CHECK='Both';
      NO_ASSERT_CHECK='TRUE';
      NO_DIR_CHECK='TRUE';
      ALLOW_CONNECT='TRUE';
    'VSS1588':
      PIN_NUMBER='(0,0,0,0,0,0,0,0,0,0,0,0,0,0,0,0,0,0,0,0,0,0,0,0,0,0,0,0,0,0,0~
,0,0,0,0,0,0,0,0,0,G43,0)';
      PINUSE='POWER';
      NO_LOAD_CHECK='Both';
      NO_IO_CHECK='Both';
      NO_ASSERT_CHECK='TRUE';
      NO_DIR_CHECK='TRUE';
      ALLOW_CONNECT='TRUE';
    'VSS1587':
      PIN_NUMBER='(0,0,0,0,0,0,0,0,0,0,0,0,0,0,0,0,0,0,0,0,0,0,0,0,0,0,0,0,0,0,0~
,0,0,0,0,0,0,0,0,0,J64,0)';
      PINUSE='POWER';
      NO_LOAD_CHECK='Both';
      NO_IO_CHECK='Both';
      NO_ASSERT_CHECK='TRUE';
      NO_DIR_CHECK='TRUE';
      ALLOW_CONNECT='TRUE';
    'VSS1586':
      PIN_NUMBER='(0,0,0,0,0,0,0,0,0,0,0,0,0,0,0,0,0,0,0,0,0,0,0,0,0,0,0,0,0,0,0~
,0,0,0,0,0,0,0,0,0,G41,0)';
      PINUSE='POWER';
      NO_LOAD_CHECK='Both';
      NO_IO_CHECK='Both';
      NO_ASSERT_CHECK='TRUE';
      NO_DIR_CHECK='TRUE';
      ALLOW_CONNECT='TRUE';
    'VSS1585':
      PIN_NUMBER='(0,0,0,0,0,0,0,0,0,0,0,0,0,0,0,0,0,0,0,0,0,0,0,0,0,0,0,0,0,0,0~
,0,0,0,0,0,0,0,0,0,G37,0)';
      PINUSE='POWER';
      NO_LOAD_CHECK='Both';
      NO_IO_CHECK='Both';
      NO_ASSERT_CHECK='TRUE';
      NO_DIR_CHECK='TRUE';
      ALLOW_CONNECT='TRUE';
    'VSS1584':
      PIN_NUMBER='(0,0,0,0,0,0,0,0,0,0,0,0,0,0,0,0,0,0,0,0,0,0,0,0,0,0,0,0,0,0,0~
,0,0,0,0,0,0,0,0,0,G31,0)';
      PINUSE='POWER';
      NO_LOAD_CHECK='Both';
      NO_IO_CHECK='Both';
      NO_ASSERT_CHECK='TRUE';
      NO_DIR_CHECK='TRUE';
      ALLOW_CONNECT='TRUE';
    'VSS1583':
      PIN_NUMBER='(0,0,0,0,0,0,0,0,0,0,0,0,0,0,0,0,0,0,0,0,0,0,0,0,0,0,0,0,0,0,0~
,0,0,0,0,0,0,0,0,0,G29,0)';
      PINUSE='POWER';
      NO_LOAD_CHECK='Both';
      NO_IO_CHECK='Both';
      NO_ASSERT_CHECK='TRUE';
      NO_DIR_CHECK='TRUE';
      ALLOW_CONNECT='TRUE';
    'VSS1582':
      PIN_NUMBER='(0,0,0,0,0,0,0,0,0,0,0,0,0,0,0,0,0,0,0,0,0,0,0,0,0,0,0,0,0,0,0~
,0,0,0,0,0,0,0,0,0,J5,0)';
      PINUSE='POWER';
      NO_LOAD_CHECK='Both';
      NO_IO_CHECK='Both';
      NO_ASSERT_CHECK='TRUE';
      NO_DIR_CHECK='TRUE';
      ALLOW_CONNECT='TRUE';
    'VSS1581':
      PIN_NUMBER='(0,0,0,0,0,0,0,0,0,0,0,0,0,0,0,0,0,0,0,0,0,0,0,0,0,0,0,0,0,0,0~
,0,0,0,0,0,0,0,0,0,G23,0)';
      PINUSE='POWER';
      NO_LOAD_CHECK='Both';
      NO_IO_CHECK='Both';
      NO_ASSERT_CHECK='TRUE';
      NO_DIR_CHECK='TRUE';
      ALLOW_CONNECT='TRUE';
    'VSS1580':
      PIN_NUMBER='(0,0,0,0,0,0,0,0,0,0,0,0,0,0,0,0,0,0,0,0,0,0,0,0,0,0,0,0,0,0,0~
,0,0,0,0,0,0,0,0,0,J39,0)';
      PINUSE='POWER';
      NO_LOAD_CHECK='Both';
      NO_IO_CHECK='Both';
      NO_ASSERT_CHECK='TRUE';
      NO_DIR_CHECK='TRUE';
      ALLOW_CONNECT='TRUE';
    'VSS1579':
      PIN_NUMBER='(0,0,0,0,0,0,0,0,0,0,0,0,0,0,0,0,0,0,0,0,0,0,0,0,0,0,0,0,0,0,0~
,0,0,0,0,0,0,0,0,0,G19,0)';
      PINUSE='POWER';
      NO_LOAD_CHECK='Both';
      NO_IO_CHECK='Both';
      NO_ASSERT_CHECK='TRUE';
      NO_DIR_CHECK='TRUE';
      ALLOW_CONNECT='TRUE';
    'VSS1578':
      PIN_NUMBER='(0,0,0,0,0,0,0,0,0,0,0,0,0,0,0,0,0,0,0,0,0,0,0,0,0,0,0,0,0,0,0~
,0,0,0,0,0,0,0,0,0,G13,0)';
      PINUSE='POWER';
      NO_LOAD_CHECK='Both';
      NO_IO_CHECK='Both';
      NO_ASSERT_CHECK='TRUE';
      NO_DIR_CHECK='TRUE';
      ALLOW_CONNECT='TRUE';
    'VSS1577':
      PIN_NUMBER='(0,0,0,0,0,0,0,0,0,0,0,0,0,0,0,0,0,0,0,0,0,0,0,0,0,0,0,0,0,0,0~
,0,0,0,0,0,0,0,0,0,F89,0)';
      PINUSE='POWER';
      NO_LOAD_CHECK='Both';
      NO_IO_CHECK='Both';
      NO_ASSERT_CHECK='TRUE';
      NO_DIR_CHECK='TRUE';
      ALLOW_CONNECT='TRUE';
    'VSS1576':
      PIN_NUMBER='(0,0,0,0,0,0,0,0,0,0,0,0,0,0,0,0,0,0,0,0,0,0,0,0,0,0,0,0,0,0,0~
,0,0,0,0,0,0,0,0,0,F83,0)';
      PINUSE='POWER';
      NO_LOAD_CHECK='Both';
      NO_IO_CHECK='Both';
      NO_ASSERT_CHECK='TRUE';
      NO_DIR_CHECK='TRUE';
      ALLOW_CONNECT='TRUE';
    'VSS1575':
      PIN_NUMBER='(0,0,0,0,0,0,0,0,0,0,0,0,0,0,0,0,0,0,0,0,0,0,0,0,0,0,0,0,0,0,0~
,0,0,0,0,0,0,0,0,0,J21,0)';
      PINUSE='POWER';
      NO_LOAD_CHECK='Both';
      NO_IO_CHECK='Both';
      NO_ASSERT_CHECK='TRUE';
      NO_DIR_CHECK='TRUE';
      ALLOW_CONNECT='TRUE';
    'VSS1574':
      PIN_NUMBER='(0,0,0,0,0,0,0,0,0,0,0,0,0,0,0,0,0,0,0,0,0,0,0,0,0,0,0,0,0,0,0~
,0,0,0,0,0,0,0,0,0,F49,0)';
      PINUSE='POWER';
      NO_LOAD_CHECK='Both';
      NO_IO_CHECK='Both';
      NO_ASSERT_CHECK='TRUE';
      NO_DIR_CHECK='TRUE';
      ALLOW_CONNECT='TRUE';
    'VSS1573':
      PIN_NUMBER='(0,0,0,0,0,0,0,0,0,0,0,0,0,0,0,0,0,0,0,0,0,0,0,0,0,0,0,0,0,0,0~
,0,0,0,0,0,0,0,0,0,F4,0)';
      PINUSE='POWER';
      NO_LOAD_CHECK='Both';
      NO_IO_CHECK='Both';
      NO_ASSERT_CHECK='TRUE';
      NO_DIR_CHECK='TRUE';
      ALLOW_CONNECT='TRUE';
    'VSS1572':
      PIN_NUMBER='(0,0,0,0,0,0,0,0,0,0,0,0,0,0,0,0,0,0,0,0,0,0,0,0,0,0,0,0,0,0,0~
,0,0,0,0,0,0,0,0,0,F36,0)';
      PINUSE='POWER';
      NO_LOAD_CHECK='Both';
      NO_IO_CHECK='Both';
      NO_ASSERT_CHECK='TRUE';
      NO_DIR_CHECK='TRUE';
      ALLOW_CONNECT='TRUE';
    'VSS1571':
      PIN_NUMBER='(0,0,0,0,0,0,0,0,0,0,0,0,0,0,0,0,0,0,0,0,0,0,0,0,0,0,0,0,0,0,0~
,0,0,0,0,0,0,0,0,0,F30,0)';
      PINUSE='POWER';
      NO_LOAD_CHECK='Both';
      NO_IO_CHECK='Both';
      NO_ASSERT_CHECK='TRUE';
      NO_DIR_CHECK='TRUE';
      ALLOW_CONNECT='TRUE';
    'VSS1570':
      PIN_NUMBER='(0,0,0,0,0,0,0,0,0,0,0,0,0,0,0,0,0,0,0,0,0,0,0,0,0,0,0,0,0,0,0~
,0,0,0,0,0,0,0,0,0,F24,0)';
      PINUSE='POWER';
      NO_LOAD_CHECK='Both';
      NO_IO_CHECK='Both';
      NO_ASSERT_CHECK='TRUE';
      NO_DIR_CHECK='TRUE';
      ALLOW_CONNECT='TRUE';
    'VSS1567':
      PIN_NUMBER='(0,0,0,0,0,0,0,0,0,0,0,0,0,0,0,0,0,0,0,0,0,0,0,0,0,0,0,0,0,0,0~
,0,0,0,0,0,0,0,0,0,H75,0)';
      PINUSE='POWER';
      NO_LOAD_CHECK='Both';
      NO_IO_CHECK='Both';
      NO_ASSERT_CHECK='TRUE';
      NO_DIR_CHECK='TRUE';
      ALLOW_CONNECT='TRUE';
    'VSS1564':
      PIN_NUMBER='(0,0,0,0,0,0,0,0,0,0,0,0,0,0,0,0,0,0,0,0,0,0,0,0,0,0,0,0,0,0,0~
,0,0,0,0,0,0,0,0,0,H65,0)';
      PINUSE='POWER';
      NO_LOAD_CHECK='Both';
      NO_IO_CHECK='Both';
      NO_ASSERT_CHECK='TRUE';
      NO_DIR_CHECK='TRUE';
      ALLOW_CONNECT='TRUE';
    'VSS1560':
      PIN_NUMBER='(0,0,0,0,0,0,0,0,0,0,0,0,0,0,0,0,0,0,0,0,0,0,0,0,0,0,0,0,0,0,0~
,0,0,0,0,0,0,0,0,0,H57,0)';
      PINUSE='POWER';
      NO_LOAD_CHECK='Both';
      NO_IO_CHECK='Both';
      NO_ASSERT_CHECK='TRUE';
      NO_DIR_CHECK='TRUE';
      ALLOW_CONNECT='TRUE';
    'VSS1558':
      PIN_NUMBER='(0,0,0,0,0,0,0,0,0,0,0,0,0,0,0,0,0,0,0,0,0,0,0,0,0,0,0,0,0,0,0~
,0,0,0,0,0,0,0,0,0,H51,0)';
      PINUSE='POWER';
      NO_LOAD_CHECK='Both';
      NO_IO_CHECK='Both';
      NO_ASSERT_CHECK='TRUE';
      NO_DIR_CHECK='TRUE';
      ALLOW_CONNECT='TRUE';
    'VSS1546':
      PIN_NUMBER='(0,0,0,0,0,0,0,0,0,0,0,0,0,0,0,0,0,0,0,0,0,0,0,0,0,0,0,0,0,0,0~
,0,0,0,0,0,0,0,0,0,H2,0)';
      PINUSE='POWER';
      NO_LOAD_CHECK='Both';
      NO_IO_CHECK='Both';
      NO_ASSERT_CHECK='TRUE';
      NO_DIR_CHECK='TRUE';
      ALLOW_CONNECT='TRUE';
    'VSS1544':
      PIN_NUMBER='(0,0,0,0,0,0,0,0,0,0,0,0,0,0,0,0,0,0,0,0,0,0,0,0,0,0,0,0,0,0,0~
,0,0,0,0,0,0,0,0,0,H14,0)';
      PINUSE='POWER';
      NO_LOAD_CHECK='Both';
      NO_IO_CHECK='Both';
      NO_ASSERT_CHECK='TRUE';
      NO_DIR_CHECK='TRUE';
      ALLOW_CONNECT='TRUE';
    'VSS1538':
      PIN_NUMBER='(0,0,0,0,0,0,0,0,0,0,0,0,0,0,0,0,0,0,0,0,0,0,0,0,0,0,0,0,0,0,0~
,0,0,0,0,0,0,0,0,0,G74,0)';
      PINUSE='POWER';
      NO_LOAD_CHECK='Both';
      NO_IO_CHECK='Both';
      NO_ASSERT_CHECK='TRUE';
      NO_DIR_CHECK='TRUE';
      ALLOW_CONNECT='TRUE';
    'VSS1536':
      PIN_NUMBER='(0,0,0,0,0,0,0,0,0,0,0,0,0,0,0,0,0,0,0,0,0,0,0,0,0,0,0,0,0,0,0~
,0,0,0,0,0,0,0,0,0,G7,0)';
      PINUSE='POWER';
      NO_LOAD_CHECK='Both';
      NO_IO_CHECK='Both';
      NO_ASSERT_CHECK='TRUE';
      NO_DIR_CHECK='TRUE';
      ALLOW_CONNECT='TRUE';
    'VSS1535':
      PIN_NUMBER='(0,0,0,0,0,0,0,0,0,0,0,0,0,0,0,0,0,0,0,0,0,0,0,0,0,0,0,0,0,0,0~
,0,0,0,0,0,0,0,0,0,G68,0)';
      PINUSE='POWER';
      NO_LOAD_CHECK='Both';
      NO_IO_CHECK='Both';
      NO_ASSERT_CHECK='TRUE';
      NO_DIR_CHECK='TRUE';
      ALLOW_CONNECT='TRUE';
    'VSS1534':
      PIN_NUMBER='(0,0,0,0,0,0,0,0,0,0,0,0,0,0,0,0,0,0,0,0,0,0,0,0,0,0,0,0,0,0,0~
,0,0,0,0,0,0,0,0,0,G66,0)';
      PINUSE='POWER';
      NO_LOAD_CHECK='Both';
      NO_IO_CHECK='Both';
      NO_ASSERT_CHECK='TRUE';
      NO_DIR_CHECK='TRUE';
      ALLOW_CONNECT='TRUE';
    'VSS1532':
      PIN_NUMBER='(0,0,0,0,0,0,0,0,0,0,0,0,0,0,0,0,0,0,0,0,0,0,0,0,0,0,0,0,0,0,0~
,0,0,0,0,0,0,0,0,0,G60,0)';
      PINUSE='POWER';
      NO_LOAD_CHECK='Both';
      NO_IO_CHECK='Both';
      NO_ASSERT_CHECK='TRUE';
      NO_DIR_CHECK='TRUE';
      ALLOW_CONNECT='TRUE';
    'VSS1527':
      PIN_NUMBER='(0,0,0,0,0,0,0,0,0,0,0,0,0,0,0,0,0,0,0,0,0,0,0,0,0,0,0,0,0,0,0~
,0,0,0,0,0,0,0,0,0,G48,0)';
      PINUSE='POWER';
      NO_LOAD_CHECK='Both';
      NO_IO_CHECK='Both';
      NO_ASSERT_CHECK='TRUE';
      NO_DIR_CHECK='TRUE';
      ALLOW_CONNECT='TRUE';
    'VSS1523':
      PIN_NUMBER='(0,0,0,0,0,0,0,0,0,0,0,0,0,0,0,0,0,0,0,0,0,0,0,0,0,0,0,0,0,0,0~
,0,0,0,0,0,0,0,0,0,G35,0)';
      PINUSE='POWER';
      NO_LOAD_CHECK='Both';
      NO_IO_CHECK='Both';
      NO_ASSERT_CHECK='TRUE';
      NO_DIR_CHECK='TRUE';
      ALLOW_CONNECT='TRUE';
    'VSS1521':
      PIN_NUMBER='(0,0,0,0,0,0,0,0,0,0,0,0,0,0,0,0,0,0,0,0,0,0,0,0,0,0,0,0,0,0,0~
,0,0,0,0,0,0,0,0,0,G3,0)';
      PINUSE='POWER';
      NO_LOAD_CHECK='Both';
      NO_IO_CHECK='Both';
      NO_ASSERT_CHECK='TRUE';
      NO_DIR_CHECK='TRUE';
      ALLOW_CONNECT='TRUE';
    'VSS1519':
      PIN_NUMBER='(0,0,0,0,0,0,0,0,0,0,0,0,0,0,0,0,0,0,0,0,0,0,0,0,0,0,0,0,0,0,0~
,0,0,0,0,0,0,0,0,0,G25,0)';
      PINUSE='POWER';
      NO_LOAD_CHECK='Both';
      NO_IO_CHECK='Both';
      NO_ASSERT_CHECK='TRUE';
      NO_DIR_CHECK='TRUE';
      ALLOW_CONNECT='TRUE';
    'VSS1516':
      PIN_NUMBER='(0,0,0,0,0,0,0,0,0,0,0,0,0,0,0,0,0,0,0,0,0,0,0,0,0,0,0,0,0,0,0~
,0,0,0,0,0,0,0,0,0,G17,0)';
      PINUSE='POWER';
      NO_LOAD_CHECK='Both';
      NO_IO_CHECK='Both';
      NO_ASSERT_CHECK='TRUE';
      NO_DIR_CHECK='TRUE';
      ALLOW_CONNECT='TRUE';
    'VSS1514':
      PIN_NUMBER='(0,0,0,0,0,0,0,0,0,0,0,0,0,0,0,0,0,0,0,0,0,0,0,0,0,0,0,0,0,0,0~
,0,0,0,0,0,0,0,0,0,G11,0)';
      PINUSE='POWER';
      NO_LOAD_CHECK='Both';
      NO_IO_CHECK='Both';
      NO_ASSERT_CHECK='TRUE';
      NO_DIR_CHECK='TRUE';
      ALLOW_CONNECT='TRUE';
    'VSS1511':
      PIN_NUMBER='(0,0,0,0,0,0,0,0,0,0,0,0,0,0,0,0,0,0,0,0,0,0,0,0,0,0,0,0,0,0,0~
,0,0,0,0,0,0,0,0,0,F79,0)';
      PINUSE='POWER';
      NO_LOAD_CHECK='Both';
      NO_IO_CHECK='Both';
      NO_ASSERT_CHECK='TRUE';
      NO_DIR_CHECK='TRUE';
      ALLOW_CONNECT='TRUE';
    'VSS1510':
      PIN_NUMBER='(0,0,0,0,0,0,0,0,0,0,0,0,0,0,0,0,0,0,0,0,0,0,0,0,0,0,0,0,0,0,0~
,0,0,0,0,0,0,0,0,0,F73,0)';
      PINUSE='POWER';
      NO_LOAD_CHECK='Both';
      NO_IO_CHECK='Both';
      NO_ASSERT_CHECK='TRUE';
      NO_DIR_CHECK='TRUE';
      ALLOW_CONNECT='TRUE';
    'VSS1509':
      PIN_NUMBER='(0,0,0,0,0,0,0,0,0,0,0,0,0,0,0,0,0,0,0,0,0,0,0,0,0,0,0,0,0,0,0~
,0,0,0,0,0,0,0,0,0,F67,0)';
      PINUSE='POWER';
      NO_LOAD_CHECK='Both';
      NO_IO_CHECK='Both';
      NO_ASSERT_CHECK='TRUE';
      NO_DIR_CHECK='TRUE';
      ALLOW_CONNECT='TRUE';
    'VSS1508':
      PIN_NUMBER='(0,0,0,0,0,0,0,0,0,0,0,0,0,0,0,0,0,0,0,0,0,0,0,0,0,0,0,0,0,0,0~
,0,0,0,0,0,0,0,0,0,F61,0)';
      PINUSE='POWER';
      NO_LOAD_CHECK='Both';
      NO_IO_CHECK='Both';
      NO_ASSERT_CHECK='TRUE';
      NO_DIR_CHECK='TRUE';
      ALLOW_CONNECT='TRUE';
    'VSS1507':
      PIN_NUMBER='(0,0,0,0,0,0,0,0,0,0,0,0,0,0,0,0,0,0,0,0,0,0,0,0,0,0,0,0,0,0,0~
,0,0,0,0,0,0,0,0,0,F6,0)';
      PINUSE='POWER';
      NO_LOAD_CHECK='Both';
      NO_IO_CHECK='Both';
      NO_ASSERT_CHECK='TRUE';
      NO_DIR_CHECK='TRUE';
      ALLOW_CONNECT='TRUE';
    'VSS1504':
      PIN_NUMBER='(0,0,0,0,0,0,0,0,0,0,0,0,0,0,0,0,0,0,0,0,0,0,0,0,0,0,0,0,0,0,0~
,0,0,0,0,0,0,0,0,0,F55,0)';
      PINUSE='POWER';
      NO_LOAD_CHECK='Both';
      NO_IO_CHECK='Both';
      NO_ASSERT_CHECK='TRUE';
      NO_DIR_CHECK='TRUE';
      ALLOW_CONNECT='TRUE';
    'VSS1502':
      PIN_NUMBER='(0,0,0,0,0,0,0,0,0,0,0,0,0,0,0,0,0,0,0,0,0,0,0,0,0,0,0,0,0,0,0~
,0,0,0,0,0,0,0,0,0,F42,0)';
      PINUSE='POWER';
      NO_LOAD_CHECK='Both';
      NO_IO_CHECK='Both';
      NO_ASSERT_CHECK='TRUE';
      NO_DIR_CHECK='TRUE';
      ALLOW_CONNECT='TRUE';
    'VSS1495':
      PIN_NUMBER='(0,0,0,0,0,0,0,0,0,0,0,0,0,0,0,0,0,0,0,0,0,0,0,0,0,0,0,0,0,0,0~
,0,0,0,0,0,0,0,0,0,F18,0)';
      PINUSE='POWER';
      NO_LOAD_CHECK='Both';
      NO_IO_CHECK='Both';
      NO_ASSERT_CHECK='TRUE';
      NO_DIR_CHECK='TRUE';
      ALLOW_CONNECT='TRUE';
    'VSS1494':
      PIN_NUMBER='(0,0,0,0,0,0,0,0,0,0,0,0,0,0,0,0,0,0,0,0,0,0,0,0,0,0,0,0,0,0,0~
,0,0,0,0,0,0,0,0,0,F12,0)';
      PINUSE='POWER';
      NO_LOAD_CHECK='Both';
      NO_IO_CHECK='Both';
      NO_ASSERT_CHECK='TRUE';
      NO_DIR_CHECK='TRUE';
      ALLOW_CONNECT='TRUE';
    'VSS1273':
      PIN_NUMBER='(0,0,0,0,0,0,0,0,0,0,0,0,0,0,0,0,0,0,0,0,0,0,0,0,0,0,0,0,0,0,0~
,0,0,0,0,0,0,0,0,0,E86,0)';
      PINUSE='POWER';
      NO_LOAD_CHECK='Both';
      NO_IO_CHECK='Both';
      NO_ASSERT_CHECK='TRUE';
      NO_DIR_CHECK='TRUE';
      ALLOW_CONNECT='TRUE';
    'VSS1272':
      PIN_NUMBER='(0,0,0,0,0,0,0,0,0,0,0,0,0,0,0,0,0,0,0,0,0,0,0,0,0,0,0,0,0,0,0~
,0,0,0,0,0,0,0,0,0,E76,0)';
      PINUSE='POWER';
      NO_LOAD_CHECK='Both';
      NO_IO_CHECK='Both';
      NO_ASSERT_CHECK='TRUE';
      NO_DIR_CHECK='TRUE';
      ALLOW_CONNECT='TRUE';
    'VSS1131':
      PIN_NUMBER='(0,0,0,0,0,0,0,0,0,0,0,0,0,0,0,0,0,0,0,0,0,0,0,0,0,0,0,0,0,0,0~
,0,0,0,0,0,0,0,0,0,E78,0)';
      PINUSE='POWER';
      NO_LOAD_CHECK='Both';
      NO_IO_CHECK='Both';
      NO_ASSERT_CHECK='TRUE';
      NO_DIR_CHECK='TRUE';
      ALLOW_CONNECT='TRUE';
    'VSS1129':
      PIN_NUMBER='(0,0,0,0,0,0,0,0,0,0,0,0,0,0,0,0,0,0,0,0,0,0,0,0,0,0,0,0,0,0,0~
,0,0,0,0,0,0,0,0,0,E74,0)';
      PINUSE='POWER';
      NO_LOAD_CHECK='Both';
      NO_IO_CHECK='Both';
      NO_ASSERT_CHECK='TRUE';
      NO_DIR_CHECK='TRUE';
      ALLOW_CONNECT='TRUE';
    'VSS1126':
      PIN_NUMBER='(0,0,0,0,0,0,0,0,0,0,0,0,0,0,0,0,0,0,0,0,0,0,0,0,0,0,0,0,0,0,0~
,0,0,0,0,0,0,0,0,0,E52,0)';
      PINUSE='POWER';
      NO_LOAD_CHECK='Both';
      NO_IO_CHECK='Both';
      NO_ASSERT_CHECK='TRUE';
      NO_DIR_CHECK='TRUE';
      ALLOW_CONNECT='TRUE';
    'VSS1271':
      PIN_NUMBER='(0,0,0,0,0,0,0,0,0,0,0,0,0,0,0,0,0,0,0,0,0,0,0,0,0,0,0,0,0,0,0~
,0,0,0,0,0,0,0,0,0,0,E39)';
      PINUSE='POWER';
      NO_LOAD_CHECK='Both';
      NO_IO_CHECK='Both';
      NO_ASSERT_CHECK='TRUE';
      NO_DIR_CHECK='TRUE';
      ALLOW_CONNECT='TRUE';
    'VSS1125':
      PIN_NUMBER='(0,0,0,0,0,0,0,0,0,0,0,0,0,0,0,0,0,0,0,0,0,0,0,0,0,0,0,0,0,0,0~
,0,0,0,0,0,0,0,0,0,0,E5)';
      PINUSE='POWER';
      NO_LOAD_CHECK='Both';
      NO_IO_CHECK='Both';
      NO_ASSERT_CHECK='TRUE';
      NO_DIR_CHECK='TRUE';
      ALLOW_CONNECT='TRUE';
    'VSS907':
      PIN_NUMBER='(0,0,0,0,0,0,0,0,0,0,0,0,0,0,0,0,0,0,0,0,0,0,0,0,0,0,0,0,0,0,0~
,0,0,0,0,0,0,0,0,0,0,D83)';
      PINUSE='POWER';
      NO_LOAD_CHECK='Both';
      NO_IO_CHECK='Both';
      NO_ASSERT_CHECK='TRUE';
      NO_DIR_CHECK='TRUE';
      ALLOW_CONNECT='TRUE';
    'VSS906':
      PIN_NUMBER='(0,0,0,0,0,0,0,0,0,0,0,0,0,0,0,0,0,0,0,0,0,0,0,0,0,0,0,0,0,0,0~
,0,0,0,0,0,0,0,0,0,0,D81)';
      PINUSE='POWER';
      NO_LOAD_CHECK='Both';
      NO_IO_CHECK='Both';
      NO_ASSERT_CHECK='TRUE';
      NO_DIR_CHECK='TRUE';
      ALLOW_CONNECT='TRUE';
    'VSS902':
      PIN_NUMBER='(0,0,0,0,0,0,0,0,0,0,0,0,0,0,0,0,0,0,0,0,0,0,0,0,0,0,0,0,0,0,0~
,0,0,0,0,0,0,0,0,0,0,D71)';
      PINUSE='POWER';
      NO_LOAD_CHECK='Both';
      NO_IO_CHECK='Both';
      NO_ASSERT_CHECK='TRUE';
      NO_DIR_CHECK='TRUE';
      ALLOW_CONNECT='TRUE';
    'VSS901':
      PIN_NUMBER='(0,0,0,0,0,0,0,0,0,0,0,0,0,0,0,0,0,0,0,0,0,0,0,0,0,0,0,0,0,0,0~
,0,0,0,0,0,0,0,0,0,0,D69)';
      PINUSE='POWER';
      NO_LOAD_CHECK='Both';
      NO_IO_CHECK='Both';
      NO_ASSERT_CHECK='TRUE';
      NO_DIR_CHECK='TRUE';
      ALLOW_CONNECT='TRUE';
    'VSS900':
      PIN_NUMBER='(0,0,0,0,0,0,0,0,0,0,0,0,0,0,0,0,0,0,0,0,0,0,0,0,0,0,0,0,0,0,0~
,0,0,0,0,0,0,0,0,0,0,D61)';
      PINUSE='POWER';
      NO_LOAD_CHECK='Both';
      NO_IO_CHECK='Both';
      NO_ASSERT_CHECK='TRUE';
      NO_DIR_CHECK='TRUE';
      ALLOW_CONNECT='TRUE';
    'VSS899':
      PIN_NUMBER='(0,0,0,0,0,0,0,0,0,0,0,0,0,0,0,0,0,0,0,0,0,0,0,0,0,0,0,0,0,0,0~
,0,0,0,0,0,0,0,0,0,0,D6)';
      PINUSE='POWER';
      NO_LOAD_CHECK='Both';
      NO_IO_CHECK='Both';
      NO_ASSERT_CHECK='TRUE';
      NO_DIR_CHECK='TRUE';
      ALLOW_CONNECT='TRUE';
    'VSS898':
      PIN_NUMBER='(0,0,0,0,0,0,0,0,0,0,0,0,0,0,0,0,0,0,0,0,0,0,0,0,0,0,0,0,0,0,0~
,0,0,0,0,0,0,0,0,0,0,D59)';
      PINUSE='POWER';
      NO_LOAD_CHECK='Both';
      NO_IO_CHECK='Both';
      NO_ASSERT_CHECK='TRUE';
      NO_DIR_CHECK='TRUE';
      ALLOW_CONNECT='TRUE';
    'VSS897':
      PIN_NUMBER='(0,0,0,0,0,0,0,0,0,0,0,0,0,0,0,0,0,0,0,0,0,0,0,0,0,0,0,0,0,0,0~
,0,0,0,0,0,0,0,0,0,0,D57)';
      PINUSE='POWER';
      NO_LOAD_CHECK='Both';
      NO_IO_CHECK='Both';
      NO_ASSERT_CHECK='TRUE';
      NO_DIR_CHECK='TRUE';
      ALLOW_CONNECT='TRUE';
    'VSS896':
      PIN_NUMBER='(0,0,0,0,0,0,0,0,0,0,0,0,0,0,0,0,0,0,0,0,0,0,0,0,0,0,0,0,0,0,0~
,0,0,0,0,0,0,0,0,0,0,D55)';
      PINUSE='POWER';
      NO_LOAD_CHECK='Both';
      NO_IO_CHECK='Both';
      NO_ASSERT_CHECK='TRUE';
      NO_DIR_CHECK='TRUE';
      ALLOW_CONNECT='TRUE';
    'VSS895':
      PIN_NUMBER='(0,0,0,0,0,0,0,0,0,0,0,0,0,0,0,0,0,0,0,0,0,0,0,0,0,0,0,0,0,0,0~
,0,0,0,0,0,0,0,0,0,0,D53)';
      PINUSE='POWER';
      NO_LOAD_CHECK='Both';
      NO_IO_CHECK='Both';
      NO_ASSERT_CHECK='TRUE';
      NO_DIR_CHECK='TRUE';
      ALLOW_CONNECT='TRUE';
    'VSS892':
      PIN_NUMBER='(0,0,0,0,0,0,0,0,0,0,0,0,0,0,0,0,0,0,0,0,0,0,0,0,0,0,0,0,0,0,0~
,0,0,0,0,0,0,0,0,0,0,D51)';
      PINUSE='POWER';
      NO_LOAD_CHECK='Both';
      NO_IO_CHECK='Both';
      NO_ASSERT_CHECK='TRUE';
      NO_DIR_CHECK='TRUE';
      ALLOW_CONNECT='TRUE';
    'VSS891':
      PIN_NUMBER='(0,0,0,0,0,0,0,0,0,0,0,0,0,0,0,0,0,0,0,0,0,0,0,0,0,0,0,0,0,0,0~
,0,0,0,0,0,0,0,0,0,0,D49)';
      PINUSE='POWER';
      NO_LOAD_CHECK='Both';
      NO_IO_CHECK='Both';
      NO_ASSERT_CHECK='TRUE';
      NO_DIR_CHECK='TRUE';
      ALLOW_CONNECT='TRUE';
    'VSS889':
      PIN_NUMBER='(0,0,0,0,0,0,0,0,0,0,0,0,0,0,0,0,0,0,0,0,0,0,0,0,0,0,0,0,0,0,0~
,0,0,0,0,0,0,0,0,0,0,D47)';
      PINUSE='POWER';
      NO_LOAD_CHECK='Both';
      NO_IO_CHECK='Both';
      NO_ASSERT_CHECK='TRUE';
      NO_DIR_CHECK='TRUE';
      ALLOW_CONNECT='TRUE';
    'VSS888':
      PIN_NUMBER='(0,0,0,0,0,0,0,0,0,0,0,0,0,0,0,0,0,0,0,0,0,0,0,0,0,0,0,0,0,0,0~
,0,0,0,0,0,0,0,0,0,0,D44)';
      PINUSE='POWER';
      NO_LOAD_CHECK='Both';
      NO_IO_CHECK='Both';
      NO_ASSERT_CHECK='TRUE';
      NO_DIR_CHECK='TRUE';
      ALLOW_CONNECT='TRUE';
    'VSS886':
      PIN_NUMBER='(0,0,0,0,0,0,0,0,0,0,0,0,0,0,0,0,0,0,0,0,0,0,0,0,0,0,0,0,0,0,0~
,0,0,0,0,0,0,0,0,0,0,D42)';
      PINUSE='POWER';
      NO_LOAD_CHECK='Both';
      NO_IO_CHECK='Both';
      NO_ASSERT_CHECK='TRUE';
      NO_DIR_CHECK='TRUE';
      ALLOW_CONNECT='TRUE';
    'VSS885':
      PIN_NUMBER='(0,0,0,0,0,0,0,0,0,0,0,0,0,0,0,0,0,0,0,0,0,0,0,0,0,0,0,0,0,0,0~
,0,0,0,0,0,0,0,0,0,0,D40)';
      PINUSE='POWER';
      NO_LOAD_CHECK='Both';
      NO_IO_CHECK='Both';
      NO_ASSERT_CHECK='TRUE';
      NO_DIR_CHECK='TRUE';
      ALLOW_CONNECT='TRUE';
    'VSS884':
      PIN_NUMBER='(0,0,0,0,0,0,0,0,0,0,0,0,0,0,0,0,0,0,0,0,0,0,0,0,0,0,0,0,0,0,0~
,0,0,0,0,0,0,0,0,0,0,D38)';
      PINUSE='POWER';
      NO_LOAD_CHECK='Both';
      NO_IO_CHECK='Both';
      NO_ASSERT_CHECK='TRUE';
      NO_DIR_CHECK='TRUE';
      ALLOW_CONNECT='TRUE';
    'VSS881':
      PIN_NUMBER='(0,0,0,0,0,0,0,0,0,0,0,0,0,0,0,0,0,0,0,0,0,0,0,0,0,0,0,0,0,0,0~
,0,0,0,0,0,0,0,0,0,0,D36)';
      PINUSE='POWER';
      NO_LOAD_CHECK='Both';
      NO_IO_CHECK='Both';
      NO_ASSERT_CHECK='TRUE';
      NO_DIR_CHECK='TRUE';
      ALLOW_CONNECT='TRUE';
    'VSS879':
      PIN_NUMBER='(0,0,0,0,0,0,0,0,0,0,0,0,0,0,0,0,0,0,0,0,0,0,0,0,0,0,0,0,0,0,0~
,0,0,0,0,0,0,0,0,0,0,D34)';
      PINUSE='POWER';
      NO_LOAD_CHECK='Both';
      NO_IO_CHECK='Both';
      NO_ASSERT_CHECK='TRUE';
      NO_DIR_CHECK='TRUE';
      ALLOW_CONNECT='TRUE';
    'VSS878':
      PIN_NUMBER='(0,0,0,0,0,0,0,0,0,0,0,0,0,0,0,0,0,0,0,0,0,0,0,0,0,0,0,0,0,0,0~
,0,0,0,0,0,0,0,0,0,0,D32)';
      PINUSE='POWER';
      NO_LOAD_CHECK='Both';
      NO_IO_CHECK='Both';
      NO_ASSERT_CHECK='TRUE';
      NO_DIR_CHECK='TRUE';
      ALLOW_CONNECT='TRUE';
    'VSS877':
      PIN_NUMBER='(0,0,0,0,0,0,0,0,0,0,0,0,0,0,0,0,0,0,0,0,0,0,0,0,0,0,0,0,0,0,0~
,0,0,0,0,0,0,0,0,0,0,D30)';
      PINUSE='POWER';
      NO_LOAD_CHECK='Both';
      NO_IO_CHECK='Both';
      NO_ASSERT_CHECK='TRUE';
      NO_DIR_CHECK='TRUE';
      ALLOW_CONNECT='TRUE';
    'VSS876':
      PIN_NUMBER='(0,0,0,0,0,0,0,0,0,0,0,0,0,0,0,0,0,0,0,0,0,0,0,0,0,0,0,0,0,0,0~
,0,0,0,0,0,0,0,0,0,0,D28)';
      PINUSE='POWER';
      NO_LOAD_CHECK='Both';
      NO_IO_CHECK='Both';
      NO_ASSERT_CHECK='TRUE';
      NO_DIR_CHECK='TRUE';
      ALLOW_CONNECT='TRUE';
    'VSS875':
      PIN_NUMBER='(0,0,0,0,0,0,0,0,0,0,0,0,0,0,0,0,0,0,0,0,0,0,0,0,0,0,0,0,0,0,0~
,0,0,0,0,0,0,0,0,0,0,D26)';
      PINUSE='POWER';
      NO_LOAD_CHECK='Both';
      NO_IO_CHECK='Both';
      NO_ASSERT_CHECK='TRUE';
      NO_DIR_CHECK='TRUE';
      ALLOW_CONNECT='TRUE';
    'VSS874':
      PIN_NUMBER='(0,0,0,0,0,0,0,0,0,0,0,0,0,0,0,0,0,0,0,0,0,0,0,0,0,0,0,0,0,0,0~
,0,0,0,0,0,0,0,0,0,0,D24)';
      PINUSE='POWER';
      NO_LOAD_CHECK='Both';
      NO_IO_CHECK='Both';
      NO_ASSERT_CHECK='TRUE';
      NO_DIR_CHECK='TRUE';
      ALLOW_CONNECT='TRUE';
    'VSS873':
      PIN_NUMBER='(0,0,0,0,0,0,0,0,0,0,0,0,0,0,0,0,0,0,0,0,0,0,0,0,0,0,0,0,0,0,0~
,0,0,0,0,0,0,0,0,0,0,D22)';
      PINUSE='POWER';
      NO_LOAD_CHECK='Both';
      NO_IO_CHECK='Both';
      NO_ASSERT_CHECK='TRUE';
      NO_DIR_CHECK='TRUE';
      ALLOW_CONNECT='TRUE';
    'VSS871':
      PIN_NUMBER='(0,0,0,0,0,0,0,0,0,0,0,0,0,0,0,0,0,0,0,0,0,0,0,0,0,0,0,0,0,0,0~
,0,0,0,0,0,0,0,0,0,0,D20)';
      PINUSE='POWER';
      NO_LOAD_CHECK='Both';
      NO_IO_CHECK='Both';
      NO_ASSERT_CHECK='TRUE';
      NO_DIR_CHECK='TRUE';
      ALLOW_CONNECT='TRUE';
    'VSS869':
      PIN_NUMBER='(0,0,0,0,0,0,0,0,0,0,0,0,0,0,0,0,0,0,0,0,0,0,0,0,0,0,0,0,0,0,0~
,0,0,0,0,0,0,0,0,0,0,D18)';
      PINUSE='POWER';
      NO_LOAD_CHECK='Both';
      NO_IO_CHECK='Both';
      NO_ASSERT_CHECK='TRUE';
      NO_DIR_CHECK='TRUE';
      ALLOW_CONNECT='TRUE';
    'VSS868':
      PIN_NUMBER='(0,0,0,0,0,0,0,0,0,0,0,0,0,0,0,0,0,0,0,0,0,0,0,0,0,0,0,0,0,0,0~
,0,0,0,0,0,0,0,0,0,0,D16)';
      PINUSE='POWER';
      NO_LOAD_CHECK='Both';
      NO_IO_CHECK='Both';
      NO_ASSERT_CHECK='TRUE';
      NO_DIR_CHECK='TRUE';
      ALLOW_CONNECT='TRUE';
    'VSS866':
      PIN_NUMBER='(0,0,0,0,0,0,0,0,0,0,0,0,0,0,0,0,0,0,0,0,0,0,0,0,0,0,0,0,0,0,0~
,0,0,0,0,0,0,0,0,0,0,D14)';
      PINUSE='POWER';
      NO_LOAD_CHECK='Both';
      NO_IO_CHECK='Both';
      NO_ASSERT_CHECK='TRUE';
      NO_DIR_CHECK='TRUE';
      ALLOW_CONNECT='TRUE';
    'VSS865':
      PIN_NUMBER='(0,0,0,0,0,0,0,0,0,0,0,0,0,0,0,0,0,0,0,0,0,0,0,0,0,0,0,0,0,0,0~
,0,0,0,0,0,0,0,0,0,0,D12)';
      PINUSE='POWER';
      NO_LOAD_CHECK='Both';
      NO_IO_CHECK='Both';
      NO_ASSERT_CHECK='TRUE';
      NO_DIR_CHECK='TRUE';
      ALLOW_CONNECT='TRUE';
    'VSS864':
      PIN_NUMBER='(0,0,0,0,0,0,0,0,0,0,0,0,0,0,0,0,0,0,0,0,0,0,0,0,0,0,0,0,0,0,0~
,0,0,0,0,0,0,0,0,0,0,D10)';
      PINUSE='POWER';
      NO_LOAD_CHECK='Both';
      NO_IO_CHECK='Both';
      NO_ASSERT_CHECK='TRUE';
      NO_DIR_CHECK='TRUE';
      ALLOW_CONNECT='TRUE';
    'VSS663':
      PIN_NUMBER='(0,0,0,0,0,0,0,0,0,0,0,0,0,0,0,0,0,0,0,0,0,0,0,0,0,0,0,0,0,0,0~
,0,0,0,0,0,0,0,0,0,0,D8)';
      PINUSE='POWER';
      NO_LOAD_CHECK='Both';
      NO_IO_CHECK='Both';
      NO_ASSERT_CHECK='TRUE';
      NO_DIR_CHECK='TRUE';
      ALLOW_CONNECT='TRUE';
    'VSS662':
      PIN_NUMBER='(0,0,0,0,0,0,0,0,0,0,0,0,0,0,0,0,0,0,0,0,0,0,0,0,0,0,0,0,0,0,0~
,0,0,0,0,0,0,0,0,0,0,D79)';
      PINUSE='POWER';
      NO_LOAD_CHECK='Both';
      NO_IO_CHECK='Both';
      NO_ASSERT_CHECK='TRUE';
      NO_DIR_CHECK='TRUE';
      ALLOW_CONNECT='TRUE';
    'VSS659':
      PIN_NUMBER='(0,0,0,0,0,0,0,0,0,0,0,0,0,0,0,0,0,0,0,0,0,0,0,0,0,0,0,0,0,0,0~
,0,0,0,0,0,0,0,0,0,0,D67)';
      PINUSE='POWER';
      NO_LOAD_CHECK='Both';
      NO_IO_CHECK='Both';
      NO_ASSERT_CHECK='TRUE';
      NO_DIR_CHECK='TRUE';
      ALLOW_CONNECT='TRUE';
    'VSS658':
      PIN_NUMBER='(0,0,0,0,0,0,0,0,0,0,0,0,0,0,0,0,0,0,0,0,0,0,0,0,0,0,0,0,0,0,0~
,0,0,0,0,0,0,0,0,0,0,D65)';
      PINUSE='POWER';
      NO_LOAD_CHECK='Both';
      NO_IO_CHECK='Both';
      NO_ASSERT_CHECK='TRUE';
      NO_DIR_CHECK='TRUE';
      ALLOW_CONNECT='TRUE';
    'VSS657':
      PIN_NUMBER='(0,0,0,0,0,0,0,0,0,0,0,0,0,0,0,0,0,0,0,0,0,0,0,0,0,0,0,0,0,0,0~
,0,0,0,0,0,0,0,0,0,0,D63)';
      PINUSE='POWER';
      NO_LOAD_CHECK='Both';
      NO_IO_CHECK='Both';
      NO_ASSERT_CHECK='TRUE';
      NO_DIR_CHECK='TRUE';
      ALLOW_CONNECT='TRUE';
    'VSS619':
      PIN_NUMBER='(0,0,0,0,0,0,0,0,0,0,0,0,0,0,0,0,0,0,0,0,0,0,0,0,0,0,0,0,0,0,0~
,0,0,0,0,0,0,0,0,0,0,C86)';
      PINUSE='POWER';
      NO_LOAD_CHECK='Both';
      NO_IO_CHECK='Both';
      NO_ASSERT_CHECK='TRUE';
      NO_DIR_CHECK='TRUE';
      ALLOW_CONNECT='TRUE';
    'VSS618':
      PIN_NUMBER='(0,0,0,0,0,0,0,0,0,0,0,0,0,0,0,0,0,0,0,0,0,0,0,0,0,0,0,0,0,0,0~
,0,0,0,0,0,0,0,0,0,0,C82)';
      PINUSE='POWER';
      NO_LOAD_CHECK='Both';
      NO_IO_CHECK='Both';
      NO_ASSERT_CHECK='TRUE';
      NO_DIR_CHECK='TRUE';
      ALLOW_CONNECT='TRUE';
    'VSS617':
      PIN_NUMBER='(0,0,0,0,0,0,0,0,0,0,0,0,0,0,0,0,0,0,0,0,0,0,0,0,0,0,0,0,0,0,0~
,0,0,0,0,0,0,0,0,0,0,C80)';
      PINUSE='POWER';
      NO_LOAD_CHECK='Both';
      NO_IO_CHECK='Both';
      NO_ASSERT_CHECK='TRUE';
      NO_DIR_CHECK='TRUE';
      ALLOW_CONNECT='TRUE';
    'VSS616':
      PIN_NUMBER='(0,0,0,0,0,0,0,0,0,0,0,0,0,0,0,0,0,0,0,0,0,0,0,0,0,0,0,0,0,0,0~
,0,0,0,0,0,0,0,0,0,0,C78)';
      PINUSE='POWER';
      NO_LOAD_CHECK='Both';
      NO_IO_CHECK='Both';
      NO_ASSERT_CHECK='TRUE';
      NO_DIR_CHECK='TRUE';
      ALLOW_CONNECT='TRUE';
    'VSS615':
      PIN_NUMBER='(0,0,0,0,0,0,0,0,0,0,0,0,0,0,0,0,0,0,0,0,0,0,0,0,0,0,0,0,0,0,0~
,0,0,0,0,0,0,0,0,0,0,C74)';
      PINUSE='POWER';
      NO_LOAD_CHECK='Both';
      NO_IO_CHECK='Both';
      NO_ASSERT_CHECK='TRUE';
      NO_DIR_CHECK='TRUE';
      ALLOW_CONNECT='TRUE';
    'VSS614':
      PIN_NUMBER='(0,0,0,0,0,0,0,0,0,0,0,0,0,0,0,0,0,0,0,0,0,0,0,0,0,0,0,0,0,0,0~
,0,0,0,0,0,0,0,0,0,0,C72)';
      PINUSE='POWER';
      NO_LOAD_CHECK='Both';
      NO_IO_CHECK='Both';
      NO_ASSERT_CHECK='TRUE';
      NO_DIR_CHECK='TRUE';
      ALLOW_CONNECT='TRUE';
    'VSS613':
      PIN_NUMBER='(0,0,0,0,0,0,0,0,0,0,0,0,0,0,0,0,0,0,0,0,0,0,0,0,0,0,0,0,0,0,0~
,0,0,0,0,0,0,0,0,0,0,C52)';
      PINUSE='POWER';
      NO_LOAD_CHECK='Both';
      NO_IO_CHECK='Both';
      NO_ASSERT_CHECK='TRUE';
      NO_DIR_CHECK='TRUE';
      ALLOW_CONNECT='TRUE';
    'VSS612':
      PIN_NUMBER='(0,0,0,0,0,0,0,0,0,0,0,0,0,0,0,0,0,0,0,0,0,0,0,0,0,0,0,0,0,0,0~
,0,0,0,0,0,0,0,0,0,0,C5)';
      PINUSE='POWER';
      NO_LOAD_CHECK='Both';
      NO_IO_CHECK='Both';
      NO_ASSERT_CHECK='TRUE';
      NO_DIR_CHECK='TRUE';
      ALLOW_CONNECT='TRUE';
    'VSS610':
      PIN_NUMBER='(0,0,0,0,0,0,0,0,0,0,0,0,0,0,0,0,0,0,0,0,0,0,0,0,0,0,0,0,0,0,0~
,0,0,0,0,0,0,0,0,0,0,C45)';
      PINUSE='POWER';
      NO_LOAD_CHECK='Both';
      NO_IO_CHECK='Both';
      NO_ASSERT_CHECK='TRUE';
      NO_DIR_CHECK='TRUE';
      ALLOW_CONNECT='TRUE';
    'VSS609':
      PIN_NUMBER='(0,0,0,0,0,0,0,0,0,0,0,0,0,0,0,0,0,0,0,0,0,0,0,0,0,0,0,0,0,0,0~
,0,0,0,0,0,0,0,0,0,0,C39)';
      PINUSE='POWER';
      NO_LOAD_CHECK='Both';
      NO_IO_CHECK='Both';
      NO_ASSERT_CHECK='TRUE';
      NO_DIR_CHECK='TRUE';
      ALLOW_CONNECT='TRUE';
    'VSS392':
      PIN_NUMBER='(0,0,0,0,0,0,0,0,0,0,0,0,0,0,0,0,0,0,0,0,0,0,0,0,0,0,0,0,0,0,0~
,0,0,0,0,0,0,0,0,0,0,B87)';
      PINUSE='POWER';
      NO_LOAD_CHECK='Both';
      NO_IO_CHECK='Both';
      NO_ASSERT_CHECK='TRUE';
      NO_DIR_CHECK='TRUE';
      ALLOW_CONNECT='TRUE';
    'VSS391':
      PIN_NUMBER='(0,0,0,0,0,0,0,0,0,0,0,0,0,0,0,0,0,0,0,0,0,0,0,0,0,0,0,0,0,0,0~
,0,0,0,0,0,0,0,0,0,0,B83)';
      PINUSE='POWER';
      NO_LOAD_CHECK='Both';
      NO_IO_CHECK='Both';
      NO_ASSERT_CHECK='TRUE';
      NO_DIR_CHECK='TRUE';
      ALLOW_CONNECT='TRUE';
    'VSS390':
      PIN_NUMBER='(0,0,0,0,0,0,0,0,0,0,0,0,0,0,0,0,0,0,0,0,0,0,0,0,0,0,0,0,0,0,0~
,0,0,0,0,0,0,0,0,0,0,B75)';
      PINUSE='POWER';
      NO_LOAD_CHECK='Both';
      NO_IO_CHECK='Both';
      NO_ASSERT_CHECK='TRUE';
      NO_DIR_CHECK='TRUE';
      ALLOW_CONNECT='TRUE';
    'VSS389':
      PIN_NUMBER='(0,0,0,0,0,0,0,0,0,0,0,0,0,0,0,0,0,0,0,0,0,0,0,0,0,0,0,0,0,0,0~
,0,0,0,0,0,0,0,0,0,0,B67)';
      PINUSE='POWER';
      NO_LOAD_CHECK='Both';
      NO_IO_CHECK='Both';
      NO_ASSERT_CHECK='TRUE';
      NO_DIR_CHECK='TRUE';
      ALLOW_CONNECT='TRUE';
    'VSS388':
      PIN_NUMBER='(0,0,0,0,0,0,0,0,0,0,0,0,0,0,0,0,0,0,0,0,0,0,0,0,0,0,0,0,0,0,0~
,0,0,0,0,0,0,0,0,0,0,B61)';
      PINUSE='POWER';
      NO_LOAD_CHECK='Both';
      NO_IO_CHECK='Both';
      NO_ASSERT_CHECK='TRUE';
      NO_DIR_CHECK='TRUE';
      ALLOW_CONNECT='TRUE';
    'VSS387':
      PIN_NUMBER='(0,0,0,0,0,0,0,0,0,0,0,0,0,0,0,0,0,0,0,0,0,0,0,0,0,0,0,0,0,0,0~
,0,0,0,0,0,0,0,0,0,0,B6)';
      PINUSE='POWER';
      NO_LOAD_CHECK='Both';
      NO_IO_CHECK='Both';
      NO_ASSERT_CHECK='TRUE';
      NO_DIR_CHECK='TRUE';
      ALLOW_CONNECT='TRUE';
    'VSS386':
      PIN_NUMBER='(0,0,0,0,0,0,0,0,0,0,0,0,0,0,0,0,0,0,0,0,0,0,0,0,0,0,0,0,0,0,0~
,0,0,0,0,0,0,0,0,0,0,B55)';
      PINUSE='POWER';
      NO_LOAD_CHECK='Both';
      NO_IO_CHECK='Both';
      NO_ASSERT_CHECK='TRUE';
      NO_DIR_CHECK='TRUE';
      ALLOW_CONNECT='TRUE';
    'VSS385':
      PIN_NUMBER='(0,0,0,0,0,0,0,0,0,0,0,0,0,0,0,0,0,0,0,0,0,0,0,0,0,0,0,0,0,0,0~
,0,0,0,0,0,0,0,0,0,0,B49)';
      PINUSE='POWER';
      NO_LOAD_CHECK='Both';
      NO_IO_CHECK='Both';
      NO_ASSERT_CHECK='TRUE';
      NO_DIR_CHECK='TRUE';
      ALLOW_CONNECT='TRUE';
    'VSS384':
      PIN_NUMBER='(0,0,0,0,0,0,0,0,0,0,0,0,0,0,0,0,0,0,0,0,0,0,0,0,0,0,0,0,0,0,0~
,0,0,0,0,0,0,0,0,0,0,B42)';
      PINUSE='POWER';
      NO_LOAD_CHECK='Both';
      NO_IO_CHECK='Both';
      NO_ASSERT_CHECK='TRUE';
      NO_DIR_CHECK='TRUE';
      ALLOW_CONNECT='TRUE';
    'VSS382':
      PIN_NUMBER='(0,0,0,0,0,0,0,0,0,0,0,0,0,0,0,0,0,0,0,0,0,0,0,0,0,0,0,0,0,0,0~
,0,0,0,0,0,0,0,0,0,0,B36)';
      PINUSE='POWER';
      NO_LOAD_CHECK='Both';
      NO_IO_CHECK='Both';
      NO_ASSERT_CHECK='TRUE';
      NO_DIR_CHECK='TRUE';
      ALLOW_CONNECT='TRUE';
    'VSS381':
      PIN_NUMBER='(0,0,0,0,0,0,0,0,0,0,0,0,0,0,0,0,0,0,0,0,0,0,0,0,0,0,0,0,0,0,0~
,0,0,0,0,0,0,0,0,0,0,B30)';
      PINUSE='POWER';
      NO_LOAD_CHECK='Both';
      NO_IO_CHECK='Both';
      NO_ASSERT_CHECK='TRUE';
      NO_DIR_CHECK='TRUE';
      ALLOW_CONNECT='TRUE';
    'VSS380':
      PIN_NUMBER='(0,0,0,0,0,0,0,0,0,0,0,0,0,0,0,0,0,0,0,0,0,0,0,0,0,0,0,0,0,0,0~
,0,0,0,0,0,0,0,0,0,0,B24)';
      PINUSE='POWER';
      NO_LOAD_CHECK='Both';
      NO_IO_CHECK='Both';
      NO_ASSERT_CHECK='TRUE';
      NO_DIR_CHECK='TRUE';
      ALLOW_CONNECT='TRUE';
    'VSS379':
      PIN_NUMBER='(0,0,0,0,0,0,0,0,0,0,0,0,0,0,0,0,0,0,0,0,0,0,0,0,0,0,0,0,0,0,0~
,0,0,0,0,0,0,0,0,0,0,B18)';
      PINUSE='POWER';
      NO_LOAD_CHECK='Both';
      NO_IO_CHECK='Both';
      NO_ASSERT_CHECK='TRUE';
      NO_DIR_CHECK='TRUE';
      ALLOW_CONNECT='TRUE';
    'VSS378':
      PIN_NUMBER='(0,0,0,0,0,0,0,0,0,0,0,0,0,0,0,0,0,0,0,0,0,0,0,0,0,0,0,0,0,0,0~
,0,0,0,0,0,0,0,0,0,0,B12)';
      PINUSE='POWER';
      NO_LOAD_CHECK='Both';
      NO_IO_CHECK='Both';
      NO_ASSERT_CHECK='TRUE';
      NO_DIR_CHECK='TRUE';
      ALLOW_CONNECT='TRUE';
    'VSS16':
      PIN_NUMBER='(0,0,0,0,0,0,0,0,0,0,0,0,0,0,0,0,0,0,0,0,0,0,0,0,0,0,0,0,0,0,0~
,0,0,0,0,0,0,0,0,0,0,A62)';
      PINUSE='POWER';
      NO_LOAD_CHECK='Both';
      NO_IO_CHECK='Both';
      NO_ASSERT_CHECK='TRUE';
      NO_DIR_CHECK='TRUE';
      ALLOW_CONNECT='TRUE';
    'VSS15':
      PIN_NUMBER='(0,0,0,0,0,0,0,0,0,0,0,0,0,0,0,0,0,0,0,0,0,0,0,0,0,0,0,0,0,0,0~
,0,0,0,0,0,0,0,0,0,0,A60)';
      PINUSE='POWER';
      NO_LOAD_CHECK='Both';
      NO_IO_CHECK='Both';
      NO_ASSERT_CHECK='TRUE';
      NO_DIR_CHECK='TRUE';
      ALLOW_CONNECT='TRUE';
    'VSS14':
      PIN_NUMBER='(0,0,0,0,0,0,0,0,0,0,0,0,0,0,0,0,0,0,0,0,0,0,0,0,0,0,0,0,0,0,0~
,0,0,0,0,0,0,0,0,0,0,A56)';
      PINUSE='POWER';
      NO_LOAD_CHECK='Both';
      NO_IO_CHECK='Both';
      NO_ASSERT_CHECK='TRUE';
      NO_DIR_CHECK='TRUE';
      ALLOW_CONNECT='TRUE';
    'VSS13':
      PIN_NUMBER='(0,0,0,0,0,0,0,0,0,0,0,0,0,0,0,0,0,0,0,0,0,0,0,0,0,0,0,0,0,0,0~
,0,0,0,0,0,0,0,0,0,0,A54)';
      PINUSE='POWER';
      NO_LOAD_CHECK='Both';
      NO_IO_CHECK='Both';
      NO_ASSERT_CHECK='TRUE';
      NO_DIR_CHECK='TRUE';
      ALLOW_CONNECT='TRUE';
    'VSS12':
      PIN_NUMBER='(0,0,0,0,0,0,0,0,0,0,0,0,0,0,0,0,0,0,0,0,0,0,0,0,0,0,0,0,0,0,0~
,0,0,0,0,0,0,0,0,0,0,A50)';
      PINUSE='POWER';
      NO_LOAD_CHECK='Both';
      NO_IO_CHECK='Both';
      NO_ASSERT_CHECK='TRUE';
      NO_DIR_CHECK='TRUE';
      ALLOW_CONNECT='TRUE';
    'VSS11':
      PIN_NUMBER='(0,0,0,0,0,0,0,0,0,0,0,0,0,0,0,0,0,0,0,0,0,0,0,0,0,0,0,0,0,0,0~
,0,0,0,0,0,0,0,0,0,0,A41)';
      PINUSE='POWER';
      NO_LOAD_CHECK='Both';
      NO_IO_CHECK='Both';
      NO_ASSERT_CHECK='TRUE';
      NO_DIR_CHECK='TRUE';
      ALLOW_CONNECT='TRUE';
    'VSS10':
      PIN_NUMBER='(0,0,0,0,0,0,0,0,0,0,0,0,0,0,0,0,0,0,0,0,0,0,0,0,0,0,0,0,0,0,0~
,0,0,0,0,0,0,0,0,0,0,A37)';
      PINUSE='POWER';
      NO_LOAD_CHECK='Both';
      NO_IO_CHECK='Both';
      NO_ASSERT_CHECK='TRUE';
      NO_DIR_CHECK='TRUE';
      ALLOW_CONNECT='TRUE';
    'VSS9':
      PIN_NUMBER='(0,0,0,0,0,0,0,0,0,0,0,0,0,0,0,0,0,0,0,0,0,0,0,0,0,0,0,0,0,0,0~
,0,0,0,0,0,0,0,0,0,0,A35)';
      PINUSE='POWER';
      NO_LOAD_CHECK='Both';
      NO_IO_CHECK='Both';
      NO_ASSERT_CHECK='TRUE';
      NO_DIR_CHECK='TRUE';
      ALLOW_CONNECT='TRUE';
    'VSS8':
      PIN_NUMBER='(0,0,0,0,0,0,0,0,0,0,0,0,0,0,0,0,0,0,0,0,0,0,0,0,0,0,0,0,0,0,0~
,0,0,0,0,0,0,0,0,0,0,A31)';
      PINUSE='POWER';
      NO_LOAD_CHECK='Both';
      NO_IO_CHECK='Both';
      NO_ASSERT_CHECK='TRUE';
      NO_DIR_CHECK='TRUE';
      ALLOW_CONNECT='TRUE';
    'VSS7':
      PIN_NUMBER='(0,0,0,0,0,0,0,0,0,0,0,0,0,0,0,0,0,0,0,0,0,0,0,0,0,0,0,0,0,0,0~
,0,0,0,0,0,0,0,0,0,0,A29)';
      PINUSE='POWER';
      NO_LOAD_CHECK='Both';
      NO_IO_CHECK='Both';
      NO_ASSERT_CHECK='TRUE';
      NO_DIR_CHECK='TRUE';
      ALLOW_CONNECT='TRUE';
    'VSS6':
      PIN_NUMBER='(0,0,0,0,0,0,0,0,0,0,0,0,0,0,0,0,0,0,0,0,0,0,0,0,0,0,0,0,0,0,0~
,0,0,0,0,0,0,0,0,0,0,A25)';
      PINUSE='POWER';
      NO_LOAD_CHECK='Both';
      NO_IO_CHECK='Both';
      NO_ASSERT_CHECK='TRUE';
      NO_DIR_CHECK='TRUE';
      ALLOW_CONNECT='TRUE';
    'VSS5':
      PIN_NUMBER='(0,0,0,0,0,0,0,0,0,0,0,0,0,0,0,0,0,0,0,0,0,0,0,0,0,0,0,0,0,0,0~
,0,0,0,0,0,0,0,0,0,0,A23)';
      PINUSE='POWER';
      NO_LOAD_CHECK='Both';
      NO_IO_CHECK='Both';
      NO_ASSERT_CHECK='TRUE';
      NO_DIR_CHECK='TRUE';
      ALLOW_CONNECT='TRUE';
    'VSS4':
      PIN_NUMBER='(0,0,0,0,0,0,0,0,0,0,0,0,0,0,0,0,0,0,0,0,0,0,0,0,0,0,0,0,0,0,0~
,0,0,0,0,0,0,0,0,0,0,A19)';
      PINUSE='POWER';
      NO_LOAD_CHECK='Both';
      NO_IO_CHECK='Both';
      NO_ASSERT_CHECK='TRUE';
      NO_DIR_CHECK='TRUE';
      ALLOW_CONNECT='TRUE';
    'VSS3':
      PIN_NUMBER='(0,0,0,0,0,0,0,0,0,0,0,0,0,0,0,0,0,0,0,0,0,0,0,0,0,0,0,0,0,0,0~
,0,0,0,0,0,0,0,0,0,0,A17)';
      PINUSE='POWER';
      NO_LOAD_CHECK='Both';
      NO_IO_CHECK='Both';
      NO_ASSERT_CHECK='TRUE';
      NO_DIR_CHECK='TRUE';
      ALLOW_CONNECT='TRUE';
    'VSS2':
      PIN_NUMBER='(0,0,0,0,0,0,0,0,0,0,0,0,0,0,0,0,0,0,0,0,0,0,0,0,0,0,0,0,0,0,0~
,0,0,0,0,0,0,0,0,0,0,A13)';
      PINUSE='POWER';
      NO_LOAD_CHECK='Both';
      NO_IO_CHECK='Both';
      NO_ASSERT_CHECK='TRUE';
      NO_DIR_CHECK='TRUE';
      ALLOW_CONNECT='TRUE';
    'VSS1':
      PIN_NUMBER='(0,0,0,0,0,0,0,0,0,0,0,0,0,0,0,0,0,0,0,0,0,0,0,0,0,0,0,0,0,0,0~
,0,0,0,0,0,0,0,0,0,0,A11)';
      PINUSE='POWER';
      NO_LOAD_CHECK='Both';
      NO_IO_CHECK='Both';
      NO_ASSERT_CHECK='TRUE';
      NO_DIR_CHECK='TRUE';
      ALLOW_CONNECT='TRUE';
  end_pin;
  body
      PART_NAME='SOCKET4677_AZIF0045P001C01CS';
      BODY_NAME='SOCKET4677_AZIF0045P001C01CS';
      PHYS_DES_PREFIX='U';
      CLASS='IO';
      STANDARD='';
      LIFECYCLE='';
      JEDEC_TYPE='SOCKET4677_82X64-5XA_H466';
      DESCRIPTION='SOCKET 4677P E LGA(P0.9398,H8.64)';
      MANUFTR='LTS';
      MANUF_PN='AZIF0045-P001C01CS';
      RD_CMPLS_LVL='EP(V1)';
      CMPLS_LVL='EP(V1)';
      DIP_SMD='';
      FROM_PJ='F0T-IVES';
      DATA='LTS_AZIF0045-P001C01CS.pdf';
      FP_ECN='AZIF0045-P001C01CS.msg';
      EE_CHECK_LIST='';
      CREATOR='';
      CREATEDAY='20211209';
      PSL='';
      STATUS='';
      ESD_CDM='';
      ESD_HBM='';
      ESD_MM='';
      MSD='';
      PIN_LENGTH_LONG_PIN='0 MILS';
      PIN_LENGTH_SHORT_PIN='0 MILS';
      PARENT_PART_TYPE='SOCKET4677_AZIF0045P001C01CS';
      PARENT_PPT='SOCKET4677_AZIF0045P001C01CS';
      PARENT_PPT_PART='SOCKET4677_AZIF0045P001C01CS-SOCKET4677_AZIF0045-P001C01CS,SMLF,IO,DGA^7000023';
  end_body;
end_primitive;
primitive 'SS15P3SM386A-SS15P3S-M3/86A,SMA';
  pin
    'ANODE_1':
      PIN_NUMBER='(1)';
      INPUT_LOAD='(-0.01,0.01)';
      PINUSE='IN';
    'CATHODE':
      PIN_NUMBER='(K)';
      OUTPUT_LOAD='(1.0,-1.0)';
      PINUSE='OUT';
    'ANODE_2':
      PIN_NUMBER='(2)';
      INPUT_LOAD='(-0.01,0.01)';
      PINUSE='IN';
  end_pin;
  body
      PART_NAME='SS15P3SM386A';
      BODY_NAME='SS15P3SM386A';
      PHYS_DES_PREFIX='D';
      CLASS='IC';
      STANDARD='';
      LIFECYCLE='';
      JEDEC_TYPE='TO277A_4-3X6-1';
      DESCRIPTION='DIODE SMD SS15P3S-M3/86A(30V,15A)';
      MANUFTR='SIL';
      MANUF_PN='SS15P3S-M3/86A';
      RD_CMPLS_LVL='EP(V1)';
      CMPLS_LVL='';
      DIP_SMD='';
      FP_ECN='SS15P3S-M386A.msg';
      FROM_PJ='S9T-YC';
      DATA='SIL_SS15P3S-M386A.pdf';
      EE_CHECK_LIST='';
      STATUS='';
      PSL='';
      PREFERENCE='';
      CREATOR='';
      CREATEDAY='20210421';
      ESD_CDM='';
      ESD_HBM='';
      ESD_MM='';
      MSD='';
      PIN_LENGTH_LONG_PIN='0 MILS';
      PIN_LENGTH_SHORT_PIN='0 MILS';
      PARENT_PART_TYPE='SS15P3SM386A';
      PARENT_PPT='SS15P3SM386A';
      PARENT_PPT_PART='SS15P3SM386A-SS15P3S-M3/86A,SMLF,IC,BC015P3SZ00';
  end_body;
end_primitive;
primitive 'SW_PUSHBUTTON4P_24-SW4S_DTSM-6A';
  pin
    '1':
      PIN_NUMBER='(1)';
      BIDIRECTIONAL='TRUE';
      INPUT_LOAD='(-0.01,0.01)';
      OUTPUT_LOAD='(1.0,-1.0)';
      PINUSE='BI';
    '2':
      PIN_NUMBER='(2)';
      BIDIRECTIONAL='TRUE';
      INPUT_LOAD='(-0.01,0.01)';
      OUTPUT_LOAD='(1.0,-1.0)';
      PINUSE='BI';
    '3':
      PIN_NUMBER='(3)';
      BIDIRECTIONAL='TRUE';
      INPUT_LOAD='(-0.01,0.01)';
      OUTPUT_LOAD='(1.0,-1.0)';
      PINUSE='BI';
    '4':
      PIN_NUMBER='(4)';
      BIDIRECTIONAL='TRUE';
      INPUT_LOAD='(-0.01,0.01)';
      OUTPUT_LOAD='(1.0,-1.0)';
      PINUSE='BI';
  end_pin;
  body
      PART_NAME='SW_PUSHBUTTON4P_24';
      BODY_NAME='SW_PUSHBUTTON4P_24';
      PHYS_DES_PREFIX='SW';
      CLASS='IO';
      STANDARD='';
      LIFECYCLE='';
      JEDEC_TYPE='SW4S_DTSM-61N';
      DESCRIPTION='SWITCH TACT SMD DTSM-61N-S-Q-T/R';
      MANUFTR='DIP';
      MANUF_PN='DTSM-61N-S-Q-T/R';
      RD_CMPLS_LVL='EP(V1)';
      CMPLS_LVL='EP(V1)';
      DIP_SMD='';
      FROM_PJ='F0C-BOSUN';
      DATA='DIP_DTSM-61N-S-Q-TR.pdf';
      FP_ECN='';
      EE_CHECK_LIST='';
      PSL='';
      PREFERENCE='';
      CREATOR='';
      CREATEDAY='20200215';
      STATUS='';
      PARENT_PART_TYPE='SW_PUSHBUTTON4P_24';
      PARENT_PPT='SW_PUSHBUTTON4P_24';
      PARENT_PPT_PART='SW_PUSHBUTTON4P_24-SW4S_DTSM-61N-S-Q-T/R,SMLF,MECH,DHP00061N15';
  end_body;
end_primitive;
primitive 'TCA9548APWR-TCA9548APWR,SMLF,IA';
  pin
    'A0':
      PIN_NUMBER='(1)';
      INPUT_LOAD='(-0.01,0.01)';
      PINUSE='IN';
    'A1':
      PIN_NUMBER='(2)';
      INPUT_LOAD='(-0.01,0.01)';
      PINUSE='IN';
    'RESET#':
      PIN_NUMBER='(3)';
      INPUT_LOAD='(-0.01,0.01)';
      PINUSE='IN';
    'SD0':
      PIN_NUMBER='(4)';
      BIDIRECTIONAL='TRUE';
      INPUT_LOAD='(-0.01,0.01)';
      OUTPUT_LOAD='(1.0,-1.0)';
      PINUSE='BI';
    'SC0':
      PIN_NUMBER='(5)';
      BIDIRECTIONAL='TRUE';
      INPUT_LOAD='(-0.01,0.01)';
      OUTPUT_LOAD='(1.0,-1.0)';
      PINUSE='BI';
    'SD1':
      PIN_NUMBER='(6)';
      BIDIRECTIONAL='TRUE';
      INPUT_LOAD='(-0.01,0.01)';
      OUTPUT_LOAD='(1.0,-1.0)';
      PINUSE='BI';
    'SC1':
      PIN_NUMBER='(7)';
      BIDIRECTIONAL='TRUE';
      INPUT_LOAD='(-0.01,0.01)';
      OUTPUT_LOAD='(1.0,-1.0)';
      PINUSE='BI';
    'SD2':
      PIN_NUMBER='(8)';
      BIDIRECTIONAL='TRUE';
      INPUT_LOAD='(-0.01,0.01)';
      OUTPUT_LOAD='(1.0,-1.0)';
      PINUSE='BI';
    'SC2':
      PIN_NUMBER='(9)';
      BIDIRECTIONAL='TRUE';
      INPUT_LOAD='(-0.01,0.01)';
      OUTPUT_LOAD='(1.0,-1.0)';
      PINUSE='BI';
    'SD3':
      PIN_NUMBER='(10)';
      BIDIRECTIONAL='TRUE';
      INPUT_LOAD='(-0.01,0.01)';
      OUTPUT_LOAD='(1.0,-1.0)';
      PINUSE='BI';
    'SC3':
      PIN_NUMBER='(11)';
      BIDIRECTIONAL='TRUE';
      INPUT_LOAD='(-0.01,0.01)';
      OUTPUT_LOAD='(1.0,-1.0)';
      PINUSE='BI';
    'GND':
      PIN_NUMBER='(12)';
      PINUSE='POWER';
      NO_LOAD_CHECK='Both';
      NO_IO_CHECK='Both';
      NO_ASSERT_CHECK='TRUE';
      NO_DIR_CHECK='TRUE';
      ALLOW_CONNECT='TRUE';
    'VCC':
      PIN_NUMBER='(24)';
      PINUSE='POWER';
      NO_LOAD_CHECK='Both';
      NO_IO_CHECK='Both';
      NO_ASSERT_CHECK='TRUE';
      NO_DIR_CHECK='TRUE';
      ALLOW_CONNECT='TRUE';
    'SDA':
      PIN_NUMBER='(23)';
      BIDIRECTIONAL='TRUE';
      INPUT_LOAD='(-0.01,0.01)';
      OUTPUT_LOAD='(1.0,-1.0)';
      PINUSE='BI';
    'SCL':
      PIN_NUMBER='(22)';
      BIDIRECTIONAL='TRUE';
      INPUT_LOAD='(-0.01,0.01)';
      OUTPUT_LOAD='(1.0,-1.0)';
      PINUSE='BI';
    'A2':
      PIN_NUMBER='(21)';
      INPUT_LOAD='(-0.01,0.01)';
      PINUSE='IN';
    'SC7':
      PIN_NUMBER='(20)';
      BIDIRECTIONAL='TRUE';
      INPUT_LOAD='(-0.01,0.01)';
      OUTPUT_LOAD='(1.0,-1.0)';
      PINUSE='BI';
    'SD7':
      PIN_NUMBER='(19)';
      BIDIRECTIONAL='TRUE';
      INPUT_LOAD='(-0.01,0.01)';
      OUTPUT_LOAD='(1.0,-1.0)';
      PINUSE='BI';
    'SC6':
      PIN_NUMBER='(18)';
      BIDIRECTIONAL='TRUE';
      INPUT_LOAD='(-0.01,0.01)';
      OUTPUT_LOAD='(1.0,-1.0)';
      PINUSE='BI';
    'SD6':
      PIN_NUMBER='(17)';
      BIDIRECTIONAL='TRUE';
      INPUT_LOAD='(-0.01,0.01)';
      OUTPUT_LOAD='(1.0,-1.0)';
      PINUSE='BI';
    'SC5':
      PIN_NUMBER='(16)';
      BIDIRECTIONAL='TRUE';
      INPUT_LOAD='(-0.01,0.01)';
      OUTPUT_LOAD='(1.0,-1.0)';
      PINUSE='BI';
    'SD5':
      PIN_NUMBER='(15)';
      BIDIRECTIONAL='TRUE';
      INPUT_LOAD='(-0.01,0.01)';
      OUTPUT_LOAD='(1.0,-1.0)';
      PINUSE='BI';
    'SC4':
      PIN_NUMBER='(14)';
      BIDIRECTIONAL='TRUE';
      INPUT_LOAD='(-0.01,0.01)';
      OUTPUT_LOAD='(1.0,-1.0)';
      PINUSE='BI';
    'SD4':
      PIN_NUMBER='(13)';
      BIDIRECTIONAL='TRUE';
      INPUT_LOAD='(-0.01,0.01)';
      OUTPUT_LOAD='(1.0,-1.0)';
      PINUSE='BI';
  end_pin;
  body
      PART_NAME='TCA9548APWR';
      BODY_NAME='TCA9548APWR';
      PHYS_DES_PREFIX='U';
      CLASS='IC';
      STANDARD='';
      LIFECYCLE='';
      JEDEC_TYPE='TSSOP24XA';
      DESCRIPTION='IC OTHER(24P) TCA9548APWR(TSSOP)';
      MANUFTR='TIC';
      MANUF_PN='TCA9548APWR';
      RD_CMPLS_LVL='EP(V1)';
      CMPLS_LVL='EP(V1)';
      FROM_PJ='T6MB-WILLIAM';
      DIP_SMD='';
      DATA='TIC_TCA9548APWR.pdf';
      EE_CHECK_LIST='';
      FP_ECN='';
      PSL='';
      CREATOR='';
      STATUS='';
      MSD='';
      ESD_CDM='';
      ESD_HBM='';
      ESD_MM='';
      PIN_LENGTH_SHORT_PIN='';
      PIN_LENGTH_LONG_PIN='';
      CREATEDAY='20160812';
      PARENT_PART_TYPE='TCA9548APWR';
      PARENT_PPT='TCA9548APWR';
      PARENT_PPT_PART='TCA9548APWR-TCA9548APWR,SMLF,IC,AL009548K02';
  end_body;
end_primitive;
primitive 'TDR_3P_TH2-EMPTY,N_A';
  pin
    'GND':
      PIN_NUMBER='(1)';
      PINUSE='UNSPEC';
      NO_LOAD_CHECK='BOTH';
      NO_IO_CHECK='BOTH';
      ALLOW_CONNECT='TRUE';
    'IO1':
      PIN_NUMBER='(2)';
      PINUSE='UNSPEC';
      NO_LOAD_CHECK='BOTH';
      NO_IO_CHECK='BOTH';
      ALLOW_CONNECT='TRUE';
    'IO2':
      PIN_NUMBER='(3)';
      PINUSE='UNSPEC';
      NO_LOAD_CHECK='BOTH';
      NO_IO_CHECK='BOTH';
      ALLOW_CONNECT='TRUE';
  end_pin;
  body
      PART_NAME='TDR_3P';
      BODY_NAME='TDR_3P';
      PHYS_DES_PREFIX='DB';
      CLASS='IO';
      STANDARD='';
      LIFECYCLE='';
      JEDEC_TYPE='TDR_3P_C85P67_141_100M_Q';
      ALT_SYMBOLS='(TDR_3P_C85P67_141_100M)';
      DESCRIPTION='(USE SYM_2)TDR 3PIN,2X141MIL 1X100MIL P2P';
      HEIGHT='0.00001 IN';
      COMPONENT_TYPE='PSEUDO';
      LPID='';
      SPEED_URL='';
      PARENT_PART_TYPE='TDR_3P_TH2';
      PARENT_PPT='TDR_3P';
      PARENT_PPT_PART='TDR_3P_TH2-EMPTY,N_A';
  end_body;
end_primitive;
primitive 'TPS3700DDCR-TPS3700DDCR,SMLF,EA';
  pin
    'VDD':
      PIN_NUMBER='(5)';
      PINUSE='POWER';
      NO_LOAD_CHECK='Both';
      NO_IO_CHECK='Both';
      NO_ASSERT_CHECK='TRUE';
      NO_DIR_CHECK='TRUE';
      ALLOW_CONNECT='TRUE';
    'INB-':
      PIN_NUMBER='(4)';
      INPUT_LOAD='(-0.01,0.01)';
      PINUSE='IN';
    'GND':
      PIN_NUMBER='(2)';
      PINUSE='POWER';
      NO_LOAD_CHECK='Both';
      NO_IO_CHECK='Both';
      NO_ASSERT_CHECK='TRUE';
      NO_DIR_CHECK='TRUE';
      ALLOW_CONNECT='TRUE';
    'OUTA':
      PIN_NUMBER='(1)';
      OUTPUT_LOAD='(1.0,-1.0)';
      PINUSE='OUT';
    'INA+':
      PIN_NUMBER='(3)';
      INPUT_LOAD='(-0.01,0.01)';
      PINUSE='IN';
    'OUTB':
      PIN_NUMBER='(6)';
      OUTPUT_LOAD='(1.0,-1.0)';
      PINUSE='OUT';
  end_pin;
  body
      PART_NAME='TPS3700DDCR';
      BODY_NAME='TPS3700DDCR';
      PHYS_DES_PREFIX='U';
      CLASS='IC';
      STANDARD='';
      LIFECYCLE='';
      JEDEC_TYPE='SOT23-6XF';
      DESCRIPTION='IC OTHER(6P)TPS3700DDCR(SOT-23-THIN)';
      MANUFTR='TIC';
      MANUF_PN='TPS3700DDCR';
      RD_CMPLS_LVL='EP(V1)';
      CMPLS_LVL='';
      FROM_PJ='F0T-IVES';
      DIP_SMD='';
      DATA='TIC_TPS3700DDCR.pdf';
      EE_CHECK_LIST='';
      FP_ECN='';
      PSL='';
      CREATOR='';
      STATUS='';
      MSD='';
      ESD_CDM='';
      ESD_HBM='';
      ESD_MM='';
      PIN_LENGTH_SHORT_PIN='0 MILS';
      PIN_LENGTH_LONG_PIN='0 MILS';
      CREATEDAY='20220805';
      PARENT_PART_TYPE='TPS3700DDCR';
      PARENT_PPT='TPS3700DDCR';
      PARENT_PPT_PART='TPS3700DDCR-TPS3700DDCR,SMLF,EMPTY,AL003700002';
  end_body;
end_primitive;
primitive 'TPS3895ADRYR-TPS3895ADRYR,SMLFA';
  pin
    'ENABLE':
      PIN_NUMBER='(1)';
      INPUT_LOAD='(-0.01,0.01)';
      PINUSE='IN';
    'GND':
      PIN_NUMBER='(2)';
      PINUSE='POWER';
      NO_LOAD_CHECK='Both';
      NO_IO_CHECK='Both';
      NO_ASSERT_CHECK='TRUE';
      NO_DIR_CHECK='TRUE';
      ALLOW_CONNECT='TRUE';
    'SENSE':
      PIN_NUMBER='(3)';
      BIDIRECTIONAL='TRUE';
      INPUT_LOAD='(-0.01,0.01)';
      OUTPUT_LOAD='(1.0,-1.0)';
      PINUSE='BI';
    'SENSE_OUT':
      PIN_NUMBER='(4)';
      OUTPUT_TYPE='(OC,AND)';
      OUTPUT_LOAD='(1.0,*)';
      PINUSE='OCA';
    'CT':
      PIN_NUMBER='(5)';
      BIDIRECTIONAL='TRUE';
      INPUT_LOAD='(-0.01,0.01)';
      OUTPUT_LOAD='(1.0,-1.0)';
      PINUSE='BI';
    'VCC':
      PIN_NUMBER='(6)';
      PINUSE='POWER';
      NO_LOAD_CHECK='Both';
      NO_IO_CHECK='Both';
      NO_ASSERT_CHECK='TRUE';
      NO_DIR_CHECK='TRUE';
      ALLOW_CONNECT='TRUE';
  end_pin;
  body
      PART_NAME='TPS3895ADRYR';
      BODY_NAME='TPS3895ADRYR';
      PHYS_DES_PREFIX='U';
      CLASS='IC';
      STANDARD='';
      LIFECYCLE='';
      JEDEC_TYPE='SON6';
      DESCRIPTION='IC OTHER(6P)TPS3895ADRYR(SON)';
      MANUFTR='TIC';
      MANUF_PN='TPS3895ADRYR';
      RD_CMPLS_LVL='EP(V1)';
      CMPLS_LVL='EP(V1)';
      FROM_PJ='S2I-ERIC';
      DIP_SMD='';
      DATA='TIC_TPS3895ADRYR.pdf';
      EE_CHECK_LIST='';
      FP_ECN='';
      PSL='';
      CREATOR='';
      STATUS='';
      MSD='NA';
      ESD_CDM='N/A';
      ESD_HBM='N/A';
      ESD_MM='N/A';
      PIN_LENGTH_SHORT_PIN='0 MILS';
      PIN_LENGTH_LONG_PIN='0 MILS';
      CREATEDAY='20190924';
      PARENT_PART_TYPE='TPS3895ADRYR';
      PARENT_PPT='TPS3895ADRYR';
      PARENT_PPT_PART='TPS3895ADRYR-TPS3895ADRYR,SMLF,EMPTY,AL003895003';
  end_body;
end_primitive;
primitive 'TP_TDR_4P_FTS_TH-TP_TDR_4P_DIPA';
  pin
    'P1':
      PIN_NUMBER='(2)';
      INPUT_LOAD='(-0.01,0.01)';
      OUTPUT_LOAD='(1.0,-1.0)';
      BIDIRECTIONAL='TRUE';
      PINUSE='BI';
    'P2':
      PIN_NUMBER='(3)';
      INPUT_LOAD='(-0.01,0.01)';
      OUTPUT_LOAD='(1.0,-1.0)';
      BIDIRECTIONAL='TRUE';
      PINUSE='BI';
    'S1':
      PIN_NUMBER='(1)';
      INPUT_LOAD='(-0.01,0.01)';
      OUTPUT_LOAD='(1.0,-1.0)';
      BIDIRECTIONAL='TRUE';
      PINUSE='BI';
    'S2':
      PIN_NUMBER='(4)';
      INPUT_LOAD='(-0.01,0.01)';
      OUTPUT_LOAD='(1.0,-1.0)';
      BIDIRECTIONAL='TRUE';
      PINUSE='BI';
  end_pin;
  body
      CLASS='IO';
      PART_NAME='TP_TDR_4P_FTS';
      PHYS_DES_PREFIX='X';
      STANDARD='';
      LIFECYCLE='';
      ENVCOMP='(Error)';
      JEDEC_TYPE='MPKT4_H025P0200';
      DESCRIPTION='DIFF_TEST_PAD DIP FOR FTS ONLY';
      HEIGHT='0.00001 IN';
      COMPONENT_TYPE='PSEUDO';
      LPID='';
      STATUS='???';
      RPL='???';
      AML='???';
      DAYS='20110210';
      PARENT_PART_TYPE='TP_TDR_4P_FTS';
      PARENT_PPT='TP_TDR_4P_FTS';
      PARENT_PPT_PART='TP_TDR_4P_FTS_TH-TP_TDR_4P_DIP,EMPTY,TP15';
  end_body;
end_primitive;
primitive 'TP_TP_BOM ONLY-NA,TP12_BOM';
  pin
    'TP':
      PIN_NUMBER='(1)';
      PINUSE='UNSPEC';
  end_pin;
  body
      PART_NAME='TP';
      BODY_NAME='TP';
      PHYS_DES_PREFIX='TP';
      CLASS='IO';
      STANDARD='';
      LIFECYCLE='';
      JEDEC_TYPE='TP30';
      HEIGHT='';
      COMPONENT_TYPE='PSEUDO';
      LEAD_LENGTH='';
      PARENT_PART_TYPE='TP';
      PARENT_PPT='TP';
      PARENT_PPT_PART='TP_TP_BOM ONLY-NA,TP12_BOM';
  end_body;
end_primitive;
primitive 'TUSB211IRWBR-TUSB211IRWBR,SMLFA';
  pin
    'RSTN':
      PIN_NUMBER='(5)';
      INPUT_LOAD='(-0.01,0.01)';
      PINUSE='IN';
    'D2M':
      PIN_NUMBER='(8)';
      BIDIRECTIONAL='TRUE';
      INPUT_LOAD='(-0.01,0.01)';
      OUTPUT_LOAD='(1.0,-1.0)';
      PINUSE='BI';
    'VREG':
      PIN_NUMBER='(11)';
      OUTPUT_LOAD='(1.0,-1.0)';
      PINUSE='OUT';
    'TEST':
      PIN_NUMBER='(3)';
      INPUT_LOAD='(-0.01,0.01)';
      PINUSE='IN';
    'VCC':
      PIN_NUMBER='(12)';
      PINUSE='POWER';
      NO_LOAD_CHECK='Both';
      NO_IO_CHECK='Both';
      NO_ASSERT_CHECK='TRUE';
      NO_DIR_CHECK='TRUE';
      ALLOW_CONNECT='TRUE';
    'ENA_HS':
      PIN_NUMBER='(9)';
      OUTPUT_LOAD='(1.0,-1.0)';
      PINUSE='OUT';
    'CD':
      PIN_NUMBER='(4)';
      OUTPUT_LOAD='(1.0,-1.0)';
      PINUSE='OUT';
    'D1M':
      PIN_NUMBER='(1)';
      BIDIRECTIONAL='TRUE';
      INPUT_LOAD='(-0.01,0.01)';
      OUTPUT_LOAD='(1.0,-1.0)';
      PINUSE='BI';
    'D1P':
      PIN_NUMBER='(2)';
      BIDIRECTIONAL='TRUE';
      INPUT_LOAD='(-0.01,0.01)';
      OUTPUT_LOAD='(1.0,-1.0)';
      PINUSE='BI';
    'D2P':
      PIN_NUMBER='(7)';
      BIDIRECTIONAL='TRUE';
      INPUT_LOAD='(-0.01,0.01)';
      OUTPUT_LOAD='(1.0,-1.0)';
      PINUSE='BI';
    'EQ':
      PIN_NUMBER='(6)';
      INPUT_LOAD='(-0.01,0.01)';
      PINUSE='IN';
    'GND':
      PIN_NUMBER='(10)';
      PINUSE='POWER';
      NO_LOAD_CHECK='Both';
      NO_IO_CHECK='Both';
      NO_ASSERT_CHECK='TRUE';
      NO_DIR_CHECK='TRUE';
      ALLOW_CONNECT='TRUE';
  end_pin;
  body
      PART_NAME='TUSB211IRWBR';
      BODY_NAME='TUSB211IRWBR';
      PHYS_DES_PREFIX='U';
      CLASS='IC';
      STANDARD='';
      LIFECYCLE='';
      JEDEC_TYPE='X2QFN12_0-4_1-6X1-6';
      DESCRIPTION='IC OTHER(12P) TUSB211IRWBR(QFN)';
      MANUFTR='TIC';
      MANUF_PN='TUSB211IRWBR';
      RD_CMPLS_LVL='EP(V1)';
      CMPLS_LVL='';
      FROM_PJ='S5A-ROGER';
      DIP_SMD='';
      DATA='TIC_TUSB211IRWBR.pdf';
      EE_CHECK_LIST='';
      FP_ECN='';
      PSL='';
      CREATOR='';
      STATUS='';
      CREATEDAY='20150203';
      PARENT_PART_TYPE='TUSB211IRWBR';
      PARENT_PPT='TUSB211IRWBR';
      PARENT_PPT_PART='TUSB211IRWBR-TUSB211IRWBR,SMLF,EMPTY,AL000211007';
  end_body;
end_primitive;
primitive 'ZENER_AC-5.0SMDJ14A,SMLF,IC,BCA';
  pin
    'A':
      PIN_NUMBER='(A)';
      BIDIRECTIONAL='TRUE';
      INPUT_LOAD='(-0.01,0.01)';
      OUTPUT_LOAD='(1.0,-1.0)';
      PINUSE='BI';
    'C':
      PIN_NUMBER='(C)';
      BIDIRECTIONAL='TRUE';
      INPUT_LOAD='(-0.01,0.01)';
      OUTPUT_LOAD='(1.0,-1.0)';
      PINUSE='BI';
  end_pin;
  body
      PART_NAME='ZENER_AC';
      BODY_NAME='ZENER_AC';
      PHYS_DES_PREFIX='D';
      CLASS='IC';
      STANDARD='';
      LIFECYCLE='';
      JEDEC_TYPE='D2723_SMCXC';
      DESCRIPTION='DIODE SMD 5.0SMDJ14A(14V,216A,5000W)';
      MANUFTR='LFI';
      MANUF_PN='5.0SMDJ14A';
      RD_CMPLS_LVL='EP(V1)';
      CMPLS_LVL='';
      DIP_SMD='';
      FP_ECN='';
      FROM_PJ='T2HV-JOHN';
      DATA='LFI_5.0SMDJ14A.pdf';
      EE_CHECK_LIST='';
      STATUS='';
      PSL='';
      PREFERENCE='';
      CREATOR='';
      CREATEDAY='20151225';
      PARENT_PART_TYPE='ZENER_AC';
      PARENT_PPT='ZENER_AC';
      PARENT_PPT_PART='ZENER_AC-5.0SMDJ14A,SMLF,IC,BC0MDJ14000';
  end_body;
end_primitive;
END.
